FILE_TYPE=LIBRARY_PARTS;
primitive 'SOCKET4677_AZIF0045P001C01CS';
  pin
    'XTAL_CLK_DP':
      PIN_NUMBER='(CY32,0,0,0,0,0,0,0,0,0,0,0,0,0,0,0,0,0,0,0,0,0,0,0,0,0,0,0,0,0,0,0,0,0,0,0,0,0,0,0,0,0)';
      INPUT_LOAD='(-0.01,0.01)';
    'TXT_PLTEN':
      PIN_NUMBER='(CT20,0,0,0,0,0,0,0,0,0,0,0,0,0,0,0,0,0,0,0,0,0,0,0,0,0,0,0,0,0,0,0,0,0,0,0,0,0,0,0,0,0)';
      INPUT_LOAD='(-0.01,0.01)';
    'TXT_AGENT':
      PIN_NUMBER='(BT26,0,0,0,0,0,0,0,0,0,0,0,0,0,0,0,0,0,0,0,0,0,0,0,0,0,0,0,0,0,0,0,0,0,0,0,0,0,0,0,0,0)';
      INPUT_LOAD='(-0.01,0.01)';
    'TMS':
      PIN_NUMBER='(BR25,0,0,0,0,0,0,0,0,0,0,0,0,0,0,0,0,0,0,0,0,0,0,0,0,0,0,0,0,0,0,0,0,0,0,0,0,0,0,0,0,0)';
      INPUT_LOAD='(-0.01,0.01)';
    'TDO':
      PIN_NUMBER='(BW25,0,0,0,0,0,0,0,0,0,0,0,0,0,0,0,0,0,0,0,0,0,0,0,0,0,0,0,0,0,0,0,0,0,0,0,0,0,0,0,0,0)';
      OUTPUT_LOAD='(1.0,-1.0)';
    'TDI':
      PIN_NUMBER='(BV24,0,0,0,0,0,0,0,0,0,0,0,0,0,0,0,0,0,0,0,0,0,0,0,0,0,0,0,0,0,0,0,0,0,0,0,0,0,0,0,0,0)';
      INPUT_LOAD='(-0.01,0.01)';
    'TCK':
      PIN_NUMBER='(BT24,0,0,0,0,0,0,0,0,0,0,0,0,0,0,0,0,0,0,0,0,0,0,0,0,0,0,0,0,0,0,0,0,0,0,0,0,0,0,0,0,0)';
      INPUT_LOAD='(-0.01,0.01)';
    'SOCKET_ID0':
      PIN_NUMBER='(CW60,0,0,0,0,0,0,0,0,0,0,0,0,0,0,0,0,0,0,0,0,0,0,0,0,0,0,0,0,0,0,0,0,0,0,0,0,0,0,0,0,0)';
      INPUT_LOAD='(-0.01,0.01)';
    'SOCKET_ID1':
      PIN_NUMBER='(CY61,0,0,0,0,0,0,0,0,0,0,0,0,0,0,0,0,0,0,0,0,0,0,0,0,0,0,0,0,0,0,0,0,0,0,0,0,0,0,0,0,0)';
      INPUT_LOAD='(-0.01,0.01)';
    'SOCKET_ID2':
      PIN_NUMBER='(CT61,0,0,0,0,0,0,0,0,0,0,0,0,0,0,0,0,0,0,0,0,0,0,0,0,0,0,0,0,0,0,0,0,0,0,0,0,0,0,0,0,0)';
      INPUT_LOAD='(-0.01,0.01)';
    'SAFE_MODE_BOOT':
      PIN_NUMBER='(AU23,0,0,0,0,0,0,0,0,0,0,0,0,0,0,0,0,0,0,0,0,0,0,0,0,0,0,0,0,0,0,0,0,0,0,0,0,0,0,0,0,0)';
      BIDIRECTIONAL='TRUE';
      INPUT_LOAD='(-0.01,0.01)';
      OUTPUT_LOAD='(1.0,-1.0)';
    'RSVD91':
      PIN_NUMBER='(CE70,0,0,0,0,0,0,0,0,0,0,0,0,0,0,0,0,0,0,0,0,0,0,0,0,0,0,0,0,0,0,0,0,0,0,0,0,0,0,0,0,0)';
      BIDIRECTIONAL='TRUE';
      INPUT_LOAD='(-0.01,0.01)';
      OUTPUT_LOAD='(1.0,-1.0)';
    'RSVD88':
      PIN_NUMBER='(CD71,0,0,0,0,0,0,0,0,0,0,0,0,0,0,0,0,0,0,0,0,0,0,0,0,0,0,0,0,0,0,0,0,0,0,0,0,0,0,0,0,0)';
      BIDIRECTIONAL='TRUE';
      INPUT_LOAD='(-0.01,0.01)';
      OUTPUT_LOAD='(1.0,-1.0)';
    'RSVD76':
      PIN_NUMBER='(BY24,0,0,0,0,0,0,0,0,0,0,0,0,0,0,0,0,0,0,0,0,0,0,0,0,0,0,0,0,0,0,0,0,0,0,0,0,0,0,0,0,0)';
      BIDIRECTIONAL='TRUE';
      INPUT_LOAD='(-0.01,0.01)';
      OUTPUT_LOAD='(1.0,-1.0)';
    'RSVD161':
      PIN_NUMBER='(G5,0,0,0,0,0,0,0,0,0,0,0,0,0,0,0,0,0,0,0,0,0,0,0,0,0,0,0,0,0,0,0,0,0,0,0,0,0,0,0,0,0)';
      BIDIRECTIONAL='TRUE';
      INPUT_LOAD='(-0.01,0.01)';
      OUTPUT_LOAD='(1.0,-1.0)';
    'RSVD108':
      PIN_NUMBER='(CJ72,0,0,0,0,0,0,0,0,0,0,0,0,0,0,0,0,0,0,0,0,0,0,0,0,0,0,0,0,0,0,0,0,0,0,0,0,0,0,0,0,0)';
      BIDIRECTIONAL='TRUE';
      INPUT_LOAD='(-0.01,0.01)';
      OUTPUT_LOAD='(1.0,-1.0)';
    'PROC_ID0':
      PIN_NUMBER='(BG72,0,0,0,0,0,0,0,0,0,0,0,0,0,0,0,0,0,0,0,0,0,0,0,0,0,0,0,0,0,0,0,0,0,0,0,0,0,0,0,0,0)';
      INPUT_LOAD='(-0.01,0.01)';
    'PROC_ID1':
      PIN_NUMBER='(BH71,0,0,0,0,0,0,0,0,0,0,0,0,0,0,0,0,0,0,0,0,0,0,0,0,0,0,0,0,0,0,0,0,0,0,0,0,0,0,0,0,0)';
      INPUT_LOAD='(-0.01,0.01)';
    '-PROCDIS':
      PIN_NUMBER='(DA52,0,0,0,0,0,0,0,0,0,0,0,0,0,0,0,0,0,0,0,0,0,0,0,0,0,0,0,0,0,0,0,0,0,0,0,0,0,0,0,0,0)';
      INPUT_LOAD='(-0.01,0.01)';
    '-PREQ':
      PIN_NUMBER='(AV22,0,0,0,0,0,0,0,0,0,0,0,0,0,0,0,0,0,0,0,0,0,0,0,0,0,0,0,0,0,0,0,0,0,0,0,0,0,0,0,0,0)';
      INPUT_LOAD='(-0.01,0.01)';
    '-PRDY':
      PIN_NUMBER='(BP26,0,0,0,0,0,0,0,0,0,0,0,0,0,0,0,0,0,0,0,0,0,0,0,0,0,0,0,0,0,0,0,0,0,0,0,0,0,0,0,0,0)';
      OUTPUT_LOAD='(1.0,-1.0)';
    'PKG_ID0':
      PIN_NUMBER='(BL64,0,0,0,0,0,0,0,0,0,0,0,0,0,0,0,0,0,0,0,0,0,0,0,0,0,0,0,0,0,0,0,0,0,0,0,0,0,0,0,0,0)';
      INPUT_LOAD='(-0.01,0.01)';
    'PKG_ID1':
      PIN_NUMBER='(AY63,0,0,0,0,0,0,0,0,0,0,0,0,0,0,0,0,0,0,0,0,0,0,0,0,0,0,0,0,0,0,0,0,0,0,0,0,0,0,0,0,0)';
      INPUT_LOAD='(-0.01,0.01)';
    'PKG_ID2':
      PIN_NUMBER='(BN64,0,0,0,0,0,0,0,0,0,0,0,0,0,0,0,0,0,0,0,0,0,0,0,0,0,0,0,0,0,0,0,0,0,0,0,0,0,0,0,0,0)';
      INPUT_LOAD='(-0.01,0.01)';
    'PECI':
      PIN_NUMBER='(BH24,0,0,0,0,0,0,0,0,0,0,0,0,0,0,0,0,0,0,0,0,0,0,0,0,0,0,0,0,0,0,0,0,0,0,0,0,0,0,0,0,0)';
      BIDIRECTIONAL='TRUE';
      INPUT_LOAD='(-0.01,0.01)';
      OUTPUT_LOAD='(1.0,-1.0)';
    'RSVD72':
      PIN_NUMBER='(BR23,0,0,0,0,0,0,0,0,0,0,0,0,0,0,0,0,0,0,0,0,0,0,0,0,0,0,0,0,0,0,0,0,0,0,0,0,0,0,0,0,0)';
      BIDIRECTIONAL='TRUE';
      INPUT_LOAD='(-0.01,0.01)';
      OUTPUT_LOAD='(1.0,-1.0)';
    'LEGACY_SKT':
      PIN_NUMBER='(CY59,0,0,0,0,0,0,0,0,0,0,0,0,0,0,0,0,0,0,0,0,0,0,0,0,0,0,0,0,0,0,0,0,0,0,0,0,0,0,0,0,0)';
      INPUT_LOAD='(-0.01,0.01)';
    'FRMAGENT':
      PIN_NUMBER='(AU17,0,0,0,0,0,0,0,0,0,0,0,0,0,0,0,0,0,0,0,0,0,0,0,0,0,0,0,0,0,0,0,0,0,0,0,0,0,0,0,0,0)';
      INPUT_LOAD='(-0.01,0.01)';
    'DMIMODE_OVERRIDE':
      PIN_NUMBER='(AW17,0,0,0,0,0,0,0,0,0,0,0,0,0,0,0,0,0,0,0,0,0,0,0,0,0,0,0,0,0,0,0,0,0,0,0,0,0,0,0,0,0)';
      INPUT_LOAD='(-0.01,0.01)';
    '-DDR67_RESET':
      PIN_NUMBER='(CY55,0,0,0,0,0,0,0,0,0,0,0,0,0,0,0,0,0,0,0,0,0,0,0,0,0,0,0,0,0,0,0,0,0,0,0,0,0,0,0,0,0)';
      OUTPUT_LOAD='(1.0,-1.0)';
    '-DDR45_RESET':
      PIN_NUMBER='(CY42,0,0,0,0,0,0,0,0,0,0,0,0,0,0,0,0,0,0,0,0,0,0,0,0,0,0,0,0,0,0,0,0,0,0,0,0,0,0,0,0,0)';
      OUTPUT_LOAD='(1.0,-1.0)';
    'DDR4567_SPDSDA':
      PIN_NUMBER='(CT18,0,0,0,0,0,0,0,0,0,0,0,0,0,0,0,0,0,0,0,0,0,0,0,0,0,0,0,0,0,0,0,0,0,0,0,0,0,0,0,0,0)';
      BIDIRECTIONAL='TRUE';
      INPUT_LOAD='(-0.01,0.01)';
      OUTPUT_LOAD='(1.0,-1.0)';
    'DDR4567_SPDSCL':
      PIN_NUMBER='(CU17,0,0,0,0,0,0,0,0,0,0,0,0,0,0,0,0,0,0,0,0,0,0,0,0,0,0,0,0,0,0,0,0,0,0,0,0,0,0,0,0,0)';
      OUTPUT_LOAD='(1.0,-1.0)';
    '-DDR23_RESET':
      PIN_NUMBER='(AV51,0,0,0,0,0,0,0,0,0,0,0,0,0,0,0,0,0,0,0,0,0,0,0,0,0,0,0,0,0,0,0,0,0,0,0,0,0,0,0,0,0)';
      OUTPUT_LOAD='(1.0,-1.0)';
    '-DDR01_RESET':
      PIN_NUMBER='(AU50,0,0,0,0,0,0,0,0,0,0,0,0,0,0,0,0,0,0,0,0,0,0,0,0,0,0,0,0,0,0,0,0,0,0,0,0,0,0,0,0,0)';
      OUTPUT_LOAD='(1.0,-1.0)';
    'DDR0123_SPDSDA':
      PIN_NUMBER='(BY22,0,0,0,0,0,0,0,0,0,0,0,0,0,0,0,0,0,0,0,0,0,0,0,0,0,0,0,0,0,0,0,0,0,0,0,0,0,0,0,0,0)';
      BIDIRECTIONAL='TRUE';
      INPUT_LOAD='(-0.01,0.01)';
      OUTPUT_LOAD='(1.0,-1.0)';
    'DDR0123_SPDSCL':
      PIN_NUMBER='(BT22,0,0,0,0,0,0,0,0,0,0,0,0,0,0,0,0,0,0,0,0,0,0,0,0,0,0,0,0,0,0,0,0,0,0,0,0,0,0,0,0,0)';
      OUTPUT_LOAD='(1.0,-1.0)';
    'BMCINIT':
      PIN_NUMBER='(BN23,0,0,0,0,0,0,0,0,0,0,0,0,0,0,0,0,0,0,0,0,0,0,0,0,0,0,0,0,0,0,0,0,0,0,0,0,0,0,0,0,0)';
      INPUT_LOAD='(-0.01,0.01)';
    'BIST_ENABLE':
      PIN_NUMBER='(AT18,0,0,0,0,0,0,0,0,0,0,0,0,0,0,0,0,0,0,0,0,0,0,0,0,0,0,0,0,0,0,0,0,0,0,0,0,0,0,0,0,0)';
      INPUT_LOAD='(-0.01,0.01)';
    'BCLK3_DP':
      PIN_NUMBER='(DA27,0,0,0,0,0,0,0,0,0,0,0,0,0,0,0,0,0,0,0,0,0,0,0,0,0,0,0,0,0,0,0,0,0,0,0,0,0,0,0,0,0)';
      INPUT_LOAD='(-0.01,0.01)';
    'BCLK3_DN':
      PIN_NUMBER='(CW27,0,0,0,0,0,0,0,0,0,0,0,0,0,0,0,0,0,0,0,0,0,0,0,0,0,0,0,0,0,0,0,0,0,0,0,0,0,0,0,0,0)';
      INPUT_LOAD='(-0.01,0.01)';
    'BCLK2_DP':
      PIN_NUMBER='(AV28,0,0,0,0,0,0,0,0,0,0,0,0,0,0,0,0,0,0,0,0,0,0,0,0,0,0,0,0,0,0,0,0,0,0,0,0,0,0,0,0,0)';
      INPUT_LOAD='(-0.01,0.01)';
    'BCLK2_DN':
      PIN_NUMBER='(AU29,0,0,0,0,0,0,0,0,0,0,0,0,0,0,0,0,0,0,0,0,0,0,0,0,0,0,0,0,0,0,0,0,0,0,0,0,0,0,0,0,0)';
      INPUT_LOAD='(-0.01,0.01)';
    'BCLK0_DP':
      PIN_NUMBER='(AV30,0,0,0,0,0,0,0,0,0,0,0,0,0,0,0,0,0,0,0,0,0,0,0,0,0,0,0,0,0,0,0,0,0,0,0,0,0,0,0,0,0)';
      INPUT_LOAD='(-0.01,0.01)';
    'BCLK1_DN':
      PIN_NUMBER='(CY28,0,0,0,0,0,0,0,0,0,0,0,0,0,0,0,0,0,0,0,0,0,0,0,0,0,0,0,0,0,0,0,0,0,0,0,0,0,0,0,0,0)';
      INPUT_LOAD='(-0.01,0.01)';
    'BCLK1_DP':
      PIN_NUMBER='(CW29,0,0,0,0,0,0,0,0,0,0,0,0,0,0,0,0,0,0,0,0,0,0,0,0,0,0,0,0,0,0,0,0,0,0,0,0,0,0,0,0,0)';
      INPUT_LOAD='(-0.01,0.01)';
    'BCLK0_DN':
      PIN_NUMBER='(AT30,0,0,0,0,0,0,0,0,0,0,0,0,0,0,0,0,0,0,0,0,0,0,0,0,0,0,0,0,0,0,0,0,0,0,0,0,0,0,0,0,0)';
      INPUT_LOAD='(-0.01,0.01)';
    'RSVD120':
      PIN_NUMBER='(CL72,0,0,0,0,0,0,0,0,0,0,0,0,0,0,0,0,0,0,0,0,0,0,0,0,0,0,0,0,0,0,0,0,0,0,0,0,0,0,0,0,0)';
      BIDIRECTIONAL='TRUE';
      INPUT_LOAD='(-0.01,0.01)';
      OUTPUT_LOAD='(1.0,-1.0)';
    'RSVD157':
      PIN_NUMBER='(D4,0,0,0,0,0,0,0,0,0,0,0,0,0,0,0,0,0,0,0,0,0,0,0,0,0,0,0,0,0,0,0,0,0,0,0,0,0,0,0,0,0)';
      BIDIRECTIONAL='TRUE';
      INPUT_LOAD='(-0.01,0.01)';
      OUTPUT_LOAD='(1.0,-1.0)';
    'XTAL_CLK_DN':
      PIN_NUMBER='(CW31,0,0,0,0,0,0,0,0,0,0,0,0,0,0,0,0,0,0,0,0,0,0,0,0,0,0,0,0,0,0,0,0,0,0,0,0,0,0,0,0,0)';
      INPUT_LOAD='(-0.01,0.01)';
    '-CATERR':
      PIN_NUMBER='(0,BP24,0,0,0,0,0,0,0,0,0,0,0,0,0,0,0,0,0,0,0,0,0,0,0,0,0,0,0,0,0,0,0,0,0,0,0,0,0,0,0,0)';
      BIDIRECTIONAL='TRUE';
      INPUT_LOAD='(-0.01,0.01)';
      OUTPUT_LOAD='(1.0,-1.0)';
    'CXPSMBUSSCL':
      PIN_NUMBER='(0,CA25,0,0,0,0,0,0,0,0,0,0,0,0,0,0,0,0,0,0,0,0,0,0,0,0,0,0,0,0,0,0,0,0,0,0,0,0,0,0,0,0)';
      OUTPUT_LOAD='(1.0,-1.0)';
    'CXPSMBUSSDA':
      PIN_NUMBER='(0,BY26,0,0,0,0,0,0,0,0,0,0,0,0,0,0,0,0,0,0,0,0,0,0,0,0,0,0,0,0,0,0,0,0,0,0,0,0,0,0,0,0)';
      BIDIRECTIONAL='TRUE';
      INPUT_LOAD='(-0.01,0.01)';
      OUTPUT_LOAD='(1.0,-1.0)';
    '-CXPSMBUS_ALERT':
      PIN_NUMBER='(0,BV26,0,0,0,0,0,0,0,0,0,0,0,0,0,0,0,0,0,0,0,0,0,0,0,0,0,0,0,0,0,0,0,0,0,0,0,0,0,0,0,0)';
      INPUT_LOAD='(-0.01,0.01)';
    'DDR01_DRAM_PWR_OK':
      PIN_NUMBER='(0,A43,0,0,0,0,0,0,0,0,0,0,0,0,0,0,0,0,0,0,0,0,0,0,0,0,0,0,0,0,0,0,0,0,0,0,0,0,0,0,0,0)';
      INPUT_LOAD='(-0.01,0.01)';
    'DDR23_DRAM_PWR_OK':
      PIN_NUMBER='(0,F47,0,0,0,0,0,0,0,0,0,0,0,0,0,0,0,0,0,0,0,0,0,0,0,0,0,0,0,0,0,0,0,0,0,0,0,0,0,0,0,0)';
      INPUT_LOAD='(-0.01,0.01)';
    'DDR45_DRAM_PWR_OK':
      PIN_NUMBER='(0,CY44,0,0,0,0,0,0,0,0,0,0,0,0,0,0,0,0,0,0,0,0,0,0,0,0,0,0,0,0,0,0,0,0,0,0,0,0,0,0,0,0)';
      INPUT_LOAD='(-0.01,0.01)';
    'DDR67_DRAM_PWR_OK':
      PIN_NUMBER='(0,CW45,0,0,0,0,0,0,0,0,0,0,0,0,0,0,0,0,0,0,0,0,0,0,0,0,0,0,0,0,0,0,0,0,0,0,0,0,0,0,0,0)';
      INPUT_LOAD='(-0.01,0.01)';
    'RSVD96':
      PIN_NUMBER='(0,CH22,0,0,0,0,0,0,0,0,0,0,0,0,0,0,0,0,0,0,0,0,0,0,0,0,0,0,0,0,0,0,0,0,0,0,0,0,0,0,0,0)';
      BIDIRECTIONAL='TRUE';
      INPUT_LOAD='(-0.01,0.01)';
      OUTPUT_LOAD='(1.0,-1.0)';
    'ERROR_N2':
      PIN_NUMBER='(0,BD22,0,0,0,0,0,0,0,0,0,0,0,0,0,0,0,0,0,0,0,0,0,0,0,0,0,0,0,0,0,0,0,0,0,0,0,0,0,0,0,0)';
      OUTPUT_LOAD='(1.0,-1.0)';
    'ERROR_N1':
      PIN_NUMBER='(0,AY22,0,0,0,0,0,0,0,0,0,0,0,0,0,0,0,0,0,0,0,0,0,0,0,0,0,0,0,0,0,0,0,0,0,0,0,0,0,0,0,0)';
      OUTPUT_LOAD='(1.0,-1.0)';
    'ERROR_N0':
      PIN_NUMBER='(0,BF22,0,0,0,0,0,0,0,0,0,0,0,0,0,0,0,0,0,0,0,0,0,0,0,0,0,0,0,0,0,0,0,0,0,0,0,0,0,0,0,0)';
      OUTPUT_LOAD='(1.0,-1.0)';
    '-FBRK':
      PIN_NUMBER='(0,AV57,0,0,0,0,0,0,0,0,0,0,0,0,0,0,0,0,0,0,0,0,0,0,0,0,0,0,0,0,0,0,0,0,0,0,0,0,0,0,0,0)';
      INPUT_LOAD='(-0.01,0.01)';
    '-MEMHOT_IN':
      PIN_NUMBER='(0,AU21,0,0,0,0,0,0,0,0,0,0,0,0,0,0,0,0,0,0,0,0,0,0,0,0,0,0,0,0,0,0,0,0,0,0,0,0,0,0,0,0)';
      INPUT_LOAD='(-0.01,0.01)';
    '-MEMHOT_OUT':
      PIN_NUMBER='(0,CF26,0,0,0,0,0,0,0,0,0,0,0,0,0,0,0,0,0,0,0,0,0,0,0,0,0,0,0,0,0,0,0,0,0,0,0,0,0,0,0,0)';
      OUTPUT_LOAD='(1.0,-1.0)';
    '-MEMTRIP':
      PIN_NUMBER='(0,AV24,0,0,0,0,0,0,0,0,0,0,0,0,0,0,0,0,0,0,0,0,0,0,0,0,0,0,0,0,0,0,0,0,0,0,0,0,0,0,0,0)';
      OUTPUT_LOAD='(1.0,-1.0)';
    'NMI':
      PIN_NUMBER='(0,AV18,0,0,0,0,0,0,0,0,0,0,0,0,0,0,0,0,0,0,0,0,0,0,0,0,0,0,0,0,0,0,0,0,0,0,0,0,0,0,0,0)';
      INPUT_LOAD='(-0.01,0.01)';
    'PIROM_AD2':
      PIN_NUMBER='(0,CP71,0,0,0,0,0,0,0,0,0,0,0,0,0,0,0,0,0,0,0,0,0,0,0,0,0,0,0,0,0,0,0,0,0,0,0,0,0,0,0,0)';
      INPUT_LOAD='(-0.01,0.01)';
    'PIROM_AD1':
      PIN_NUMBER='(0,CT71,0,0,0,0,0,0,0,0,0,0,0,0,0,0,0,0,0,0,0,0,0,0,0,0,0,0,0,0,0,0,0,0,0,0,0,0,0,0,0,0)';
      INPUT_LOAD='(-0.01,0.01)';
    'PIROM_AD0':
      PIN_NUMBER='(0,CR70,0,0,0,0,0,0,0,0,0,0,0,0,0,0,0,0,0,0,0,0,0,0,0,0,0,0,0,0,0,0,0,0,0,0,0,0,0,0,0,0)';
      INPUT_LOAD='(-0.01,0.01)';
    'PIROM_SCL':
      PIN_NUMBER='(0,CU70,0,0,0,0,0,0,0,0,0,0,0,0,0,0,0,0,0,0,0,0,0,0,0,0,0,0,0,0,0,0,0,0,0,0,0,0,0,0,0,0)';
      INPUT_LOAD='(-0.01,0.01)';
    'PIROM_SDA':
      PIN_NUMBER='(0,CM71,0,0,0,0,0,0,0,0,0,0,0,0,0,0,0,0,0,0,0,0,0,0,0,0,0,0,0,0,0,0,0,0,0,0,0,0,0,0,0,0)';
      BIDIRECTIONAL='TRUE';
      INPUT_LOAD='(-0.01,0.01)';
      OUTPUT_LOAD='(1.0,-1.0)';
    'PIROM_SM_WP':
      PIN_NUMBER='(0,CR72,0,0,0,0,0,0,0,0,0,0,0,0,0,0,0,0,0,0,0,0,0,0,0,0,0,0,0,0,0,0,0,0,0,0,0,0,0,0,0,0)';
      INPUT_LOAD='(-0.01,0.01)';
    'PMDOWN6':
      PIN_NUMBER='(0,CC25,0,0,0,0,0,0,0,0,0,0,0,0,0,0,0,0,0,0,0,0,0,0,0,0,0,0,0,0,0,0,0,0,0,0,0,0,0,0,0,0)';
      BIDIRECTIONAL='TRUE';
      INPUT_LOAD='(-0.01,0.01)';
      OUTPUT_LOAD='(1.0,-1.0)';
    'PMDOWN5':
      PIN_NUMBER='(0,CE23,0,0,0,0,0,0,0,0,0,0,0,0,0,0,0,0,0,0,0,0,0,0,0,0,0,0,0,0,0,0,0,0,0,0,0,0,0,0,0,0)';
      BIDIRECTIONAL='TRUE';
      INPUT_LOAD='(-0.01,0.01)';
      OUTPUT_LOAD='(1.0,-1.0)';
    'PMDOWN4':
      PIN_NUMBER='(0,CV18,0,0,0,0,0,0,0,0,0,0,0,0,0,0,0,0,0,0,0,0,0,0,0,0,0,0,0,0,0,0,0,0,0,0,0,0,0,0,0,0)';
      BIDIRECTIONAL='TRUE';
      INPUT_LOAD='(-0.01,0.01)';
      OUTPUT_LOAD='(1.0,-1.0)';
    'PMDOWN3':
      PIN_NUMBER='(0,CD24,0,0,0,0,0,0,0,0,0,0,0,0,0,0,0,0,0,0,0,0,0,0,0,0,0,0,0,0,0,0,0,0,0,0,0,0,0,0,0,0)';
      BIDIRECTIONAL='TRUE';
      INPUT_LOAD='(-0.01,0.01)';
      OUTPUT_LOAD='(1.0,-1.0)';
    'PMDOWN2':
      PIN_NUMBER='(0,CM26,0,0,0,0,0,0,0,0,0,0,0,0,0,0,0,0,0,0,0,0,0,0,0,0,0,0,0,0,0,0,0,0,0,0,0,0,0,0,0,0)';
      BIDIRECTIONAL='TRUE';
      INPUT_LOAD='(-0.01,0.01)';
      OUTPUT_LOAD='(1.0,-1.0)';
    'PMDOWN1':
      PIN_NUMBER='(0,CP26,0,0,0,0,0,0,0,0,0,0,0,0,0,0,0,0,0,0,0,0,0,0,0,0,0,0,0,0,0,0,0,0,0,0,0,0,0,0,0,0)';
      BIDIRECTIONAL='TRUE';
      INPUT_LOAD='(-0.01,0.01)';
      OUTPUT_LOAD='(1.0,-1.0)';
    'PMDOWN0':
      PIN_NUMBER='(0,CW39,0,0,0,0,0,0,0,0,0,0,0,0,0,0,0,0,0,0,0,0,0,0,0,0,0,0,0,0,0,0,0,0,0,0,0,0,0,0,0,0)';
      INPUT_LOAD='(-0.01,0.01)';
    'PMDOWN_PCH':
      PIN_NUMBER='(0,CY40,0,0,0,0,0,0,0,0,0,0,0,0,0,0,0,0,0,0,0,0,0,0,0,0,0,0,0,0,0,0,0,0,0,0,0,0,0,0,0,0)';
      BIDIRECTIONAL='TRUE';
      INPUT_LOAD='(-0.01,0.01)';
      OUTPUT_LOAD='(1.0,-1.0)';
    '-PMFAST_WAKE':
      PIN_NUMBER='(0,CP20,0,0,0,0,0,0,0,0,0,0,0,0,0,0,0,0,0,0,0,0,0,0,0,0,0,0,0,0,0,0,0,0,0,0,0,0,0,0,0,0)';
      BIDIRECTIONAL='TRUE';
      INPUT_LOAD='(-0.01,0.01)';
      OUTPUT_LOAD='(1.0,-1.0)';
    'PMSYNC6':
      PIN_NUMBER='(0,CF24,0,0,0,0,0,0,0,0,0,0,0,0,0,0,0,0,0,0,0,0,0,0,0,0,0,0,0,0,0,0,0,0,0,0,0,0,0,0,0,0)';
      BIDIRECTIONAL='TRUE';
      INPUT_LOAD='(-0.01,0.01)';
      OUTPUT_LOAD='(1.0,-1.0)';
    'PMSYNC5':
      PIN_NUMBER='(0,CH24,0,0,0,0,0,0,0,0,0,0,0,0,0,0,0,0,0,0,0,0,0,0,0,0,0,0,0,0,0,0,0,0,0,0,0,0,0,0,0,0)';
      BIDIRECTIONAL='TRUE';
      INPUT_LOAD='(-0.01,0.01)';
      OUTPUT_LOAD='(1.0,-1.0)';
    'PMSYNC4':
      PIN_NUMBER='(0,CR19,0,0,0,0,0,0,0,0,0,0,0,0,0,0,0,0,0,0,0,0,0,0,0,0,0,0,0,0,0,0,0,0,0,0,0,0,0,0,0,0)';
      BIDIRECTIONAL='TRUE';
      INPUT_LOAD='(-0.01,0.01)';
      OUTPUT_LOAD='(1.0,-1.0)';
    'PMSYNC3':
      PIN_NUMBER='(0,CE25,0,0,0,0,0,0,0,0,0,0,0,0,0,0,0,0,0,0,0,0,0,0,0,0,0,0,0,0,0,0,0,0,0,0,0,0,0,0,0,0)';
      BIDIRECTIONAL='TRUE';
      INPUT_LOAD='(-0.01,0.01)';
      OUTPUT_LOAD='(1.0,-1.0)';
    'PMSYNC2':
      PIN_NUMBER='(0,CH26,0,0,0,0,0,0,0,0,0,0,0,0,0,0,0,0,0,0,0,0,0,0,0,0,0,0,0,0,0,0,0,0,0,0,0,0,0,0,0,0)';
      BIDIRECTIONAL='TRUE';
      INPUT_LOAD='(-0.01,0.01)';
      OUTPUT_LOAD='(1.0,-1.0)';
    'PMSYNC1':
      PIN_NUMBER='(0,CL25,0,0,0,0,0,0,0,0,0,0,0,0,0,0,0,0,0,0,0,0,0,0,0,0,0,0,0,0,0,0,0,0,0,0,0,0,0,0,0,0)';
      BIDIRECTIONAL='TRUE';
      INPUT_LOAD='(-0.01,0.01)';
      OUTPUT_LOAD='(1.0,-1.0)';
    'PMSYNC0':
      PIN_NUMBER='(0,CN25,0,0,0,0,0,0,0,0,0,0,0,0,0,0,0,0,0,0,0,0,0,0,0,0,0,0,0,0,0,0,0,0,0,0,0,0,0,0,0,0)';
      BIDIRECTIONAL='TRUE';
      INPUT_LOAD='(-0.01,0.01)';
      OUTPUT_LOAD='(1.0,-1.0)';
    'PMSYNC_PCH':
      PIN_NUMBER='(0,DA39,0,0,0,0,0,0,0,0,0,0,0,0,0,0,0,0,0,0,0,0,0,0,0,0,0,0,0,0,0,0,0,0,0,0,0,0,0,0,0,0)';
      BIDIRECTIONAL='TRUE';
      INPUT_LOAD='(-0.01,0.01)';
      OUTPUT_LOAD='(1.0,-1.0)';
    '-PROCHOT':
      PIN_NUMBER='(0,AU19,0,0,0,0,0,0,0,0,0,0,0,0,0,0,0,0,0,0,0,0,0,0,0,0,0,0,0,0,0,0,0,0,0,0,0,0,0,0,0,0)';
      INPUT_LOAD='(-0.01,0.01)';
    'PWRGOOD':
      PIN_NUMBER='(0,AV20,0,0,0,0,0,0,0,0,0,0,0,0,0,0,0,0,0,0,0,0,0,0,0,0,0,0,0,0,0,0,0,0,0,0,0,0,0,0,0,0)';
      INPUT_LOAD='(-0.01,0.01)';
    '-RESET':
      PIN_NUMBER='(0,BH61,0,0,0,0,0,0,0,0,0,0,0,0,0,0,0,0,0,0,0,0,0,0,0,0,0,0,0,0,0,0,0,0,0,0,0,0,0,0,0,0)';
      INPUT_LOAD='(-0.01,0.01)';
    'RSVD113':
      PIN_NUMBER='(0,CL21,0,0,0,0,0,0,0,0,0,0,0,0,0,0,0,0,0,0,0,0,0,0,0,0,0,0,0,0,0,0,0,0,0,0,0,0,0,0,0,0)';
      BIDIRECTIONAL='TRUE';
      INPUT_LOAD='(-0.01,0.01)';
      OUTPUT_LOAD='(1.0,-1.0)';
    'RSVD116':
      PIN_NUMBER='(0,CL64,0,0,0,0,0,0,0,0,0,0,0,0,0,0,0,0,0,0,0,0,0,0,0,0,0,0,0,0,0,0,0,0,0,0,0,0,0,0,0,0)';
      BIDIRECTIONAL='TRUE';
      INPUT_LOAD='(-0.01,0.01)';
      OUTPUT_LOAD='(1.0,-1.0)';
    'RSVD121':
      PIN_NUMBER='(0,CM63,0,0,0,0,0,0,0,0,0,0,0,0,0,0,0,0,0,0,0,0,0,0,0,0,0,0,0,0,0,0,0,0,0,0,0,0,0,0,0,0)';
      BIDIRECTIONAL='TRUE';
      INPUT_LOAD='(-0.01,0.01)';
      OUTPUT_LOAD='(1.0,-1.0)';
    'RSVD126':
      PIN_NUMBER='(0,CN62,0,0,0,0,0,0,0,0,0,0,0,0,0,0,0,0,0,0,0,0,0,0,0,0,0,0,0,0,0,0,0,0,0,0,0,0,0,0,0,0)';
      BIDIRECTIONAL='TRUE';
      INPUT_LOAD='(-0.01,0.01)';
      OUTPUT_LOAD='(1.0,-1.0)';
    'RSVD132':
      PIN_NUMBER='(0,CR23,0,0,0,0,0,0,0,0,0,0,0,0,0,0,0,0,0,0,0,0,0,0,0,0,0,0,0,0,0,0,0,0,0,0,0,0,0,0,0,0)';
      BIDIRECTIONAL='TRUE';
      INPUT_LOAD='(-0.01,0.01)';
      OUTPUT_LOAD='(1.0,-1.0)';
    'RSVD141':
      PIN_NUMBER='(0,CV24,0,0,0,0,0,0,0,0,0,0,0,0,0,0,0,0,0,0,0,0,0,0,0,0,0,0,0,0,0,0,0,0,0,0,0,0,0,0,0,0)';
      BIDIRECTIONAL='TRUE';
      INPUT_LOAD='(-0.01,0.01)';
      OUTPUT_LOAD='(1.0,-1.0)';
    'RSVD145':
      PIN_NUMBER='(0,CW23,0,0,0,0,0,0,0,0,0,0,0,0,0,0,0,0,0,0,0,0,0,0,0,0,0,0,0,0,0,0,0,0,0,0,0,0,0,0,0,0)';
      BIDIRECTIONAL='TRUE';
      INPUT_LOAD='(-0.01,0.01)';
      OUTPUT_LOAD='(1.0,-1.0)';
    'RSVD146':
      PIN_NUMBER='(0,CW25,0,0,0,0,0,0,0,0,0,0,0,0,0,0,0,0,0,0,0,0,0,0,0,0,0,0,0,0,0,0,0,0,0,0,0,0,0,0,0,0)';
      BIDIRECTIONAL='TRUE';
      INPUT_LOAD='(-0.01,0.01)';
      OUTPUT_LOAD='(1.0,-1.0)';
    'RSVD150':
      PIN_NUMBER='(0,CW68,0,0,0,0,0,0,0,0,0,0,0,0,0,0,0,0,0,0,0,0,0,0,0,0,0,0,0,0,0,0,0,0,0,0,0,0,0,0,0,0)';
      BIDIRECTIONAL='TRUE';
      INPUT_LOAD='(-0.01,0.01)';
      OUTPUT_LOAD='(1.0,-1.0)';
    'RSVD15':
      PIN_NUMBER='(0,AV26,0,0,0,0,0,0,0,0,0,0,0,0,0,0,0,0,0,0,0,0,0,0,0,0,0,0,0,0,0,0,0,0,0,0,0,0,0,0,0,0)';
      BIDIRECTIONAL='TRUE';
      INPUT_LOAD='(-0.01,0.01)';
      OUTPUT_LOAD='(1.0,-1.0)';
    'RSVD27':
      PIN_NUMBER='(0,AY26,0,0,0,0,0,0,0,0,0,0,0,0,0,0,0,0,0,0,0,0,0,0,0,0,0,0,0,0,0,0,0,0,0,0,0,0,0,0,0,0)';
      BIDIRECTIONAL='TRUE';
      INPUT_LOAD='(-0.01,0.01)';
      OUTPUT_LOAD='(1.0,-1.0)';
    'RSVD29':
      PIN_NUMBER='(0,AY65,0,0,0,0,0,0,0,0,0,0,0,0,0,0,0,0,0,0,0,0,0,0,0,0,0,0,0,0,0,0,0,0,0,0,0,0,0,0,0,0)';
      BIDIRECTIONAL='TRUE';
      INPUT_LOAD='(-0.01,0.01)';
      OUTPUT_LOAD='(1.0,-1.0)';
    'RSVD4':
      PIN_NUMBER='(0,AT24,0,0,0,0,0,0,0,0,0,0,0,0,0,0,0,0,0,0,0,0,0,0,0,0,0,0,0,0,0,0,0,0,0,0,0,0,0,0,0,0)';
      BIDIRECTIONAL='TRUE';
      INPUT_LOAD='(-0.01,0.01)';
      OUTPUT_LOAD='(1.0,-1.0)';
    'RSVD59':
      PIN_NUMBER='(0,BJ70,0,0,0,0,0,0,0,0,0,0,0,0,0,0,0,0,0,0,0,0,0,0,0,0,0,0,0,0,0,0,0,0,0,0,0,0,0,0,0,0)';
      BIDIRECTIONAL='TRUE';
      INPUT_LOAD='(-0.01,0.01)';
      OUTPUT_LOAD='(1.0,-1.0)';
    'RSVD6':
      PIN_NUMBER='(0,AU25,0,0,0,0,0,0,0,0,0,0,0,0,0,0,0,0,0,0,0,0,0,0,0,0,0,0,0,0,0,0,0,0,0,0,0,0,0,0,0,0)';
      BIDIRECTIONAL='TRUE';
      INPUT_LOAD='(-0.01,0.01)';
      OUTPUT_LOAD='(1.0,-1.0)';
    'RSVD69':
      PIN_NUMBER='(0,BP67,0,0,0,0,0,0,0,0,0,0,0,0,0,0,0,0,0,0,0,0,0,0,0,0,0,0,0,0,0,0,0,0,0,0,0,0,0,0,0,0)';
      BIDIRECTIONAL='TRUE';
      INPUT_LOAD='(-0.01,0.01)';
      OUTPUT_LOAD='(1.0,-1.0)';
    'RSVD70':
      PIN_NUMBER='(0,BP69,0,0,0,0,0,0,0,0,0,0,0,0,0,0,0,0,0,0,0,0,0,0,0,0,0,0,0,0,0,0,0,0,0,0,0,0,0,0,0,0)';
      BIDIRECTIONAL='TRUE';
      INPUT_LOAD='(-0.01,0.01)';
      OUTPUT_LOAD='(1.0,-1.0)';
    'RSVD104':
      PIN_NUMBER='(0,CJ62,0,0,0,0,0,0,0,0,0,0,0,0,0,0,0,0,0,0,0,0,0,0,0,0,0,0,0,0,0,0,0,0,0,0,0,0,0,0,0,0)';
      BIDIRECTIONAL='TRUE';
      INPUT_LOAD='(-0.01,0.01)';
      OUTPUT_LOAD='(1.0,-1.0)';
    '-SKTOCC':
      PIN_NUMBER='(0,CG66,0,0,0,0,0,0,0,0,0,0,0,0,0,0,0,0,0,0,0,0,0,0,0,0,0,0,0,0,0,0,0,0,0,0,0,0,0,0,0,0)';
      OUTPUT_LOAD='(1.0,-1.0)';
    '-SVIDALERT0':
      PIN_NUMBER='(0,BK26,0,0,0,0,0,0,0,0,0,0,0,0,0,0,0,0,0,0,0,0,0,0,0,0,0,0,0,0,0,0,0,0,0,0,0,0,0,0,0,0)';
      INPUT_LOAD='(-0.01,0.01)';
    '-SVIDALERT1':
      PIN_NUMBER='(0,BJ25,0,0,0,0,0,0,0,0,0,0,0,0,0,0,0,0,0,0,0,0,0,0,0,0,0,0,0,0,0,0,0,0,0,0,0,0,0,0,0,0)';
      INPUT_LOAD='(-0.01,0.01)';
    'SVIDCLK0':
      PIN_NUMBER='(0,BH26,0,0,0,0,0,0,0,0,0,0,0,0,0,0,0,0,0,0,0,0,0,0,0,0,0,0,0,0,0,0,0,0,0,0,0,0,0,0,0,0)';
      OUTPUT_LOAD='(1.0,-1.0)';
    'SVIDCLK1':
      PIN_NUMBER='(0,BF26,0,0,0,0,0,0,0,0,0,0,0,0,0,0,0,0,0,0,0,0,0,0,0,0,0,0,0,0,0,0,0,0,0,0,0,0,0,0,0,0)';
      OUTPUT_LOAD='(1.0,-1.0)';
    'SVIDDATA0':
      PIN_NUMBER='(0,BD26,0,0,0,0,0,0,0,0,0,0,0,0,0,0,0,0,0,0,0,0,0,0,0,0,0,0,0,0,0,0,0,0,0,0,0,0,0,0,0,0)';
      BIDIRECTIONAL='TRUE';
      INPUT_LOAD='(-0.01,0.01)';
      OUTPUT_LOAD='(1.0,-1.0)';
    'SVIDDATA1':
      PIN_NUMBER='(0,BL25,0,0,0,0,0,0,0,0,0,0,0,0,0,0,0,0,0,0,0,0,0,0,0,0,0,0,0,0,0,0,0,0,0,0,0,0,0,0,0,0)';
      BIDIRECTIONAL='TRUE';
      INPUT_LOAD='(-0.01,0.01)';
      OUTPUT_LOAD='(1.0,-1.0)';
    'TAP_ODT_EN':
      PIN_NUMBER='(0,AY20,0,0,0,0,0,0,0,0,0,0,0,0,0,0,0,0,0,0,0,0,0,0,0,0,0,0,0,0,0,0,0,0,0,0,0,0,0,0,0,0)';
      INPUT_LOAD='(-0.01,0.01)';
    'RSVD19':
      PIN_NUMBER='(0,AV59,0,0,0,0,0,0,0,0,0,0,0,0,0,0,0,0,0,0,0,0,0,0,0,0,0,0,0,0,0,0,0,0,0,0,0,0,0,0,0,0)';
      BIDIRECTIONAL='TRUE';
      INPUT_LOAD='(-0.01,0.01)';
      OUTPUT_LOAD='(1.0,-1.0)';
    '-THERMTRIP':
      PIN_NUMBER='(0,BL62,0,0,0,0,0,0,0,0,0,0,0,0,0,0,0,0,0,0,0,0,0,0,0,0,0,0,0,0,0,0,0,0,0,0,0,0,0,0,0,0)';
      OUTPUT_LOAD='(1.0,-1.0)';
    'PLT_AUX_PWRGOOD':
      PIN_NUMBER='(0,0,CV20,0,0,0,0,0,0,0,0,0,0,0,0,0,0,0,0,0,0,0,0,0,0,0,0,0,0,0,0,0,0,0,0,0,0,0,0,0,0,0)';
      INPUT_LOAD='(-0.01,0.01)';
    'RSVD109':
      PIN_NUMBER='(0,0,CK22,0,0,0,0,0,0,0,0,0,0,0,0,0,0,0,0,0,0,0,0,0,0,0,0,0,0,0,0,0,0,0,0,0,0,0,0,0,0,0)';
      BIDIRECTIONAL='TRUE';
      INPUT_LOAD='(-0.01,0.01)';
      OUTPUT_LOAD='(1.0,-1.0)';
    'RSVD110':
      PIN_NUMBER='(0,0,CK24,0,0,0,0,0,0,0,0,0,0,0,0,0,0,0,0,0,0,0,0,0,0,0,0,0,0,0,0,0,0,0,0,0,0,0,0,0,0,0)';
      BIDIRECTIONAL='TRUE';
      INPUT_LOAD='(-0.01,0.01)';
      OUTPUT_LOAD='(1.0,-1.0)';
    'RSVD114':
      PIN_NUMBER='(0,0,CL23,0,0,0,0,0,0,0,0,0,0,0,0,0,0,0,0,0,0,0,0,0,0,0,0,0,0,0,0,0,0,0,0,0,0,0,0,0,0,0)';
      BIDIRECTIONAL='TRUE';
      INPUT_LOAD='(-0.01,0.01)';
      OUTPUT_LOAD='(1.0,-1.0)';
    'RSVD11':
      PIN_NUMBER='(0,0,AU62,0,0,0,0,0,0,0,0,0,0,0,0,0,0,0,0,0,0,0,0,0,0,0,0,0,0,0,0,0,0,0,0,0,0,0,0,0,0,0)';
      BIDIRECTIONAL='TRUE';
      INPUT_LOAD='(-0.01,0.01)';
      OUTPUT_LOAD='(1.0,-1.0)';
    'RSVD117':
      PIN_NUMBER='(0,0,CL66,0,0,0,0,0,0,0,0,0,0,0,0,0,0,0,0,0,0,0,0,0,0,0,0,0,0,0,0,0,0,0,0,0,0,0,0,0,0,0)';
      BIDIRECTIONAL='TRUE';
      INPUT_LOAD='(-0.01,0.01)';
      OUTPUT_LOAD='(1.0,-1.0)';
    'RSVD123':
      PIN_NUMBER='(0,0,CN21,0,0,0,0,0,0,0,0,0,0,0,0,0,0,0,0,0,0,0,0,0,0,0,0,0,0,0,0,0,0,0,0,0,0,0,0,0,0,0)';
      BIDIRECTIONAL='TRUE';
      INPUT_LOAD='(-0.01,0.01)';
      OUTPUT_LOAD='(1.0,-1.0)';
    'RSVD124':
      PIN_NUMBER='(0,0,CN23,0,0,0,0,0,0,0,0,0,0,0,0,0,0,0,0,0,0,0,0,0,0,0,0,0,0,0,0,0,0,0,0,0,0,0,0,0,0,0)';
      BIDIRECTIONAL='TRUE';
      INPUT_LOAD='(-0.01,0.01)';
      OUTPUT_LOAD='(1.0,-1.0)';
    'RSVD12':
      PIN_NUMBER='(0,0,AU64,0,0,0,0,0,0,0,0,0,0,0,0,0,0,0,0,0,0,0,0,0,0,0,0,0,0,0,0,0,0,0,0,0,0,0,0,0,0,0)';
      BIDIRECTIONAL='TRUE';
      INPUT_LOAD='(-0.01,0.01)';
      OUTPUT_LOAD='(1.0,-1.0)';
    'RSVD127':
      PIN_NUMBER='(0,0,CP22,0,0,0,0,0,0,0,0,0,0,0,0,0,0,0,0,0,0,0,0,0,0,0,0,0,0,0,0,0,0,0,0,0,0,0,0,0,0,0)';
      BIDIRECTIONAL='TRUE';
      INPUT_LOAD='(-0.01,0.01)';
      OUTPUT_LOAD='(1.0,-1.0)';
    'RSVD128':
      PIN_NUMBER='(0,0,CP24,0,0,0,0,0,0,0,0,0,0,0,0,0,0,0,0,0,0,0,0,0,0,0,0,0,0,0,0,0,0,0,0,0,0,0,0,0,0,0)';
      BIDIRECTIONAL='TRUE';
      INPUT_LOAD='(-0.01,0.01)';
      OUTPUT_LOAD='(1.0,-1.0)';
    'RSVD131':
      PIN_NUMBER='(0,0,CR21,0,0,0,0,0,0,0,0,0,0,0,0,0,0,0,0,0,0,0,0,0,0,0,0,0,0,0,0,0,0,0,0,0,0,0,0,0,0,0)';
      BIDIRECTIONAL='TRUE';
      INPUT_LOAD='(-0.01,0.01)';
      OUTPUT_LOAD='(1.0,-1.0)';
    'RSVD136':
      PIN_NUMBER='(0,0,CT22,0,0,0,0,0,0,0,0,0,0,0,0,0,0,0,0,0,0,0,0,0,0,0,0,0,0,0,0,0,0,0,0,0,0,0,0,0,0,0)';
      BIDIRECTIONAL='TRUE';
      INPUT_LOAD='(-0.01,0.01)';
      OUTPUT_LOAD='(1.0,-1.0)';
    'RSVD137':
      PIN_NUMBER='(0,0,CT24,0,0,0,0,0,0,0,0,0,0,0,0,0,0,0,0,0,0,0,0,0,0,0,0,0,0,0,0,0,0,0,0,0,0,0,0,0,0,0)';
      BIDIRECTIONAL='TRUE';
      INPUT_LOAD='(-0.01,0.01)';
      OUTPUT_LOAD='(1.0,-1.0)';
    'RSVD140':
      PIN_NUMBER='(0,0,CV22,0,0,0,0,0,0,0,0,0,0,0,0,0,0,0,0,0,0,0,0,0,0,0,0,0,0,0,0,0,0,0,0,0,0,0,0,0,0,0)';
      BIDIRECTIONAL='TRUE';
      INPUT_LOAD='(-0.01,0.01)';
      OUTPUT_LOAD='(1.0,-1.0)';
    'RSVD142':
      PIN_NUMBER='(0,0,CV69,0,0,0,0,0,0,0,0,0,0,0,0,0,0,0,0,0,0,0,0,0,0,0,0,0,0,0,0,0,0,0,0,0,0,0,0,0,0,0)';
      BIDIRECTIONAL='TRUE';
      INPUT_LOAD='(-0.01,0.01)';
      OUTPUT_LOAD='(1.0,-1.0)';
    'RSVD143':
      PIN_NUMBER='(0,0,CV71,0,0,0,0,0,0,0,0,0,0,0,0,0,0,0,0,0,0,0,0,0,0,0,0,0,0,0,0,0,0,0,0,0,0,0,0,0,0,0)';
      BIDIRECTIONAL='TRUE';
      INPUT_LOAD='(-0.01,0.01)';
      OUTPUT_LOAD='(1.0,-1.0)';
    'RSVD144':
      PIN_NUMBER='(0,0,CW21,0,0,0,0,0,0,0,0,0,0,0,0,0,0,0,0,0,0,0,0,0,0,0,0,0,0,0,0,0,0,0,0,0,0,0,0,0,0,0)';
      BIDIRECTIONAL='TRUE';
      INPUT_LOAD='(-0.01,0.01)';
      OUTPUT_LOAD='(1.0,-1.0)';
    'CD_INIT_ERROR':
      PIN_NUMBER='(0,0,CY20,0,0,0,0,0,0,0,0,0,0,0,0,0,0,0,0,0,0,0,0,0,0,0,0,0,0,0,0,0,0,0,0,0,0,0,0,0,0,0)';
      OUTPUT_LOAD='(1.0,-1.0)';
    'TEST_5':
      PIN_NUMBER='(0,0,CY22,0,0,0,0,0,0,0,0,0,0,0,0,0,0,0,0,0,0,0,0,0,0,0,0,0,0,0,0,0,0,0,0,0,0,0,0,0,0,0)';
      BIDIRECTIONAL='TRUE';
      INPUT_LOAD='(-0.01,0.01)';
      OUTPUT_LOAD='(1.0,-1.0)';
    'RSVD155':
      PIN_NUMBER='(0,0,CY69,0,0,0,0,0,0,0,0,0,0,0,0,0,0,0,0,0,0,0,0,0,0,0,0,0,0,0,0,0,0,0,0,0,0,0,0,0,0,0)';
      BIDIRECTIONAL='TRUE';
      INPUT_LOAD='(-0.01,0.01)';
      OUTPUT_LOAD='(1.0,-1.0)';
    'RSVD156':
      PIN_NUMBER='(0,0,CY71,0,0,0,0,0,0,0,0,0,0,0,0,0,0,0,0,0,0,0,0,0,0,0,0,0,0,0,0,0,0,0,0,0,0,0,0,0,0,0)';
      BIDIRECTIONAL='TRUE';
      INPUT_LOAD='(-0.01,0.01)';
      OUTPUT_LOAD='(1.0,-1.0)';
    'RSVD20':
      PIN_NUMBER='(0,0,AV63,0,0,0,0,0,0,0,0,0,0,0,0,0,0,0,0,0,0,0,0,0,0,0,0,0,0,0,0,0,0,0,0,0,0,0,0,0,0,0)';
      BIDIRECTIONAL='TRUE';
      INPUT_LOAD='(-0.01,0.01)';
      OUTPUT_LOAD='(1.0,-1.0)';
    'RSVD23':
      PIN_NUMBER='(0,0,AW19,0,0,0,0,0,0,0,0,0,0,0,0,0,0,0,0,0,0,0,0,0,0,0,0,0,0,0,0,0,0,0,0,0,0,0,0,0,0,0)';
      BIDIRECTIONAL='TRUE';
      INPUT_LOAD='(-0.01,0.01)';
      OUTPUT_LOAD='(1.0,-1.0)';
    'RSVD24':
      PIN_NUMBER='(0,0,AW64,0,0,0,0,0,0,0,0,0,0,0,0,0,0,0,0,0,0,0,0,0,0,0,0,0,0,0,0,0,0,0,0,0,0,0,0,0,0,0)';
      BIDIRECTIONAL='TRUE';
      INPUT_LOAD='(-0.01,0.01)';
      OUTPUT_LOAD='(1.0,-1.0)';
    'RSVD28':
      PIN_NUMBER='(0,0,AY61,0,0,0,0,0,0,0,0,0,0,0,0,0,0,0,0,0,0,0,0,0,0,0,0,0,0,0,0,0,0,0,0,0,0,0,0,0,0,0)';
      BIDIRECTIONAL='TRUE';
      INPUT_LOAD='(-0.01,0.01)';
      OUTPUT_LOAD='(1.0,-1.0)';
    'RSVD30':
      PIN_NUMBER='(0,0,AY67,0,0,0,0,0,0,0,0,0,0,0,0,0,0,0,0,0,0,0,0,0,0,0,0,0,0,0,0,0,0,0,0,0,0,0,0,0,0,0)';
      BIDIRECTIONAL='TRUE';
      INPUT_LOAD='(-0.01,0.01)';
      OUTPUT_LOAD='(1.0,-1.0)';
    'RSVD32':
      PIN_NUMBER='(0,0,BA62,0,0,0,0,0,0,0,0,0,0,0,0,0,0,0,0,0,0,0,0,0,0,0,0,0,0,0,0,0,0,0,0,0,0,0,0,0,0,0)';
      BIDIRECTIONAL='TRUE';
      INPUT_LOAD='(-0.01,0.01)';
      OUTPUT_LOAD='(1.0,-1.0)';
    'RSVD33':
      PIN_NUMBER='(0,0,BA66,0,0,0,0,0,0,0,0,0,0,0,0,0,0,0,0,0,0,0,0,0,0,0,0,0,0,0,0,0,0,0,0,0,0,0,0,0,0,0)';
      BIDIRECTIONAL='TRUE';
      INPUT_LOAD='(-0.01,0.01)';
      OUTPUT_LOAD='(1.0,-1.0)';
    'RSVD34':
      PIN_NUMBER='(0,0,BA68,0,0,0,0,0,0,0,0,0,0,0,0,0,0,0,0,0,0,0,0,0,0,0,0,0,0,0,0,0,0,0,0,0,0,0,0,0,0,0)';
      BIDIRECTIONAL='TRUE';
      INPUT_LOAD='(-0.01,0.01)';
      OUTPUT_LOAD='(1.0,-1.0)';
    'RSVD35':
      PIN_NUMBER='(0,0,BB61,0,0,0,0,0,0,0,0,0,0,0,0,0,0,0,0,0,0,0,0,0,0,0,0,0,0,0,0,0,0,0,0,0,0,0,0,0,0,0)';
      BIDIRECTIONAL='TRUE';
      INPUT_LOAD='(-0.01,0.01)';
      OUTPUT_LOAD='(1.0,-1.0)';
    'RSVD36':
      PIN_NUMBER='(0,0,BB67,0,0,0,0,0,0,0,0,0,0,0,0,0,0,0,0,0,0,0,0,0,0,0,0,0,0,0,0,0,0,0,0,0,0,0,0,0,0,0)';
      BIDIRECTIONAL='TRUE';
      INPUT_LOAD='(-0.01,0.01)';
      OUTPUT_LOAD='(1.0,-1.0)';
    'RSVD38':
      PIN_NUMBER='(0,0,BC25,0,0,0,0,0,0,0,0,0,0,0,0,0,0,0,0,0,0,0,0,0,0,0,0,0,0,0,0,0,0,0,0,0,0,0,0,0,0,0)';
      BIDIRECTIONAL='TRUE';
      INPUT_LOAD='(-0.01,0.01)';
      OUTPUT_LOAD='(1.0,-1.0)';
    'RSVD39':
      PIN_NUMBER='(0,0,BC64,0,0,0,0,0,0,0,0,0,0,0,0,0,0,0,0,0,0,0,0,0,0,0,0,0,0,0,0,0,0,0,0,0,0,0,0,0,0,0)';
      BIDIRECTIONAL='TRUE';
      INPUT_LOAD='(-0.01,0.01)';
      OUTPUT_LOAD='(1.0,-1.0)';
    'RSVD40':
      PIN_NUMBER='(0,0,BD61,0,0,0,0,0,0,0,0,0,0,0,0,0,0,0,0,0,0,0,0,0,0,0,0,0,0,0,0,0,0,0,0,0,0,0,0,0,0,0)';
      BIDIRECTIONAL='TRUE';
      INPUT_LOAD='(-0.01,0.01)';
      OUTPUT_LOAD='(1.0,-1.0)';
    'RSVD41':
      PIN_NUMBER='(0,0,BD63,0,0,0,0,0,0,0,0,0,0,0,0,0,0,0,0,0,0,0,0,0,0,0,0,0,0,0,0,0,0,0,0,0,0,0,0,0,0,0)';
      BIDIRECTIONAL='TRUE';
      INPUT_LOAD='(-0.01,0.01)';
      OUTPUT_LOAD='(1.0,-1.0)';
    'RSVD42':
      PIN_NUMBER='(0,0,BD65,0,0,0,0,0,0,0,0,0,0,0,0,0,0,0,0,0,0,0,0,0,0,0,0,0,0,0,0,0,0,0,0,0,0,0,0,0,0,0)';
      BIDIRECTIONAL='TRUE';
      INPUT_LOAD='(-0.01,0.01)';
      OUTPUT_LOAD='(1.0,-1.0)';
    'RSVD47':
      PIN_NUMBER='(0,0,BE25,0,0,0,0,0,0,0,0,0,0,0,0,0,0,0,0,0,0,0,0,0,0,0,0,0,0,0,0,0,0,0,0,0,0,0,0,0,0,0)';
      BIDIRECTIONAL='TRUE';
      INPUT_LOAD='(-0.01,0.01)';
      OUTPUT_LOAD='(1.0,-1.0)';
    'RSVD48':
      PIN_NUMBER='(0,0,BE62,0,0,0,0,0,0,0,0,0,0,0,0,0,0,0,0,0,0,0,0,0,0,0,0,0,0,0,0,0,0,0,0,0,0,0,0,0,0,0)';
      BIDIRECTIONAL='TRUE';
      INPUT_LOAD='(-0.01,0.01)';
      OUTPUT_LOAD='(1.0,-1.0)';
    'RSVD50':
      PIN_NUMBER='(0,0,BF65,0,0,0,0,0,0,0,0,0,0,0,0,0,0,0,0,0,0,0,0,0,0,0,0,0,0,0,0,0,0,0,0,0,0,0,0,0,0,0)';
      BIDIRECTIONAL='TRUE';
      INPUT_LOAD='(-0.01,0.01)';
      OUTPUT_LOAD='(1.0,-1.0)';
    'RSVD52':
      PIN_NUMBER='(0,0,BG62,0,0,0,0,0,0,0,0,0,0,0,0,0,0,0,0,0,0,0,0,0,0,0,0,0,0,0,0,0,0,0,0,0,0,0,0,0,0,0)';
      BIDIRECTIONAL='TRUE';
      INPUT_LOAD='(-0.01,0.01)';
      OUTPUT_LOAD='(1.0,-1.0)';
    'RSVD53':
      PIN_NUMBER='(0,0,BG64,0,0,0,0,0,0,0,0,0,0,0,0,0,0,0,0,0,0,0,0,0,0,0,0,0,0,0,0,0,0,0,0,0,0,0,0,0,0,0)';
      BIDIRECTIONAL='TRUE';
      INPUT_LOAD='(-0.01,0.01)';
      OUTPUT_LOAD='(1.0,-1.0)';
    'RSVD55':
      PIN_NUMBER='(0,0,BH63,0,0,0,0,0,0,0,0,0,0,0,0,0,0,0,0,0,0,0,0,0,0,0,0,0,0,0,0,0,0,0,0,0,0,0,0,0,0,0)';
      BIDIRECTIONAL='TRUE';
      INPUT_LOAD='(-0.01,0.01)';
      OUTPUT_LOAD='(1.0,-1.0)';
    'RSVD56':
      PIN_NUMBER='(0,0,BH65,0,0,0,0,0,0,0,0,0,0,0,0,0,0,0,0,0,0,0,0,0,0,0,0,0,0,0,0,0,0,0,0,0,0,0,0,0,0,0)';
      BIDIRECTIONAL='TRUE';
      INPUT_LOAD='(-0.01,0.01)';
      OUTPUT_LOAD='(1.0,-1.0)';
    'RSVD58':
      PIN_NUMBER='(0,0,BJ64,0,0,0,0,0,0,0,0,0,0,0,0,0,0,0,0,0,0,0,0,0,0,0,0,0,0,0,0,0,0,0,0,0,0,0,0,0,0,0)';
      BIDIRECTIONAL='TRUE';
      INPUT_LOAD='(-0.01,0.01)';
      OUTPUT_LOAD='(1.0,-1.0)';
    'RSVD61':
      PIN_NUMBER='(0,0,BK63,0,0,0,0,0,0,0,0,0,0,0,0,0,0,0,0,0,0,0,0,0,0,0,0,0,0,0,0,0,0,0,0,0,0,0,0,0,0,0)';
      BIDIRECTIONAL='TRUE';
      INPUT_LOAD='(-0.01,0.01)';
      OUTPUT_LOAD='(1.0,-1.0)';
    'RSVD64':
      PIN_NUMBER='(0,0,BM63,0,0,0,0,0,0,0,0,0,0,0,0,0,0,0,0,0,0,0,0,0,0,0,0,0,0,0,0,0,0,0,0,0,0,0,0,0,0,0)';
      BIDIRECTIONAL='TRUE';
      INPUT_LOAD='(-0.01,0.01)';
      OUTPUT_LOAD='(1.0,-1.0)';
    'RSVD86':
      PIN_NUMBER='(0,0,CD65,0,0,0,0,0,0,0,0,0,0,0,0,0,0,0,0,0,0,0,0,0,0,0,0,0,0,0,0,0,0,0,0,0,0,0,0,0,0,0)';
      BIDIRECTIONAL='TRUE';
      INPUT_LOAD='(-0.01,0.01)';
      OUTPUT_LOAD='(1.0,-1.0)';
    'TEST_6':
      PIN_NUMBER='(0,0,CF61,0,0,0,0,0,0,0,0,0,0,0,0,0,0,0,0,0,0,0,0,0,0,0,0,0,0,0,0,0,0,0,0,0,0,0,0,0,0,0)';
      BIDIRECTIONAL='TRUE';
      INPUT_LOAD='(-0.01,0.01)';
      OUTPUT_LOAD='(1.0,-1.0)';
    'RSVD93':
      PIN_NUMBER='(0,0,CF63,0,0,0,0,0,0,0,0,0,0,0,0,0,0,0,0,0,0,0,0,0,0,0,0,0,0,0,0,0,0,0,0,0,0,0,0,0,0,0)';
      BIDIRECTIONAL='TRUE';
      INPUT_LOAD='(-0.01,0.01)';
      OUTPUT_LOAD='(1.0,-1.0)';
    'RSVD94':
      PIN_NUMBER='(0,0,CF65,0,0,0,0,0,0,0,0,0,0,0,0,0,0,0,0,0,0,0,0,0,0,0,0,0,0,0,0,0,0,0,0,0,0,0,0,0,0,0)';
      BIDIRECTIONAL='TRUE';
      INPUT_LOAD='(-0.01,0.01)';
      OUTPUT_LOAD='(1.0,-1.0)';
    'RSVD98':
      PIN_NUMBER='(0,0,CH63,0,0,0,0,0,0,0,0,0,0,0,0,0,0,0,0,0,0,0,0,0,0,0,0,0,0,0,0,0,0,0,0,0,0,0,0,0,0,0)';
      BIDIRECTIONAL='TRUE';
      INPUT_LOAD='(-0.01,0.01)';
      OUTPUT_LOAD='(1.0,-1.0)';
    'RSVD100':
      PIN_NUMBER='(0,0,CH71,0,0,0,0,0,0,0,0,0,0,0,0,0,0,0,0,0,0,0,0,0,0,0,0,0,0,0,0,0,0,0,0,0,0,0,0,0,0,0)';
      BIDIRECTIONAL='TRUE';
      INPUT_LOAD='(-0.01,0.01)';
      OUTPUT_LOAD='(1.0,-1.0)';
    'RSVD101':
      PIN_NUMBER='(0,0,CJ21,0,0,0,0,0,0,0,0,0,0,0,0,0,0,0,0,0,0,0,0,0,0,0,0,0,0,0,0,0,0,0,0,0,0,0,0,0,0,0)';
      BIDIRECTIONAL='TRUE';
      INPUT_LOAD='(-0.01,0.01)';
      OUTPUT_LOAD='(1.0,-1.0)';
    'RSVD102':
      PIN_NUMBER='(0,0,CJ23,0,0,0,0,0,0,0,0,0,0,0,0,0,0,0,0,0,0,0,0,0,0,0,0,0,0,0,0,0,0,0,0,0,0,0,0,0,0,0)';
      BIDIRECTIONAL='TRUE';
      INPUT_LOAD='(-0.01,0.01)';
      OUTPUT_LOAD='(1.0,-1.0)';
    'RSVD103':
      PIN_NUMBER='(0,0,CJ25,0,0,0,0,0,0,0,0,0,0,0,0,0,0,0,0,0,0,0,0,0,0,0,0,0,0,0,0,0,0,0,0,0,0,0,0,0,0,0)';
      BIDIRECTIONAL='TRUE';
      INPUT_LOAD='(-0.01,0.01)';
      OUTPUT_LOAD='(1.0,-1.0)';
    'RSVD105':
      PIN_NUMBER='(0,0,CJ66,0,0,0,0,0,0,0,0,0,0,0,0,0,0,0,0,0,0,0,0,0,0,0,0,0,0,0,0,0,0,0,0,0,0,0,0,0,0,0)';
      BIDIRECTIONAL='TRUE';
      INPUT_LOAD='(-0.01,0.01)';
      OUTPUT_LOAD='(1.0,-1.0)';
    'RSVD25':
      PIN_NUMBER='(0,0,AW70,0,0,0,0,0,0,0,0,0,0,0,0,0,0,0,0,0,0,0,0,0,0,0,0,0,0,0,0,0,0,0,0,0,0,0,0,0,0,0)';
      BIDIRECTIONAL='TRUE';
      INPUT_LOAD='(-0.01,0.01)';
      OUTPUT_LOAD='(1.0,-1.0)';
    'TEST_8':
      PIN_NUMBER='(0,0,AY69,0,0,0,0,0,0,0,0,0,0,0,0,0,0,0,0,0,0,0,0,0,0,0,0,0,0,0,0,0,0,0,0,0,0,0,0,0,0,0)';
      BIDIRECTIONAL='TRUE';
      INPUT_LOAD='(-0.01,0.01)';
      OUTPUT_LOAD='(1.0,-1.0)';
    'TEST_7':
      PIN_NUMBER='(0,0,AV69,0,0,0,0,0,0,0,0,0,0,0,0,0,0,0,0,0,0,0,0,0,0,0,0,0,0,0,0,0,0,0,0,0,0,0,0,0,0,0)';
      BIDIRECTIONAL='TRUE';
      INPUT_LOAD='(-0.01,0.01)';
      OUTPUT_LOAD='(1.0,-1.0)';
    'PARTITION_ID1':
      PIN_NUMBER='(0,0,AV71,0,0,0,0,0,0,0,0,0,0,0,0,0,0,0,0,0,0,0,0,0,0,0,0,0,0,0,0,0,0,0,0,0,0,0,0,0,0,0)';
      INPUT_LOAD='(-0.01,0.01)';
    'PARTITION_ID0':
      PIN_NUMBER='(0,0,BA70,0,0,0,0,0,0,0,0,0,0,0,0,0,0,0,0,0,0,0,0,0,0,0,0,0,0,0,0,0,0,0,0,0,0,0,0,0,0,0)';
      INPUT_LOAD='(-0.01,0.01)';
    'SMB_CLK':
      PIN_NUMBER='(0,0,CE64,0,0,0,0,0,0,0,0,0,0,0,0,0,0,0,0,0,0,0,0,0,0,0,0,0,0,0,0,0,0,0,0,0,0,0,0,0,0,0)';
      OUTPUT_LOAD='(1.0,-1.0)';
    'SMB_DATA':
      PIN_NUMBER='(0,0,CD63,0,0,0,0,0,0,0,0,0,0,0,0,0,0,0,0,0,0,0,0,0,0,0,0,0,0,0,0,0,0,0,0,0,0,0,0,0,0,0)';
      BIDIRECTIONAL='TRUE';
      INPUT_LOAD='(-0.01,0.01)';
      OUTPUT_LOAD='(1.0,-1.0)';
    'TEST_1':
      PIN_NUMBER='(0,0,CJ64,0,0,0,0,0,0,0,0,0,0,0,0,0,0,0,0,0,0,0,0,0,0,0,0,0,0,0,0,0,0,0,0,0,0,0,0,0,0,0)';
      BIDIRECTIONAL='TRUE';
      INPUT_LOAD='(-0.01,0.01)';
      OUTPUT_LOAD='(1.0,-1.0)';
    'TEST_2':
      PIN_NUMBER='(0,0,CK65,0,0,0,0,0,0,0,0,0,0,0,0,0,0,0,0,0,0,0,0,0,0,0,0,0,0,0,0,0,0,0,0,0,0,0,0,0,0,0)';
      BIDIRECTIONAL='TRUE';
      INPUT_LOAD='(-0.01,0.01)';
      OUTPUT_LOAD='(1.0,-1.0)';
    'TEST_3':
      PIN_NUMBER='(0,0,CH65,0,0,0,0,0,0,0,0,0,0,0,0,0,0,0,0,0,0,0,0,0,0,0,0,0,0,0,0,0,0,0,0,0,0,0,0,0,0,0)';
      BIDIRECTIONAL='TRUE';
      INPUT_LOAD='(-0.01,0.01)';
      OUTPUT_LOAD='(1.0,-1.0)';
    'RSVD37':
      PIN_NUMBER='(0,0,0,BC23,0,0,0,0,0,0,0,0,0,0,0,0,0,0,0,0,0,0,0,0,0,0,0,0,0,0,0,0,0,0,0,0,0,0,0,0,0,0)';
      BIDIRECTIONAL='TRUE';
      INPUT_LOAD='(-0.01,0.01)';
      OUTPUT_LOAD='(1.0,-1.0)';
    'RSVD46':
      PIN_NUMBER='(0,0,0,BE23,0,0,0,0,0,0,0,0,0,0,0,0,0,0,0,0,0,0,0,0,0,0,0,0,0,0,0,0,0,0,0,0,0,0,0,0,0,0)';
      BIDIRECTIONAL='TRUE';
      INPUT_LOAD='(-0.01,0.01)';
      OUTPUT_LOAD='(1.0,-1.0)';
    'RSVD49':
      PIN_NUMBER='(0,0,0,BF24,0,0,0,0,0,0,0,0,0,0,0,0,0,0,0,0,0,0,0,0,0,0,0,0,0,0,0,0,0,0,0,0,0,0,0,0,0,0)';
      BIDIRECTIONAL='TRUE';
      INPUT_LOAD='(-0.01,0.01)';
      OUTPUT_LOAD='(1.0,-1.0)';
    '-MBP0':
      PIN_NUMBER='(0,0,0,BL23,0,0,0,0,0,0,0,0,0,0,0,0,0,0,0,0,0,0,0,0,0,0,0,0,0,0,0,0,0,0,0,0,0,0,0,0,0,0)';
      BIDIRECTIONAL='TRUE';
      INPUT_LOAD='(-0.01,0.01)';
      OUTPUT_LOAD='(1.0,-1.0)';
    '-MBP1':
      PIN_NUMBER='(0,0,0,BN25,0,0,0,0,0,0,0,0,0,0,0,0,0,0,0,0,0,0,0,0,0,0,0,0,0,0,0,0,0,0,0,0,0,0,0,0,0,0)';
      BIDIRECTIONAL='TRUE';
      INPUT_LOAD='(-0.01,0.01)';
      OUTPUT_LOAD='(1.0,-1.0)';
    '-MBP2':
      PIN_NUMBER='(0,0,0,BJ23,0,0,0,0,0,0,0,0,0,0,0,0,0,0,0,0,0,0,0,0,0,0,0,0,0,0,0,0,0,0,0,0,0,0,0,0,0,0)';
      BIDIRECTIONAL='TRUE';
      INPUT_LOAD='(-0.01,0.01)';
      OUTPUT_LOAD='(1.0,-1.0)';
    '-MBP3':
      PIN_NUMBER='(0,0,0,BK24,0,0,0,0,0,0,0,0,0,0,0,0,0,0,0,0,0,0,0,0,0,0,0,0,0,0,0,0,0,0,0,0,0,0,0,0,0,0)';
      BIDIRECTIONAL='TRUE';
      INPUT_LOAD='(-0.01,0.01)';
      OUTPUT_LOAD='(1.0,-1.0)';
    'PMAX_TRIGGER_IO':
      PIN_NUMBER='(0,0,0,BD24,0,0,0,0,0,0,0,0,0,0,0,0,0,0,0,0,0,0,0,0,0,0,0,0,0,0,0,0,0,0,0,0,0,0,0,0,0,0)';
      BIDIRECTIONAL='TRUE';
      INPUT_LOAD='(-0.01,0.01)';
      OUTPUT_LOAD='(1.0,-1.0)';
    '-RMCA':
      PIN_NUMBER='(0,0,0,BH22,0,0,0,0,0,0,0,0,0,0,0,0,0,0,0,0,0,0,0,0,0,0,0,0,0,0,0,0,0,0,0,0,0,0,0,0,0,0)';
      BIDIRECTIONAL='TRUE';
      INPUT_LOAD='(-0.01,0.01)';
      OUTPUT_LOAD='(1.0,-1.0)';
    'RSVD10':
      PIN_NUMBER='(0,0,0,AU58,0,0,0,0,0,0,0,0,0,0,0,0,0,0,0,0,0,0,0,0,0,0,0,0,0,0,0,0,0,0,0,0,0,0,0,0,0,0)';
      BIDIRECTIONAL='TRUE';
      INPUT_LOAD='(-0.01,0.01)';
      OUTPUT_LOAD='(1.0,-1.0)';
    'RSVD90':
      PIN_NUMBER='(0,0,0,CE62,0,0,0,0,0,0,0,0,0,0,0,0,0,0,0,0,0,0,0,0,0,0,0,0,0,0,0,0,0,0,0,0,0,0,0,0,0,0)';
      BIDIRECTIONAL='TRUE';
      INPUT_LOAD='(-0.01,0.01)';
      OUTPUT_LOAD='(1.0,-1.0)';
    'RSVD139':
      PIN_NUMBER='(0,0,0,CU62,0,0,0,0,0,0,0,0,0,0,0,0,0,0,0,0,0,0,0,0,0,0,0,0,0,0,0,0,0,0,0,0,0,0,0,0,0,0)';
      BIDIRECTIONAL='TRUE';
      INPUT_LOAD='(-0.01,0.01)';
      OUTPUT_LOAD='(1.0,-1.0)';
    'RSVD125':
      PIN_NUMBER='(0,0,0,CN60,0,0,0,0,0,0,0,0,0,0,0,0,0,0,0,0,0,0,0,0,0,0,0,0,0,0,0,0,0,0,0,0,0,0,0,0,0,0)';
      BIDIRECTIONAL='TRUE';
      INPUT_LOAD='(-0.01,0.01)';
      OUTPUT_LOAD='(1.0,-1.0)';
    'RSVD129':
      PIN_NUMBER='(0,0,0,CP61,0,0,0,0,0,0,0,0,0,0,0,0,0,0,0,0,0,0,0,0,0,0,0,0,0,0,0,0,0,0,0,0,0,0,0,0,0,0)';
      BIDIRECTIONAL='TRUE';
      INPUT_LOAD='(-0.01,0.01)';
      OUTPUT_LOAD='(1.0,-1.0)';
    'RSVD134':
      PIN_NUMBER='(0,0,0,CR60,0,0,0,0,0,0,0,0,0,0,0,0,0,0,0,0,0,0,0,0,0,0,0,0,0,0,0,0,0,0,0,0,0,0,0,0,0,0)';
      BIDIRECTIONAL='TRUE';
      INPUT_LOAD='(-0.01,0.01)';
      OUTPUT_LOAD='(1.0,-1.0)';
    'RSVD151':
      PIN_NUMBER='(0,0,0,CY24,0,0,0,0,0,0,0,0,0,0,0,0,0,0,0,0,0,0,0,0,0,0,0,0,0,0,0,0,0,0,0,0,0,0,0,0,0,0)';
      BIDIRECTIONAL='TRUE';
      INPUT_LOAD='(-0.01,0.01)';
      OUTPUT_LOAD='(1.0,-1.0)';
    'RSVD152':
      PIN_NUMBER='(0,0,0,CY38,0,0,0,0,0,0,0,0,0,0,0,0,0,0,0,0,0,0,0,0,0,0,0,0,0,0,0,0,0,0,0,0,0,0,0,0,0,0)';
      BIDIRECTIONAL='TRUE';
      INPUT_LOAD='(-0.01,0.01)';
      OUTPUT_LOAD='(1.0,-1.0)';
    'RSVD153':
      PIN_NUMBER='(0,0,0,CY49,0,0,0,0,0,0,0,0,0,0,0,0,0,0,0,0,0,0,0,0,0,0,0,0,0,0,0,0,0,0,0,0,0,0,0,0,0,0)';
      BIDIRECTIONAL='TRUE';
      INPUT_LOAD='(-0.01,0.01)';
      OUTPUT_LOAD='(1.0,-1.0)';
    'RSVD158':
      PIN_NUMBER='(0,0,0,DA45,0,0,0,0,0,0,0,0,0,0,0,0,0,0,0,0,0,0,0,0,0,0,0,0,0,0,0,0,0,0,0,0,0,0,0,0,0,0)';
      BIDIRECTIONAL='TRUE';
      INPUT_LOAD='(-0.01,0.01)';
      OUTPUT_LOAD='(1.0,-1.0)';
    'RSVD162':
      PIN_NUMBER='(0,0,0,H12,0,0,0,0,0,0,0,0,0,0,0,0,0,0,0,0,0,0,0,0,0,0,0,0,0,0,0,0,0,0,0,0,0,0,0,0,0,0)';
      BIDIRECTIONAL='TRUE';
      INPUT_LOAD='(-0.01,0.01)';
      OUTPUT_LOAD='(1.0,-1.0)';
    'RSVD16':
      PIN_NUMBER='(0,0,0,AV32,0,0,0,0,0,0,0,0,0,0,0,0,0,0,0,0,0,0,0,0,0,0,0,0,0,0,0,0,0,0,0,0,0,0,0,0,0,0)';
      BIDIRECTIONAL='TRUE';
      INPUT_LOAD='(-0.01,0.01)';
      OUTPUT_LOAD='(1.0,-1.0)';
    'RSVD17':
      PIN_NUMBER='(0,0,0,AV38,0,0,0,0,0,0,0,0,0,0,0,0,0,0,0,0,0,0,0,0,0,0,0,0,0,0,0,0,0,0,0,0,0,0,0,0,0,0)';
      BIDIRECTIONAL='TRUE';
      INPUT_LOAD='(-0.01,0.01)';
      OUTPUT_LOAD='(1.0,-1.0)';
    'RSVD18':
      PIN_NUMBER='(0,0,0,AV40,0,0,0,0,0,0,0,0,0,0,0,0,0,0,0,0,0,0,0,0,0,0,0,0,0,0,0,0,0,0,0,0,0,0,0,0,0,0)';
      BIDIRECTIONAL='TRUE';
      INPUT_LOAD='(-0.01,0.01)';
      OUTPUT_LOAD='(1.0,-1.0)';
    'RSVD7':
      PIN_NUMBER='(0,0,0,AU33,0,0,0,0,0,0,0,0,0,0,0,0,0,0,0,0,0,0,0,0,0,0,0,0,0,0,0,0,0,0,0,0,0,0,0,0,0,0)';
      BIDIRECTIONAL='TRUE';
      INPUT_LOAD='(-0.01,0.01)';
      OUTPUT_LOAD='(1.0,-1.0)';
    'RSVD9':
      PIN_NUMBER='(0,0,0,AU56,0,0,0,0,0,0,0,0,0,0,0,0,0,0,0,0,0,0,0,0,0,0,0,0,0,0,0,0,0,0,0,0,0,0,0,0,0,0)';
      BIDIRECTIONAL='TRUE';
      INPUT_LOAD='(-0.01,0.01)';
      OUTPUT_LOAD='(1.0,-1.0)';
    'RSVD81':
      PIN_NUMBER='(0,0,0,CC64,0,0,0,0,0,0,0,0,0,0,0,0,0,0,0,0,0,0,0,0,0,0,0,0,0,0,0,0,0,0,0,0,0,0,0,0,0,0)';
      BIDIRECTIONAL='TRUE';
      INPUT_LOAD='(-0.01,0.01)';
      OUTPUT_LOAD='(1.0,-1.0)';
    'VCCD_HV_SENSE':
      PIN_NUMBER='(0,0,0,BU11,0,0,0,0,0,0,0,0,0,0,0,0,0,0,0,0,0,0,0,0,0,0,0,0,0,0,0,0,0,0,0,0,0,0,0,0,0,0)';
      PINUSE='POWER';
      NO_LOAD_CHECK='Both';
      NO_IO_CHECK='Both';
      NO_ASSERT_CHECK='TRUE';
      NO_DIR_CHECK='TRUE';
      ALLOW_CONNECT='TRUE';
    'VCCFA_EHV_FIVRA_SENSE':
      PIN_NUMBER='(0,0,0,AY85,0,0,0,0,0,0,0,0,0,0,0,0,0,0,0,0,0,0,0,0,0,0,0,0,0,0,0,0,0,0,0,0,0,0,0,0,0,0)';
      PINUSE='POWER';
      NO_LOAD_CHECK='Both';
      NO_IO_CHECK='Both';
      NO_ASSERT_CHECK='TRUE';
      NO_DIR_CHECK='TRUE';
      ALLOW_CONNECT='TRUE';
    'VCCFA_EHV_SENSE':
      PIN_NUMBER='(0,0,0,AU11,0,0,0,0,0,0,0,0,0,0,0,0,0,0,0,0,0,0,0,0,0,0,0,0,0,0,0,0,0,0,0,0,0,0,0,0,0,0)';
      PINUSE='POWER';
      NO_LOAD_CHECK='Both';
      NO_IO_CHECK='Both';
      NO_ASSERT_CHECK='TRUE';
      NO_DIR_CHECK='TRUE';
      ALLOW_CONNECT='TRUE';
    'VCCINFAON_SENSE':
      PIN_NUMBER='(0,0,0,CA11,0,0,0,0,0,0,0,0,0,0,0,0,0,0,0,0,0,0,0,0,0,0,0,0,0,0,0,0,0,0,0,0,0,0,0,0,0,0)';
      PINUSE='POWER';
      NO_LOAD_CHECK='Both';
      NO_IO_CHECK='Both';
      NO_ASSERT_CHECK='TRUE';
      NO_DIR_CHECK='TRUE';
      ALLOW_CONNECT='TRUE';
    'VCCIN_SENSE':
      PIN_NUMBER='(0,0,0,BD87,0,0,0,0,0,0,0,0,0,0,0,0,0,0,0,0,0,0,0,0,0,0,0,0,0,0,0,0,0,0,0,0,0,0,0,0,0,0)';
      PINUSE='POWER';
      NO_LOAD_CHECK='Both';
      NO_IO_CHECK='Both';
      NO_ASSERT_CHECK='TRUE';
      NO_DIR_CHECK='TRUE';
      ALLOW_CONNECT='TRUE';
    'VSS_VCCD_HV_SENSE':
      PIN_NUMBER='(0,0,0,BN11,0,0,0,0,0,0,0,0,0,0,0,0,0,0,0,0,0,0,0,0,0,0,0,0,0,0,0,0,0,0,0,0,0,0,0,0,0,0)';
      PINUSE='POWER';
      NO_LOAD_CHECK='Both';
      NO_IO_CHECK='Both';
      NO_ASSERT_CHECK='TRUE';
      NO_DIR_CHECK='TRUE';
      ALLOW_CONNECT='TRUE';
    'VSS_VCCFA_EHV_FIVRA_SENSE':
      PIN_NUMBER='(0,0,0,AT85,0,0,0,0,0,0,0,0,0,0,0,0,0,0,0,0,0,0,0,0,0,0,0,0,0,0,0,0,0,0,0,0,0,0,0,0,0,0)';
      PINUSE='POWER';
      NO_LOAD_CHECK='Both';
      NO_IO_CHECK='Both';
      NO_ASSERT_CHECK='TRUE';
      NO_DIR_CHECK='TRUE';
      ALLOW_CONNECT='TRUE';
    'VSS_VCCFA_EHV_SENSE':
      PIN_NUMBER='(0,0,0,BA11,0,0,0,0,0,0,0,0,0,0,0,0,0,0,0,0,0,0,0,0,0,0,0,0,0,0,0,0,0,0,0,0,0,0,0,0,0,0)';
      PINUSE='POWER';
      NO_LOAD_CHECK='Both';
      NO_IO_CHECK='Both';
      NO_ASSERT_CHECK='TRUE';
      NO_DIR_CHECK='TRUE';
      ALLOW_CONNECT='TRUE';
    'VSS_VCCINFAON_SENSE':
      PIN_NUMBER='(0,0,0,CE11,0,0,0,0,0,0,0,0,0,0,0,0,0,0,0,0,0,0,0,0,0,0,0,0,0,0,0,0,0,0,0,0,0,0,0,0,0,0)';
      PINUSE='POWER';
      NO_LOAD_CHECK='Both';
      NO_IO_CHECK='Both';
      NO_ASSERT_CHECK='TRUE';
      NO_DIR_CHECK='TRUE';
      ALLOW_CONNECT='TRUE';
    'VSS_VCCIN_SENSE':
      PIN_NUMBER='(0,0,0,BC90,0,0,0,0,0,0,0,0,0,0,0,0,0,0,0,0,0,0,0,0,0,0,0,0,0,0,0,0,0,0,0,0,0,0,0,0,0,0)';
      PINUSE='POWER';
      NO_LOAD_CHECK='Both';
      NO_IO_CHECK='Both';
      NO_ASSERT_CHECK='TRUE';
      NO_DIR_CHECK='TRUE';
      ALLOW_CONNECT='TRUE';
    'RSVD0':
      PIN_NUMBER='(0,0,0,0,AC78,0,0,0,0,0,0,0,0,0,0,0,0,0,0,0,0,0,0,0,0,0,0,0,0,0,0,0,0,0,0,0,0,0,0,0,0,0)';
      BIDIRECTIONAL='TRUE';
      INPUT_LOAD='(-0.01,0.01)';
      OUTPUT_LOAD='(1.0,-1.0)';
    'RSVD1':
      PIN_NUMBER='(0,0,0,0,AD77,0,0,0,0,0,0,0,0,0,0,0,0,0,0,0,0,0,0,0,0,0,0,0,0,0,0,0,0,0,0,0,0,0,0,0,0,0)';
      BIDIRECTIONAL='TRUE';
      INPUT_LOAD='(-0.01,0.01)';
      OUTPUT_LOAD='(1.0,-1.0)';
    'RSVD106':
      PIN_NUMBER='(0,0,0,0,CJ68,0,0,0,0,0,0,0,0,0,0,0,0,0,0,0,0,0,0,0,0,0,0,0,0,0,0,0,0,0,0,0,0,0,0,0,0,0)';
      BIDIRECTIONAL='TRUE';
      INPUT_LOAD='(-0.01,0.01)';
      OUTPUT_LOAD='(1.0,-1.0)';
    'RSVD107':
      PIN_NUMBER='(0,0,0,0,CJ70,0,0,0,0,0,0,0,0,0,0,0,0,0,0,0,0,0,0,0,0,0,0,0,0,0,0,0,0,0,0,0,0,0,0,0,0,0)';
      BIDIRECTIONAL='TRUE';
      INPUT_LOAD='(-0.01,0.01)';
      OUTPUT_LOAD='(1.0,-1.0)';
    'RSVD112':
      PIN_NUMBER='(0,0,0,0,CK67,0,0,0,0,0,0,0,0,0,0,0,0,0,0,0,0,0,0,0,0,0,0,0,0,0,0,0,0,0,0,0,0,0,0,0,0,0)';
      BIDIRECTIONAL='TRUE';
      INPUT_LOAD='(-0.01,0.01)';
      OUTPUT_LOAD='(1.0,-1.0)';
    'RSVD133':
      PIN_NUMBER='(0,0,0,0,CR25,0,0,0,0,0,0,0,0,0,0,0,0,0,0,0,0,0,0,0,0,0,0,0,0,0,0,0,0,0,0,0,0,0,0,0,0,0)';
      BIDIRECTIONAL='TRUE';
      INPUT_LOAD='(-0.01,0.01)';
      OUTPUT_LOAD='(1.0,-1.0)';
    'RSVD138':
      PIN_NUMBER='(0,0,0,0,CT26,0,0,0,0,0,0,0,0,0,0,0,0,0,0,0,0,0,0,0,0,0,0,0,0,0,0,0,0,0,0,0,0,0,0,0,0,0)';
      BIDIRECTIONAL='TRUE';
      INPUT_LOAD='(-0.01,0.01)';
      OUTPUT_LOAD='(1.0,-1.0)';
    'RSVD147':
      PIN_NUMBER='(0,0,0,0,CW41,0,0,0,0,0,0,0,0,0,0,0,0,0,0,0,0,0,0,0,0,0,0,0,0,0,0,0,0,0,0,0,0,0,0,0,0,0)';
      BIDIRECTIONAL='TRUE';
      INPUT_LOAD='(-0.01,0.01)';
      OUTPUT_LOAD='(1.0,-1.0)';
    'RSVD149':
      PIN_NUMBER='(0,0,0,0,CW58,0,0,0,0,0,0,0,0,0,0,0,0,0,0,0,0,0,0,0,0,0,0,0,0,0,0,0,0,0,0,0,0,0,0,0,0,0)';
      BIDIRECTIONAL='TRUE';
      INPUT_LOAD='(-0.01,0.01)';
      OUTPUT_LOAD='(1.0,-1.0)';
    'RSVD154':
      PIN_NUMBER='(0,0,0,0,CY57,0,0,0,0,0,0,0,0,0,0,0,0,0,0,0,0,0,0,0,0,0,0,0,0,0,0,0,0,0,0,0,0,0,0,0,0,0)';
      BIDIRECTIONAL='TRUE';
      INPUT_LOAD='(-0.01,0.01)';
      OUTPUT_LOAD='(1.0,-1.0)';
    'RSVD160':
      PIN_NUMBER='(0,0,0,0,EG17,0,0,0,0,0,0,0,0,0,0,0,0,0,0,0,0,0,0,0,0,0,0,0,0,0,0,0,0,0,0,0,0,0,0,0,0,0)';
      BIDIRECTIONAL='TRUE';
      INPUT_LOAD='(-0.01,0.01)';
      OUTPUT_LOAD='(1.0,-1.0)';
    'RSVD164':
      PIN_NUMBER='(0,0,0,0,U17,0,0,0,0,0,0,0,0,0,0,0,0,0,0,0,0,0,0,0,0,0,0,0,0,0,0,0,0,0,0,0,0,0,0,0,0,0)';
      BIDIRECTIONAL='TRUE';
      INPUT_LOAD='(-0.01,0.01)';
      OUTPUT_LOAD='(1.0,-1.0)';
    'RSVD165':
      PIN_NUMBER='(0,0,0,0,W17,0,0,0,0,0,0,0,0,0,0,0,0,0,0,0,0,0,0,0,0,0,0,0,0,0,0,0,0,0,0,0,0,0,0,0,0,0)';
      BIDIRECTIONAL='TRUE';
      INPUT_LOAD='(-0.01,0.01)';
      OUTPUT_LOAD='(1.0,-1.0)';
    'RSVD21':
      PIN_NUMBER='(0,0,0,0,AV65,0,0,0,0,0,0,0,0,0,0,0,0,0,0,0,0,0,0,0,0,0,0,0,0,0,0,0,0,0,0,0,0,0,0,0,0,0)';
      BIDIRECTIONAL='TRUE';
      INPUT_LOAD='(-0.01,0.01)';
      OUTPUT_LOAD='(1.0,-1.0)';
    'RSVD26':
      PIN_NUMBER='(0,0,0,0,AY24,0,0,0,0,0,0,0,0,0,0,0,0,0,0,0,0,0,0,0,0,0,0,0,0,0,0,0,0,0,0,0,0,0,0,0,0,0)';
      BIDIRECTIONAL='TRUE';
      INPUT_LOAD='(-0.01,0.01)';
      OUTPUT_LOAD='(1.0,-1.0)';
    'RSVD31':
      PIN_NUMBER='(0,0,0,0,BA25,0,0,0,0,0,0,0,0,0,0,0,0,0,0,0,0,0,0,0,0,0,0,0,0,0,0,0,0,0,0,0,0,0,0,0,0,0)';
      BIDIRECTIONAL='TRUE';
      INPUT_LOAD='(-0.01,0.01)';
      OUTPUT_LOAD='(1.0,-1.0)';
    'RSVD43':
      PIN_NUMBER='(0,0,0,0,BD71,0,0,0,0,0,0,0,0,0,0,0,0,0,0,0,0,0,0,0,0,0,0,0,0,0,0,0,0,0,0,0,0,0,0,0,0,0)';
      BIDIRECTIONAL='TRUE';
      INPUT_LOAD='(-0.01,0.01)';
      OUTPUT_LOAD='(1.0,-1.0)';
    'RSVD45':
      PIN_NUMBER='(0,0,0,0,BE21,0,0,0,0,0,0,0,0,0,0,0,0,0,0,0,0,0,0,0,0,0,0,0,0,0,0,0,0,0,0,0,0,0,0,0,0,0)';
      BIDIRECTIONAL='TRUE';
      INPUT_LOAD='(-0.01,0.01)';
      OUTPUT_LOAD='(1.0,-1.0)';
    'RSVD51':
      PIN_NUMBER='(0,0,0,0,BF71,0,0,0,0,0,0,0,0,0,0,0,0,0,0,0,0,0,0,0,0,0,0,0,0,0,0,0,0,0,0,0,0,0,0,0,0,0)';
      BIDIRECTIONAL='TRUE';
      INPUT_LOAD='(-0.01,0.01)';
      OUTPUT_LOAD='(1.0,-1.0)';
    'RSVD54':
      PIN_NUMBER='(0,0,0,0,BG78,0,0,0,0,0,0,0,0,0,0,0,0,0,0,0,0,0,0,0,0,0,0,0,0,0,0,0,0,0,0,0,0,0,0,0,0,0)';
      BIDIRECTIONAL='TRUE';
      INPUT_LOAD='(-0.01,0.01)';
      OUTPUT_LOAD='(1.0,-1.0)';
    'RSVD57':
      PIN_NUMBER='(0,0,0,0,BJ21,0,0,0,0,0,0,0,0,0,0,0,0,0,0,0,0,0,0,0,0,0,0,0,0,0,0,0,0,0,0,0,0,0,0,0,0,0)';
      BIDIRECTIONAL='TRUE';
      INPUT_LOAD='(-0.01,0.01)';
      OUTPUT_LOAD='(1.0,-1.0)';
    'RSVD60':
      PIN_NUMBER='(0,0,0,0,BK22,0,0,0,0,0,0,0,0,0,0,0,0,0,0,0,0,0,0,0,0,0,0,0,0,0,0,0,0,0,0,0,0,0,0,0,0,0)';
      BIDIRECTIONAL='TRUE';
      INPUT_LOAD='(-0.01,0.01)';
      OUTPUT_LOAD='(1.0,-1.0)';
    'RSVD63':
      PIN_NUMBER='(0,0,0,0,BL60,0,0,0,0,0,0,0,0,0,0,0,0,0,0,0,0,0,0,0,0,0,0,0,0,0,0,0,0,0,0,0,0,0,0,0,0,0)';
      BIDIRECTIONAL='TRUE';
      INPUT_LOAD='(-0.01,0.01)';
      OUTPUT_LOAD='(1.0,-1.0)';
    'RSVD65':
      PIN_NUMBER='(0,0,0,0,BM65,0,0,0,0,0,0,0,0,0,0,0,0,0,0,0,0,0,0,0,0,0,0,0,0,0,0,0,0,0,0,0,0,0,0,0,0,0)';
      BIDIRECTIONAL='TRUE';
      INPUT_LOAD='(-0.01,0.01)';
      OUTPUT_LOAD='(1.0,-1.0)';
    'RSVD67':
      PIN_NUMBER='(0,0,0,0,BP22,0,0,0,0,0,0,0,0,0,0,0,0,0,0,0,0,0,0,0,0,0,0,0,0,0,0,0,0,0,0,0,0,0,0,0,0,0)';
      BIDIRECTIONAL='TRUE';
      INPUT_LOAD='(-0.01,0.01)';
      OUTPUT_LOAD='(1.0,-1.0)';
    'RSVD68':
      PIN_NUMBER='(0,0,0,0,BP65,0,0,0,0,0,0,0,0,0,0,0,0,0,0,0,0,0,0,0,0,0,0,0,0,0,0,0,0,0,0,0,0,0,0,0,0,0)';
      BIDIRECTIONAL='TRUE';
      INPUT_LOAD='(-0.01,0.01)';
      OUTPUT_LOAD='(1.0,-1.0)';
    'RSVD71':
      PIN_NUMBER='(0,0,0,0,BR21,0,0,0,0,0,0,0,0,0,0,0,0,0,0,0,0,0,0,0,0,0,0,0,0,0,0,0,0,0,0,0,0,0,0,0,0,0)';
      BIDIRECTIONAL='TRUE';
      INPUT_LOAD='(-0.01,0.01)';
      OUTPUT_LOAD='(1.0,-1.0)';
    'RSVD82':
      PIN_NUMBER='(0,0,0,0,CC66,0,0,0,0,0,0,0,0,0,0,0,0,0,0,0,0,0,0,0,0,0,0,0,0,0,0,0,0,0,0,0,0,0,0,0,0,0)';
      BIDIRECTIONAL='TRUE';
      INPUT_LOAD='(-0.01,0.01)';
      OUTPUT_LOAD='(1.0,-1.0)';
    'RSVD83':
      PIN_NUMBER='(0,0,0,0,CD22,0,0,0,0,0,0,0,0,0,0,0,0,0,0,0,0,0,0,0,0,0,0,0,0,0,0,0,0,0,0,0,0,0,0,0,0,0)';
      BIDIRECTIONAL='TRUE';
      INPUT_LOAD='(-0.01,0.01)';
      OUTPUT_LOAD='(1.0,-1.0)';
    'RSVD84':
      PIN_NUMBER='(0,0,0,0,CD26,0,0,0,0,0,0,0,0,0,0,0,0,0,0,0,0,0,0,0,0,0,0,0,0,0,0,0,0,0,0,0,0,0,0,0,0,0)';
      BIDIRECTIONAL='TRUE';
      INPUT_LOAD='(-0.01,0.01)';
      OUTPUT_LOAD='(1.0,-1.0)';
    'RSVD85':
      PIN_NUMBER='(0,0,0,0,CD30,0,0,0,0,0,0,0,0,0,0,0,0,0,0,0,0,0,0,0,0,0,0,0,0,0,0,0,0,0,0,0,0,0,0,0,0,0)';
      BIDIRECTIONAL='TRUE';
      INPUT_LOAD='(-0.01,0.01)';
      OUTPUT_LOAD='(1.0,-1.0)';
    'RSVD92':
      PIN_NUMBER='(0,0,0,0,CF22,0,0,0,0,0,0,0,0,0,0,0,0,0,0,0,0,0,0,0,0,0,0,0,0,0,0,0,0,0,0,0,0,0,0,0,0,0)';
      BIDIRECTIONAL='TRUE';
      INPUT_LOAD='(-0.01,0.01)';
      OUTPUT_LOAD='(1.0,-1.0)';
    'RSVD99':
      PIN_NUMBER='(0,0,0,0,CH69,0,0,0,0,0,0,0,0,0,0,0,0,0,0,0,0,0,0,0,0,0,0,0,0,0,0,0,0,0,0,0,0,0,0,0,0,0)';
      BIDIRECTIONAL='TRUE';
      INPUT_LOAD='(-0.01,0.01)';
      OUTPUT_LOAD='(1.0,-1.0)';
    'RSVD119':
      PIN_NUMBER='(0,0,0,0,0,CL70,0,0,0,0,0,0,0,0,0,0,0,0,0,0,0,0,0,0,0,0,0,0,0,0,0,0,0,0,0,0,0,0,0,0,0,0)';
      BIDIRECTIONAL='TRUE';
      INPUT_LOAD='(-0.01,0.01)';
      OUTPUT_LOAD='(1.0,-1.0)';
    'RSVD115':
      PIN_NUMBER='(0,0,0,0,0,CL60,0,0,0,0,0,0,0,0,0,0,0,0,0,0,0,0,0,0,0,0,0,0,0,0,0,0,0,0,0,0,0,0,0,0,0,0)';
      BIDIRECTIONAL='TRUE';
      INPUT_LOAD='(-0.01,0.01)';
      OUTPUT_LOAD='(1.0,-1.0)';
    'RSVD148':
      PIN_NUMBER='(0,0,0,0,0,CW43,0,0,0,0,0,0,0,0,0,0,0,0,0,0,0,0,0,0,0,0,0,0,0,0,0,0,0,0,0,0,0,0,0,0,0,0)';
      BIDIRECTIONAL='TRUE';
      INPUT_LOAD='(-0.01,0.01)';
      OUTPUT_LOAD='(1.0,-1.0)';
    'RSVD159':
      PIN_NUMBER='(0,0,0,0,0,DA70,0,0,0,0,0,0,0,0,0,0,0,0,0,0,0,0,0,0,0,0,0,0,0,0,0,0,0,0,0,0,0,0,0,0,0,0)';
      BIDIRECTIONAL='TRUE';
      INPUT_LOAD='(-0.01,0.01)';
      OUTPUT_LOAD='(1.0,-1.0)';
    'RSVD44':
      PIN_NUMBER='(0,0,0,0,0,BD77,0,0,0,0,0,0,0,0,0,0,0,0,0,0,0,0,0,0,0,0,0,0,0,0,0,0,0,0,0,0,0,0,0,0,0,0)';
      BIDIRECTIONAL='TRUE';
      INPUT_LOAD='(-0.01,0.01)';
      OUTPUT_LOAD='(1.0,-1.0)';
    'RSVD97':
      PIN_NUMBER='(0,0,0,0,0,CH61,0,0,0,0,0,0,0,0,0,0,0,0,0,0,0,0,0,0,0,0,0,0,0,0,0,0,0,0,0,0,0,0,0,0,0,0)';
      BIDIRECTIONAL='TRUE';
      INPUT_LOAD='(-0.01,0.01)';
      OUTPUT_LOAD='(1.0,-1.0)';
    'RSVD8':
      PIN_NUMBER='(0,0,0,0,0,AU52,0,0,0,0,0,0,0,0,0,0,0,0,0,0,0,0,0,0,0,0,0,0,0,0,0,0,0,0,0,0,0,0,0,0,0,0)';
      BIDIRECTIONAL='TRUE';
      INPUT_LOAD='(-0.01,0.01)';
      OUTPUT_LOAD='(1.0,-1.0)';
    'RSVD87':
      PIN_NUMBER='(0,0,0,0,0,CD69,0,0,0,0,0,0,0,0,0,0,0,0,0,0,0,0,0,0,0,0,0,0,0,0,0,0,0,0,0,0,0,0,0,0,0,0)';
      BIDIRECTIONAL='TRUE';
      INPUT_LOAD='(-0.01,0.01)';
      OUTPUT_LOAD='(1.0,-1.0)';
    'RSVD111':
      PIN_NUMBER='(0,0,0,0,0,CK61,0,0,0,0,0,0,0,0,0,0,0,0,0,0,0,0,0,0,0,0,0,0,0,0,0,0,0,0,0,0,0,0,0,0,0,0)';
      BIDIRECTIONAL='TRUE';
      INPUT_LOAD='(-0.01,0.01)';
      OUTPUT_LOAD='(1.0,-1.0)';
    'RSVD95':
      PIN_NUMBER='(0,0,0,0,0,CG60,0,0,0,0,0,0,0,0,0,0,0,0,0,0,0,0,0,0,0,0,0,0,0,0,0,0,0,0,0,0,0,0,0,0,0,0)';
      BIDIRECTIONAL='TRUE';
      INPUT_LOAD='(-0.01,0.01)';
      OUTPUT_LOAD='(1.0,-1.0)';
    'RSVD163':
      PIN_NUMBER='(0,0,0,0,0,J13,0,0,0,0,0,0,0,0,0,0,0,0,0,0,0,0,0,0,0,0,0,0,0,0,0,0,0,0,0,0,0,0,0,0,0,0)';
      BIDIRECTIONAL='TRUE';
      INPUT_LOAD='(-0.01,0.01)';
      OUTPUT_LOAD='(1.0,-1.0)';
    'PTI_DIE0015':
      PIN_NUMBER='(0,0,0,0,0,0,BP30,0,0,0,0,0,0,0,0,0,0,0,0,0,0,0,0,0,0,0,0,0,0,0,0,0,0,0,0,0,0,0,0,0,0,0)';
      OUTPUT_LOAD='(1.0,-1.0)';
    'PTI_DIE0014':
      PIN_NUMBER='(0,0,0,0,0,0,BN29,0,0,0,0,0,0,0,0,0,0,0,0,0,0,0,0,0,0,0,0,0,0,0,0,0,0,0,0,0,0,0,0,0,0,0)';
      OUTPUT_LOAD='(1.0,-1.0)';
    'PTI_DIE0013':
      PIN_NUMBER='(0,0,0,0,0,0,BP28,0,0,0,0,0,0,0,0,0,0,0,0,0,0,0,0,0,0,0,0,0,0,0,0,0,0,0,0,0,0,0,0,0,0,0)';
      OUTPUT_LOAD='(1.0,-1.0)';
    'PTI_DIE0012':
      PIN_NUMBER='(0,0,0,0,0,0,BN27,0,0,0,0,0,0,0,0,0,0,0,0,0,0,0,0,0,0,0,0,0,0,0,0,0,0,0,0,0,0,0,0,0,0,0)';
      OUTPUT_LOAD='(1.0,-1.0)';
    'PTI_DIE0011':
      PIN_NUMBER='(0,0,0,0,0,0,BT30,0,0,0,0,0,0,0,0,0,0,0,0,0,0,0,0,0,0,0,0,0,0,0,0,0,0,0,0,0,0,0,0,0,0,0)';
      OUTPUT_LOAD='(1.0,-1.0)';
    'PTI_DIE0010':
      PIN_NUMBER='(0,0,0,0,0,0,BU29,0,0,0,0,0,0,0,0,0,0,0,0,0,0,0,0,0,0,0,0,0,0,0,0,0,0,0,0,0,0,0,0,0,0,0)';
      OUTPUT_LOAD='(1.0,-1.0)';
    'PTI_DIE009':
      PIN_NUMBER='(0,0,0,0,0,0,BT28,0,0,0,0,0,0,0,0,0,0,0,0,0,0,0,0,0,0,0,0,0,0,0,0,0,0,0,0,0,0,0,0,0,0,0)';
      OUTPUT_LOAD='(1.0,-1.0)';
    'PTI_DIE008':
      PIN_NUMBER='(0,0,0,0,0,0,BU27,0,0,0,0,0,0,0,0,0,0,0,0,0,0,0,0,0,0,0,0,0,0,0,0,0,0,0,0,0,0,0,0,0,0,0)';
      OUTPUT_LOAD='(1.0,-1.0)';
    'PTI_DIE007':
      PIN_NUMBER='(0,0,0,0,0,0,BV28,0,0,0,0,0,0,0,0,0,0,0,0,0,0,0,0,0,0,0,0,0,0,0,0,0,0,0,0,0,0,0,0,0,0,0)';
      OUTPUT_LOAD='(1.0,-1.0)';
    'PTI_DIE006':
      PIN_NUMBER='(0,0,0,0,0,0,CA27,0,0,0,0,0,0,0,0,0,0,0,0,0,0,0,0,0,0,0,0,0,0,0,0,0,0,0,0,0,0,0,0,0,0,0)';
      OUTPUT_LOAD='(1.0,-1.0)';
    'PTI_DIE005':
      PIN_NUMBER='(0,0,0,0,0,0,BV30,0,0,0,0,0,0,0,0,0,0,0,0,0,0,0,0,0,0,0,0,0,0,0,0,0,0,0,0,0,0,0,0,0,0,0)';
      OUTPUT_LOAD='(1.0,-1.0)';
    'PTI_DIE004':
      PIN_NUMBER='(0,0,0,0,0,0,CA29,0,0,0,0,0,0,0,0,0,0,0,0,0,0,0,0,0,0,0,0,0,0,0,0,0,0,0,0,0,0,0,0,0,0,0)';
      OUTPUT_LOAD='(1.0,-1.0)';
    'PTI_DIE003':
      PIN_NUMBER='(0,0,0,0,0,0,BY30,0,0,0,0,0,0,0,0,0,0,0,0,0,0,0,0,0,0,0,0,0,0,0,0,0,0,0,0,0,0,0,0,0,0,0)';
      OUTPUT_LOAD='(1.0,-1.0)';
    'PTI_DIE002':
      PIN_NUMBER='(0,0,0,0,0,0,CC27,0,0,0,0,0,0,0,0,0,0,0,0,0,0,0,0,0,0,0,0,0,0,0,0,0,0,0,0,0,0,0,0,0,0,0)';
      OUTPUT_LOAD='(1.0,-1.0)';
    'PTI_DIE001':
      PIN_NUMBER='(0,0,0,0,0,0,CD28,0,0,0,0,0,0,0,0,0,0,0,0,0,0,0,0,0,0,0,0,0,0,0,0,0,0,0,0,0,0,0,0,0,0,0)';
      OUTPUT_LOAD='(1.0,-1.0)';
    'PTI_DIE000':
      PIN_NUMBER='(0,0,0,0,0,0,CC29,0,0,0,0,0,0,0,0,0,0,0,0,0,0,0,0,0,0,0,0,0,0,0,0,0,0,0,0,0,0,0,0,0,0,0)';
      OUTPUT_LOAD='(1.0,-1.0)';
    'PTI_DIE00_STB_0':
      PIN_NUMBER='(0,0,0,0,0,0,CB30,0,0,0,0,0,0,0,0,0,0,0,0,0,0,0,0,0,0,0,0,0,0,0,0,0,0,0,0,0,0,0,0,0,0,0)';
      OUTPUT_LOAD='(1.0,-1.0)';
    'PTI_DIE00_STB_1':
      PIN_NUMBER='(0,0,0,0,0,0,BY28,0,0,0,0,0,0,0,0,0,0,0,0,0,0,0,0,0,0,0,0,0,0,0,0,0,0,0,0,0,0,0,0,0,0,0)';
      OUTPUT_LOAD='(1.0,-1.0)';
    'PTI_DIE0115':
      PIN_NUMBER='(0,0,0,0,0,0,BN66,0,0,0,0,0,0,0,0,0,0,0,0,0,0,0,0,0,0,0,0,0,0,0,0,0,0,0,0,0,0,0,0,0,0,0)';
      OUTPUT_LOAD='(1.0,-1.0)';
    'PTI_DIE0114':
      PIN_NUMBER='(0,0,0,0,0,0,BM67,0,0,0,0,0,0,0,0,0,0,0,0,0,0,0,0,0,0,0,0,0,0,0,0,0,0,0,0,0,0,0,0,0,0,0)';
      OUTPUT_LOAD='(1.0,-1.0)';
    'PTI_DIE0113':
      PIN_NUMBER='(0,0,0,0,0,0,BL66,0,0,0,0,0,0,0,0,0,0,0,0,0,0,0,0,0,0,0,0,0,0,0,0,0,0,0,0,0,0,0,0,0,0,0)';
      OUTPUT_LOAD='(1.0,-1.0)';
    'PTI_DIE0112':
      PIN_NUMBER='(0,0,0,0,0,0,BJ66,0,0,0,0,0,0,0,0,0,0,0,0,0,0,0,0,0,0,0,0,0,0,0,0,0,0,0,0,0,0,0,0,0,0,0)';
      OUTPUT_LOAD='(1.0,-1.0)';
    'PTI_DIE0111':
      PIN_NUMBER='(0,0,0,0,0,0,BG66,0,0,0,0,0,0,0,0,0,0,0,0,0,0,0,0,0,0,0,0,0,0,0,0,0,0,0,0,0,0,0,0,0,0,0)';
      OUTPUT_LOAD='(1.0,-1.0)';
    'PTI_DIE0110':
      PIN_NUMBER='(0,0,0,0,0,0,BN68,0,0,0,0,0,0,0,0,0,0,0,0,0,0,0,0,0,0,0,0,0,0,0,0,0,0,0,0,0,0,0,0,0,0,0)';
      OUTPUT_LOAD='(1.0,-1.0)';
    'PTI_DIE019':
      PIN_NUMBER='(0,0,0,0,0,0,BM69,0,0,0,0,0,0,0,0,0,0,0,0,0,0,0,0,0,0,0,0,0,0,0,0,0,0,0,0,0,0,0,0,0,0,0)';
      OUTPUT_LOAD='(1.0,-1.0)';
    'PTI_DIE018':
      PIN_NUMBER='(0,0,0,0,0,0,BK69,0,0,0,0,0,0,0,0,0,0,0,0,0,0,0,0,0,0,0,0,0,0,0,0,0,0,0,0,0,0,0,0,0,0,0)';
      OUTPUT_LOAD='(1.0,-1.0)';
    'PTI_DIE017':
      PIN_NUMBER='(0,0,0,0,0,0,BD67,0,0,0,0,0,0,0,0,0,0,0,0,0,0,0,0,0,0,0,0,0,0,0,0,0,0,0,0,0,0,0,0,0,0,0)';
      OUTPUT_LOAD='(1.0,-1.0)';
    'PTI_DIE016':
      PIN_NUMBER='(0,0,0,0,0,0,BG68,0,0,0,0,0,0,0,0,0,0,0,0,0,0,0,0,0,0,0,0,0,0,0,0,0,0,0,0,0,0,0,0,0,0,0)';
      OUTPUT_LOAD='(1.0,-1.0)';
    'PTI_DIE015':
      PIN_NUMBER='(0,0,0,0,0,0,BC68,0,0,0,0,0,0,0,0,0,0,0,0,0,0,0,0,0,0,0,0,0,0,0,0,0,0,0,0,0,0,0,0,0,0,0)';
      OUTPUT_LOAD='(1.0,-1.0)';
    'PTI_DIE014':
      PIN_NUMBER='(0,0,0,0,0,0,BH69,0,0,0,0,0,0,0,0,0,0,0,0,0,0,0,0,0,0,0,0,0,0,0,0,0,0,0,0,0,0,0,0,0,0,0)';
      OUTPUT_LOAD='(1.0,-1.0)';
    'PTI_DIE013':
      PIN_NUMBER='(0,0,0,0,0,0,BF69,0,0,0,0,0,0,0,0,0,0,0,0,0,0,0,0,0,0,0,0,0,0,0,0,0,0,0,0,0,0,0,0,0,0,0)';
      OUTPUT_LOAD='(1.0,-1.0)';
    'PTI_DIE012':
      PIN_NUMBER='(0,0,0,0,0,0,BD69,0,0,0,0,0,0,0,0,0,0,0,0,0,0,0,0,0,0,0,0,0,0,0,0,0,0,0,0,0,0,0,0,0,0,0)';
      OUTPUT_LOAD='(1.0,-1.0)';
    'PTI_DIE011':
      PIN_NUMBER='(0,0,0,0,0,0,BE70,0,0,0,0,0,0,0,0,0,0,0,0,0,0,0,0,0,0,0,0,0,0,0,0,0,0,0,0,0,0,0,0,0,0,0)';
      OUTPUT_LOAD='(1.0,-1.0)';
    'PTI_DIE010':
      PIN_NUMBER='(0,0,0,0,0,0,BC70,0,0,0,0,0,0,0,0,0,0,0,0,0,0,0,0,0,0,0,0,0,0,0,0,0,0,0,0,0,0,0,0,0,0,0)';
      OUTPUT_LOAD='(1.0,-1.0)';
    'PTI_DIE01_STB_0':
      PIN_NUMBER='(0,0,0,0,0,0,BF67,0,0,0,0,0,0,0,0,0,0,0,0,0,0,0,0,0,0,0,0,0,0,0,0,0,0,0,0,0,0,0,0,0,0,0)';
      OUTPUT_LOAD='(1.0,-1.0)';
    'PTI_DIE01_STB_1':
      PIN_NUMBER='(0,0,0,0,0,0,BK67,0,0,0,0,0,0,0,0,0,0,0,0,0,0,0,0,0,0,0,0,0,0,0,0,0,0,0,0,0,0,0,0,0,0,0)';
      OUTPUT_LOAD='(1.0,-1.0)';
    'RSVD118':
      PIN_NUMBER='(0,0,0,0,0,0,CL68,0,0,0,0,0,0,0,0,0,0,0,0,0,0,0,0,0,0,0,0,0,0,0,0,0,0,0,0,0,0,0,0,0,0,0)';
      BIDIRECTIONAL='TRUE';
      INPUT_LOAD='(-0.01,0.01)';
      OUTPUT_LOAD='(1.0,-1.0)';
    'RSVD122':
      PIN_NUMBER='(0,0,0,0,0,0,CM69,0,0,0,0,0,0,0,0,0,0,0,0,0,0,0,0,0,0,0,0,0,0,0,0,0,0,0,0,0,0,0,0,0,0,0)';
      BIDIRECTIONAL='TRUE';
      INPUT_LOAD='(-0.01,0.01)';
      OUTPUT_LOAD='(1.0,-1.0)';
    'RSVD130':
      PIN_NUMBER='(0,0,0,0,0,0,CP69,0,0,0,0,0,0,0,0,0,0,0,0,0,0,0,0,0,0,0,0,0,0,0,0,0,0,0,0,0,0,0,0,0,0,0)';
      BIDIRECTIONAL='TRUE';
      INPUT_LOAD='(-0.01,0.01)';
      OUTPUT_LOAD='(1.0,-1.0)';
    'RSVD135':
      PIN_NUMBER='(0,0,0,0,0,0,CR68,0,0,0,0,0,0,0,0,0,0,0,0,0,0,0,0,0,0,0,0,0,0,0,0,0,0,0,0,0,0,0,0,0,0,0)';
      BIDIRECTIONAL='TRUE';
      INPUT_LOAD='(-0.01,0.01)';
      OUTPUT_LOAD='(1.0,-1.0)';
    'RSVD13':
      PIN_NUMBER='(0,0,0,0,0,0,AU66,0,0,0,0,0,0,0,0,0,0,0,0,0,0,0,0,0,0,0,0,0,0,0,0,0,0,0,0,0,0,0,0,0,0,0)';
      BIDIRECTIONAL='TRUE';
      INPUT_LOAD='(-0.01,0.01)';
      OUTPUT_LOAD='(1.0,-1.0)';
    'RSVD14':
      PIN_NUMBER='(0,0,0,0,0,0,AU68,0,0,0,0,0,0,0,0,0,0,0,0,0,0,0,0,0,0,0,0,0,0,0,0,0,0,0,0,0,0,0,0,0,0,0)';
      BIDIRECTIONAL='TRUE';
      INPUT_LOAD='(-0.01,0.01)';
      OUTPUT_LOAD='(1.0,-1.0)';
    'RSVD2':
      PIN_NUMBER='(0,0,0,0,0,0,AN17,0,0,0,0,0,0,0,0,0,0,0,0,0,0,0,0,0,0,0,0,0,0,0,0,0,0,0,0,0,0,0,0,0,0,0)';
      BIDIRECTIONAL='TRUE';
      INPUT_LOAD='(-0.01,0.01)';
      OUTPUT_LOAD='(1.0,-1.0)';
    'RSVD22':
      PIN_NUMBER='(0,0,0,0,0,0,AV67,0,0,0,0,0,0,0,0,0,0,0,0,0,0,0,0,0,0,0,0,0,0,0,0,0,0,0,0,0,0,0,0,0,0,0)';
      BIDIRECTIONAL='TRUE';
      INPUT_LOAD='(-0.01,0.01)';
      OUTPUT_LOAD='(1.0,-1.0)';
    'RSVD3':
      PIN_NUMBER='(0,0,0,0,0,0,AR17,0,0,0,0,0,0,0,0,0,0,0,0,0,0,0,0,0,0,0,0,0,0,0,0,0,0,0,0,0,0,0,0,0,0,0)';
      BIDIRECTIONAL='TRUE';
      INPUT_LOAD='(-0.01,0.01)';
      OUTPUT_LOAD='(1.0,-1.0)';
    'RSVD5':
      PIN_NUMBER='(0,0,0,0,0,0,AT67,0,0,0,0,0,0,0,0,0,0,0,0,0,0,0,0,0,0,0,0,0,0,0,0,0,0,0,0,0,0,0,0,0,0,0)';
      BIDIRECTIONAL='TRUE';
      INPUT_LOAD='(-0.01,0.01)';
      OUTPUT_LOAD='(1.0,-1.0)';
    'RSVD62':
      PIN_NUMBER='(0,0,0,0,0,0,BL21,0,0,0,0,0,0,0,0,0,0,0,0,0,0,0,0,0,0,0,0,0,0,0,0,0,0,0,0,0,0,0,0,0,0,0)';
      BIDIRECTIONAL='TRUE';
      INPUT_LOAD='(-0.01,0.01)';
      OUTPUT_LOAD='(1.0,-1.0)';
    'RSVD66':
      PIN_NUMBER='(0,0,0,0,0,0,BN21,0,0,0,0,0,0,0,0,0,0,0,0,0,0,0,0,0,0,0,0,0,0,0,0,0,0,0,0,0,0,0,0,0,0,0)';
      BIDIRECTIONAL='TRUE';
      INPUT_LOAD='(-0.01,0.01)';
      OUTPUT_LOAD='(1.0,-1.0)';
    'RSVD73':
      PIN_NUMBER='(0,0,0,0,0,0,BV22,0,0,0,0,0,0,0,0,0,0,0,0,0,0,0,0,0,0,0,0,0,0,0,0,0,0,0,0,0,0,0,0,0,0,0)';
      BIDIRECTIONAL='TRUE';
      INPUT_LOAD='(-0.01,0.01)';
      OUTPUT_LOAD='(1.0,-1.0)';
    'RSVD74':
      PIN_NUMBER='(0,0,0,0,0,0,BW21,0,0,0,0,0,0,0,0,0,0,0,0,0,0,0,0,0,0,0,0,0,0,0,0,0,0,0,0,0,0,0,0,0,0,0)';
      BIDIRECTIONAL='TRUE';
      INPUT_LOAD='(-0.01,0.01)';
      OUTPUT_LOAD='(1.0,-1.0)';
    'RSVD75':
      PIN_NUMBER='(0,0,0,0,0,0,BW23,0,0,0,0,0,0,0,0,0,0,0,0,0,0,0,0,0,0,0,0,0,0,0,0,0,0,0,0,0,0,0,0,0,0,0)';
      BIDIRECTIONAL='TRUE';
      INPUT_LOAD='(-0.01,0.01)';
      OUTPUT_LOAD='(1.0,-1.0)';
    'RSVD77':
      PIN_NUMBER='(0,0,0,0,0,0,CA21,0,0,0,0,0,0,0,0,0,0,0,0,0,0,0,0,0,0,0,0,0,0,0,0,0,0,0,0,0,0,0,0,0,0,0)';
      BIDIRECTIONAL='TRUE';
      INPUT_LOAD='(-0.01,0.01)';
      OUTPUT_LOAD='(1.0,-1.0)';
    'RSVD78':
      PIN_NUMBER='(0,0,0,0,0,0,CA23,0,0,0,0,0,0,0,0,0,0,0,0,0,0,0,0,0,0,0,0,0,0,0,0,0,0,0,0,0,0,0,0,0,0,0)';
      BIDIRECTIONAL='TRUE';
      INPUT_LOAD='(-0.01,0.01)';
      OUTPUT_LOAD='(1.0,-1.0)';
    'RSVD79':
      PIN_NUMBER='(0,0,0,0,0,0,CC21,0,0,0,0,0,0,0,0,0,0,0,0,0,0,0,0,0,0,0,0,0,0,0,0,0,0,0,0,0,0,0,0,0,0,0)';
      BIDIRECTIONAL='TRUE';
      INPUT_LOAD='(-0.01,0.01)';
      OUTPUT_LOAD='(1.0,-1.0)';
    'RSVD80':
      PIN_NUMBER='(0,0,0,0,0,0,CC23,0,0,0,0,0,0,0,0,0,0,0,0,0,0,0,0,0,0,0,0,0,0,0,0,0,0,0,0,0,0,0,0,0,0,0)';
      BIDIRECTIONAL='TRUE';
      INPUT_LOAD='(-0.01,0.01)';
      OUTPUT_LOAD='(1.0,-1.0)';
    'RSVD89':
      PIN_NUMBER='(0,0,0,0,0,0,CE21,0,0,0,0,0,0,0,0,0,0,0,0,0,0,0,0,0,0,0,0,0,0,0,0,0,0,0,0,0,0,0,0,0,0,0)';
      BIDIRECTIONAL='TRUE';
      INPUT_LOAD='(-0.01,0.01)';
      OUTPUT_LOAD='(1.0,-1.0)';
    'UPI0_AC_COUPLING':
      PIN_NUMBER='(0,0,0,0,0,0,BA23,0,0,0,0,0,0,0,0,0,0,0,0,0,0,0,0,0,0,0,0,0,0,0,0,0,0,0,0,0,0,0,0,0,0,0)';
      INPUT_LOAD='(-0.01,0.01)';
    'UPI1_AC_COUPLING':
      PIN_NUMBER='(0,0,0,0,0,0,CW19,0,0,0,0,0,0,0,0,0,0,0,0,0,0,0,0,0,0,0,0,0,0,0,0,0,0,0,0,0,0,0,0,0,0,0)';
      INPUT_LOAD='(-0.01,0.01)';
    'UPI2_AC_COUPLING':
      PIN_NUMBER='(0,0,0,0,0,0,BB65,0,0,0,0,0,0,0,0,0,0,0,0,0,0,0,0,0,0,0,0,0,0,0,0,0,0,0,0,0,0,0,0,0,0,0)';
      INPUT_LOAD='(-0.01,0.01)';
    'UPI3_AC_COUPLING':
      PIN_NUMBER='(0,0,0,0,0,0,CK71,0,0,0,0,0,0,0,0,0,0,0,0,0,0,0,0,0,0,0,0,0,0,0,0,0,0,0,0,0,0,0,0,0,0,0)';
      INPUT_LOAD='(-0.01,0.01)';
    '-DDR0_ALERT':
      PIN_NUMBER='(0,0,0,0,0,0,0,AT49,0,0,0,0,0,0,0,0,0,0,0,0,0,0,0,0,0,0,0,0,0,0,0,0,0,0,0,0,0,0,0,0,0,0)';
      INPUT_LOAD='(-0.01,0.01)';
    'DDR0_A_RSP1':
      PIN_NUMBER='(0,0,0,0,0,0,0,AU43,0,0,0,0,0,0,0,0,0,0,0,0,0,0,0,0,0,0,0,0,0,0,0,0,0,0,0,0,0,0,0,0,0,0)';
      INPUT_LOAD='(-0.01,0.01)';
    'DDR0_A_RSP0':
      PIN_NUMBER='(0,0,0,0,0,0,0,AT42,0,0,0,0,0,0,0,0,0,0,0,0,0,0,0,0,0,0,0,0,0,0,0,0,0,0,0,0,0,0,0,0,0,0)';
      INPUT_LOAD='(-0.01,0.01)';
    'DDR0_B_RSP1':
      PIN_NUMBER='(0,0,0,0,0,0,0,AV42,0,0,0,0,0,0,0,0,0,0,0,0,0,0,0,0,0,0,0,0,0,0,0,0,0,0,0,0,0,0,0,0,0,0)';
      INPUT_LOAD='(-0.01,0.01)';
    'DDR0_B_RSP0':
      PIN_NUMBER='(0,0,0,0,0,0,0,AV44,0,0,0,0,0,0,0,0,0,0,0,0,0,0,0,0,0,0,0,0,0,0,0,0,0,0,0,0,0,0,0,0,0,0)';
      INPUT_LOAD='(-0.01,0.01)';
    'DDR0_CLK_DN1':
      PIN_NUMBER='(0,0,0,0,0,0,0,G45,0,0,0,0,0,0,0,0,0,0,0,0,0,0,0,0,0,0,0,0,0,0,0,0,0,0,0,0,0,0,0,0,0,0)';
      OUTPUT_LOAD='(1.0,-1.0)';
    'DDR0_CLK_DN0':
      PIN_NUMBER='(0,0,0,0,0,0,0,B44,0,0,0,0,0,0,0,0,0,0,0,0,0,0,0,0,0,0,0,0,0,0,0,0,0,0,0,0,0,0,0,0,0,0)';
      OUTPUT_LOAD='(1.0,-1.0)';
    'DDR0_CLK_DP1':
      PIN_NUMBER='(0,0,0,0,0,0,0,E45,0,0,0,0,0,0,0,0,0,0,0,0,0,0,0,0,0,0,0,0,0,0,0,0,0,0,0,0,0,0,0,0,0,0)';
      OUTPUT_LOAD='(1.0,-1.0)';
    'DDR0_CLK_DP0':
      PIN_NUMBER='(0,0,0,0,0,0,0,C43,0,0,0,0,0,0,0,0,0,0,0,0,0,0,0,0,0,0,0,0,0,0,0,0,0,0,0,0,0,0,0,0,0,0)';
      OUTPUT_LOAD='(1.0,-1.0)';
    'DDR0_SA_CA6':
      PIN_NUMBER='(0,0,0,0,0,0,0,C48,0,0,0,0,0,0,0,0,0,0,0,0,0,0,0,0,0,0,0,0,0,0,0,0,0,0,0,0,0,0,0,0,0,0)';
      OUTPUT_LOAD='(1.0,-1.0)';
    'DDR0_SA_CA5':
      PIN_NUMBER='(0,0,0,0,0,0,0,E50,0,0,0,0,0,0,0,0,0,0,0,0,0,0,0,0,0,0,0,0,0,0,0,0,0,0,0,0,0,0,0,0,0,0)';
      OUTPUT_LOAD='(1.0,-1.0)';
    'DDR0_SA_CA4':
      PIN_NUMBER='(0,0,0,0,0,0,0,C50,0,0,0,0,0,0,0,0,0,0,0,0,0,0,0,0,0,0,0,0,0,0,0,0,0,0,0,0,0,0,0,0,0,0)';
      OUTPUT_LOAD='(1.0,-1.0)';
    'DDR0_SA_CA3':
      PIN_NUMBER='(0,0,0,0,0,0,0,F51,0,0,0,0,0,0,0,0,0,0,0,0,0,0,0,0,0,0,0,0,0,0,0,0,0,0,0,0,0,0,0,0,0,0)';
      OUTPUT_LOAD='(1.0,-1.0)';
    'DDR0_SA_CA2':
      PIN_NUMBER='(0,0,0,0,0,0,0,B51,0,0,0,0,0,0,0,0,0,0,0,0,0,0,0,0,0,0,0,0,0,0,0,0,0,0,0,0,0,0,0,0,0,0)';
      OUTPUT_LOAD='(1.0,-1.0)';
    'DDR0_SA_CA1':
      PIN_NUMBER='(0,0,0,0,0,0,0,G52,0,0,0,0,0,0,0,0,0,0,0,0,0,0,0,0,0,0,0,0,0,0,0,0,0,0,0,0,0,0,0,0,0,0)';
      OUTPUT_LOAD='(1.0,-1.0)';
    'DDR0_SA_CA0':
      PIN_NUMBER='(0,0,0,0,0,0,0,A52,0,0,0,0,0,0,0,0,0,0,0,0,0,0,0,0,0,0,0,0,0,0,0,0,0,0,0,0,0,0,0,0,0,0)';
      OUTPUT_LOAD='(1.0,-1.0)';
    'DDR0_SA_CS_N3':
      PIN_NUMBER='(0,0,0,0,0,0,0,F53,0,0,0,0,0,0,0,0,0,0,0,0,0,0,0,0,0,0,0,0,0,0,0,0,0,0,0,0,0,0,0,0,0,0)';
      OUTPUT_LOAD='(1.0,-1.0)';
    'DDR0_SA_CS_N2':
      PIN_NUMBER='(0,0,0,0,0,0,0,E54,0,0,0,0,0,0,0,0,0,0,0,0,0,0,0,0,0,0,0,0,0,0,0,0,0,0,0,0,0,0,0,0,0,0)';
      OUTPUT_LOAD='(1.0,-1.0)';
    'DDR0_SA_CS_N1':
      PIN_NUMBER='(0,0,0,0,0,0,0,B53,0,0,0,0,0,0,0,0,0,0,0,0,0,0,0,0,0,0,0,0,0,0,0,0,0,0,0,0,0,0,0,0,0,0)';
      OUTPUT_LOAD='(1.0,-1.0)';
    'DDR0_SA_CS_N0':
      PIN_NUMBER='(0,0,0,0,0,0,0,C54,0,0,0,0,0,0,0,0,0,0,0,0,0,0,0,0,0,0,0,0,0,0,0,0,0,0,0,0,0,0,0,0,0,0)';
      OUTPUT_LOAD='(1.0,-1.0)';
    'DDR0_SA_DQ31':
      PIN_NUMBER='(0,0,0,0,0,0,0,E62,0,0,0,0,0,0,0,0,0,0,0,0,0,0,0,0,0,0,0,0,0,0,0,0,0,0,0,0,0,0,0,0,0,0)';
      BIDIRECTIONAL='TRUE';
      INPUT_LOAD='(-0.01,0.01)';
      OUTPUT_LOAD='(1.0,-1.0)';
    'DDR0_SA_DQ30':
      PIN_NUMBER='(0,0,0,0,0,0,0,F63,0,0,0,0,0,0,0,0,0,0,0,0,0,0,0,0,0,0,0,0,0,0,0,0,0,0,0,0,0,0,0,0,0,0)';
      BIDIRECTIONAL='TRUE';
      INPUT_LOAD='(-0.01,0.01)';
      OUTPUT_LOAD='(1.0,-1.0)';
    'DDR0_SA_DQ29':
      PIN_NUMBER='(0,0,0,0,0,0,0,C62,0,0,0,0,0,0,0,0,0,0,0,0,0,0,0,0,0,0,0,0,0,0,0,0,0,0,0,0,0,0,0,0,0,0)';
      BIDIRECTIONAL='TRUE';
      INPUT_LOAD='(-0.01,0.01)';
      OUTPUT_LOAD='(1.0,-1.0)';
    'DDR0_SA_DQ28':
      PIN_NUMBER='(0,0,0,0,0,0,0,B63,0,0,0,0,0,0,0,0,0,0,0,0,0,0,0,0,0,0,0,0,0,0,0,0,0,0,0,0,0,0,0,0,0,0)';
      BIDIRECTIONAL='TRUE';
      INPUT_LOAD='(-0.01,0.01)';
      OUTPUT_LOAD='(1.0,-1.0)';
    'DDR0_SA_DQ27':
      PIN_NUMBER='(0,0,0,0,0,0,0,F65,0,0,0,0,0,0,0,0,0,0,0,0,0,0,0,0,0,0,0,0,0,0,0,0,0,0,0,0,0,0,0,0,0,0)';
      BIDIRECTIONAL='TRUE';
      INPUT_LOAD='(-0.01,0.01)';
      OUTPUT_LOAD='(1.0,-1.0)';
    'DDR0_SA_DQ26':
      PIN_NUMBER='(0,0,0,0,0,0,0,E66,0,0,0,0,0,0,0,0,0,0,0,0,0,0,0,0,0,0,0,0,0,0,0,0,0,0,0,0,0,0,0,0,0,0)';
      BIDIRECTIONAL='TRUE';
      INPUT_LOAD='(-0.01,0.01)';
      OUTPUT_LOAD='(1.0,-1.0)';
    'DDR0_SA_DQ25':
      PIN_NUMBER='(0,0,0,0,0,0,0,B65,0,0,0,0,0,0,0,0,0,0,0,0,0,0,0,0,0,0,0,0,0,0,0,0,0,0,0,0,0,0,0,0,0,0)';
      BIDIRECTIONAL='TRUE';
      INPUT_LOAD='(-0.01,0.01)';
      OUTPUT_LOAD='(1.0,-1.0)';
    'DDR0_SA_DQ24':
      PIN_NUMBER='(0,0,0,0,0,0,0,C66,0,0,0,0,0,0,0,0,0,0,0,0,0,0,0,0,0,0,0,0,0,0,0,0,0,0,0,0,0,0,0,0,0,0)';
      BIDIRECTIONAL='TRUE';
      INPUT_LOAD='(-0.01,0.01)';
      OUTPUT_LOAD='(1.0,-1.0)';
    'DDR0_SA_DQ23':
      PIN_NUMBER='(0,0,0,0,0,0,0,E68,0,0,0,0,0,0,0,0,0,0,0,0,0,0,0,0,0,0,0,0,0,0,0,0,0,0,0,0,0,0,0,0,0,0)';
      BIDIRECTIONAL='TRUE';
      INPUT_LOAD='(-0.01,0.01)';
      OUTPUT_LOAD='(1.0,-1.0)';
    'DDR0_SA_DQ22':
      PIN_NUMBER='(0,0,0,0,0,0,0,F69,0,0,0,0,0,0,0,0,0,0,0,0,0,0,0,0,0,0,0,0,0,0,0,0,0,0,0,0,0,0,0,0,0,0)';
      BIDIRECTIONAL='TRUE';
      INPUT_LOAD='(-0.01,0.01)';
      OUTPUT_LOAD='(1.0,-1.0)';
    'DDR0_SA_DQ21':
      PIN_NUMBER='(0,0,0,0,0,0,0,C68,0,0,0,0,0,0,0,0,0,0,0,0,0,0,0,0,0,0,0,0,0,0,0,0,0,0,0,0,0,0,0,0,0,0)';
      BIDIRECTIONAL='TRUE';
      INPUT_LOAD='(-0.01,0.01)';
      OUTPUT_LOAD='(1.0,-1.0)';
    'DDR0_SA_DQ20':
      PIN_NUMBER='(0,0,0,0,0,0,0,B69,0,0,0,0,0,0,0,0,0,0,0,0,0,0,0,0,0,0,0,0,0,0,0,0,0,0,0,0,0,0,0,0,0,0)';
      BIDIRECTIONAL='TRUE';
      INPUT_LOAD='(-0.01,0.01)';
      OUTPUT_LOAD='(1.0,-1.0)';
    'DDR0_SA_DQ19':
      PIN_NUMBER='(0,0,0,0,0,0,0,F71,0,0,0,0,0,0,0,0,0,0,0,0,0,0,0,0,0,0,0,0,0,0,0,0,0,0,0,0,0,0,0,0,0,0)';
      BIDIRECTIONAL='TRUE';
      INPUT_LOAD='(-0.01,0.01)';
      OUTPUT_LOAD='(1.0,-1.0)';
    'DDR0_SA_DQ18':
      PIN_NUMBER='(0,0,0,0,0,0,0,D73,0,0,0,0,0,0,0,0,0,0,0,0,0,0,0,0,0,0,0,0,0,0,0,0,0,0,0,0,0,0,0,0,0,0)';
      BIDIRECTIONAL='TRUE';
      INPUT_LOAD='(-0.01,0.01)';
      OUTPUT_LOAD='(1.0,-1.0)';
    'DDR0_SA_DQ17':
      PIN_NUMBER='(0,0,0,0,0,0,0,E72,0,0,0,0,0,0,0,0,0,0,0,0,0,0,0,0,0,0,0,0,0,0,0,0,0,0,0,0,0,0,0,0,0,0)';
      BIDIRECTIONAL='TRUE';
      INPUT_LOAD='(-0.01,0.01)';
      OUTPUT_LOAD='(1.0,-1.0)';
    'DDR0_SA_DQ16':
      PIN_NUMBER='(0,0,0,0,0,0,0,B73,0,0,0,0,0,0,0,0,0,0,0,0,0,0,0,0,0,0,0,0,0,0,0,0,0,0,0,0,0,0,0,0,0,0)';
      BIDIRECTIONAL='TRUE';
      INPUT_LOAD='(-0.01,0.01)';
      OUTPUT_LOAD='(1.0,-1.0)';
    'DDR0_SA_DQ15':
      PIN_NUMBER='(0,0,0,0,0,0,0,M65,0,0,0,0,0,0,0,0,0,0,0,0,0,0,0,0,0,0,0,0,0,0,0,0,0,0,0,0,0,0,0,0,0,0)';
      BIDIRECTIONAL='TRUE';
      INPUT_LOAD='(-0.01,0.01)';
      OUTPUT_LOAD='(1.0,-1.0)';
    'DDR0_SA_DQ14':
      PIN_NUMBER='(0,0,0,0,0,0,0,N66,0,0,0,0,0,0,0,0,0,0,0,0,0,0,0,0,0,0,0,0,0,0,0,0,0,0,0,0,0,0,0,0,0,0)';
      BIDIRECTIONAL='TRUE';
      INPUT_LOAD='(-0.01,0.01)';
      OUTPUT_LOAD='(1.0,-1.0)';
    'DDR0_SA_DQ13':
      PIN_NUMBER='(0,0,0,0,0,0,0,K65,0,0,0,0,0,0,0,0,0,0,0,0,0,0,0,0,0,0,0,0,0,0,0,0,0,0,0,0,0,0,0,0,0,0)';
      BIDIRECTIONAL='TRUE';
      INPUT_LOAD='(-0.01,0.01)';
      OUTPUT_LOAD='(1.0,-1.0)';
    'DDR0_SA_DQ12':
      PIN_NUMBER='(0,0,0,0,0,0,0,J66,0,0,0,0,0,0,0,0,0,0,0,0,0,0,0,0,0,0,0,0,0,0,0,0,0,0,0,0,0,0,0,0,0,0)';
      BIDIRECTIONAL='TRUE';
      INPUT_LOAD='(-0.01,0.01)';
      OUTPUT_LOAD='(1.0,-1.0)';
    'DDR0_SA_DQ11':
      PIN_NUMBER='(0,0,0,0,0,0,0,N68,0,0,0,0,0,0,0,0,0,0,0,0,0,0,0,0,0,0,0,0,0,0,0,0,0,0,0,0,0,0,0,0,0,0)';
      BIDIRECTIONAL='TRUE';
      INPUT_LOAD='(-0.01,0.01)';
      OUTPUT_LOAD='(1.0,-1.0)';
    'DDR0_SA_DQ10':
      PIN_NUMBER='(0,0,0,0,0,0,0,M69,0,0,0,0,0,0,0,0,0,0,0,0,0,0,0,0,0,0,0,0,0,0,0,0,0,0,0,0,0,0,0,0,0,0)';
      BIDIRECTIONAL='TRUE';
      INPUT_LOAD='(-0.01,0.01)';
      OUTPUT_LOAD='(1.0,-1.0)';
    'DDR0_SA_DQ9':
      PIN_NUMBER='(0,0,0,0,0,0,0,J68,0,0,0,0,0,0,0,0,0,0,0,0,0,0,0,0,0,0,0,0,0,0,0,0,0,0,0,0,0,0,0,0,0,0)';
      BIDIRECTIONAL='TRUE';
      INPUT_LOAD='(-0.01,0.01)';
      OUTPUT_LOAD='(1.0,-1.0)';
    'DDR0_SA_DQ8':
      PIN_NUMBER='(0,0,0,0,0,0,0,K69,0,0,0,0,0,0,0,0,0,0,0,0,0,0,0,0,0,0,0,0,0,0,0,0,0,0,0,0,0,0,0,0,0,0)';
      BIDIRECTIONAL='TRUE';
      INPUT_LOAD='(-0.01,0.01)';
      OUTPUT_LOAD='(1.0,-1.0)';
    'DDR0_SA_DQ7':
      PIN_NUMBER='(0,0,0,0,0,0,0,F75,0,0,0,0,0,0,0,0,0,0,0,0,0,0,0,0,0,0,0,0,0,0,0,0,0,0,0,0,0,0,0,0,0,0)';
      BIDIRECTIONAL='TRUE';
      INPUT_LOAD='(-0.01,0.01)';
      OUTPUT_LOAD='(1.0,-1.0)';
    'DDR0_SA_DQ6':
      PIN_NUMBER='(0,0,0,0,0,0,0,G76,0,0,0,0,0,0,0,0,0,0,0,0,0,0,0,0,0,0,0,0,0,0,0,0,0,0,0,0,0,0,0,0,0,0)';
      BIDIRECTIONAL='TRUE';
      INPUT_LOAD='(-0.01,0.01)';
      OUTPUT_LOAD='(1.0,-1.0)';
    'DDR0_SA_DQ5':
      PIN_NUMBER='(0,0,0,0,0,0,0,D75,0,0,0,0,0,0,0,0,0,0,0,0,0,0,0,0,0,0,0,0,0,0,0,0,0,0,0,0,0,0,0,0,0,0)';
      BIDIRECTIONAL='TRUE';
      INPUT_LOAD='(-0.01,0.01)';
      OUTPUT_LOAD='(1.0,-1.0)';
    'DDR0_SA_DQ4':
      PIN_NUMBER='(0,0,0,0,0,0,0,C76,0,0,0,0,0,0,0,0,0,0,0,0,0,0,0,0,0,0,0,0,0,0,0,0,0,0,0,0,0,0,0,0,0,0)';
      BIDIRECTIONAL='TRUE';
      INPUT_LOAD='(-0.01,0.01)';
      OUTPUT_LOAD='(1.0,-1.0)';
    'DDR0_SA_DQ3':
      PIN_NUMBER='(0,0,0,0,0,0,0,G78,0,0,0,0,0,0,0,0,0,0,0,0,0,0,0,0,0,0,0,0,0,0,0,0,0,0,0,0,0,0,0,0,0,0)';
      BIDIRECTIONAL='TRUE';
      INPUT_LOAD='(-0.01,0.01)';
      OUTPUT_LOAD='(1.0,-1.0)';
    'DDR0_SA_DQ2':
      PIN_NUMBER='(0,0,0,0,0,0,0,M77,0,0,0,0,0,0,0,0,0,0,0,0,0,0,0,0,0,0,0,0,0,0,0,0,0,0,0,0,0,0,0,0,0,0)';
      BIDIRECTIONAL='TRUE';
      INPUT_LOAD='(-0.01,0.01)';
      OUTPUT_LOAD='(1.0,-1.0)';
    'DDR0_SA_DQ1':
      PIN_NUMBER='(0,0,0,0,0,0,0,B79,0,0,0,0,0,0,0,0,0,0,0,0,0,0,0,0,0,0,0,0,0,0,0,0,0,0,0,0,0,0,0,0,0,0)';
      BIDIRECTIONAL='TRUE';
      INPUT_LOAD='(-0.01,0.01)';
      OUTPUT_LOAD='(1.0,-1.0)';
    'DDR0_SA_DQ0':
      PIN_NUMBER='(0,0,0,0,0,0,0,B81,0,0,0,0,0,0,0,0,0,0,0,0,0,0,0,0,0,0,0,0,0,0,0,0,0,0,0,0,0,0,0,0,0,0)';
      BIDIRECTIONAL='TRUE';
      INPUT_LOAD='(-0.01,0.01)';
      OUTPUT_LOAD='(1.0,-1.0)';
    'DDR0_SA_DQS_DN9':
      PIN_NUMBER='(0,0,0,0,0,0,0,G58,0,0,0,0,0,0,0,0,0,0,0,0,0,0,0,0,0,0,0,0,0,0,0,0,0,0,0,0,0,0,0,0,0,0)';
      BIDIRECTIONAL='TRUE';
      INPUT_LOAD='(-0.01,0.01)';
      OUTPUT_LOAD='(1.0,-1.0)';
    'DDR0_SA_DQS_DN8':
      PIN_NUMBER='(0,0,0,0,0,0,0,G64,0,0,0,0,0,0,0,0,0,0,0,0,0,0,0,0,0,0,0,0,0,0,0,0,0,0,0,0,0,0,0,0,0,0)';
      BIDIRECTIONAL='TRUE';
      INPUT_LOAD='(-0.01,0.01)';
      OUTPUT_LOAD='(1.0,-1.0)';
    'DDR0_SA_DQS_DN7':
      PIN_NUMBER='(0,0,0,0,0,0,0,G70,0,0,0,0,0,0,0,0,0,0,0,0,0,0,0,0,0,0,0,0,0,0,0,0,0,0,0,0,0,0,0,0,0,0)';
      BIDIRECTIONAL='TRUE';
      INPUT_LOAD='(-0.01,0.01)';
      OUTPUT_LOAD='(1.0,-1.0)';
    'DDR0_SA_DQS_DN6':
      PIN_NUMBER='(0,0,0,0,0,0,0,P67,0,0,0,0,0,0,0,0,0,0,0,0,0,0,0,0,0,0,0,0,0,0,0,0,0,0,0,0,0,0,0,0,0,0)';
      BIDIRECTIONAL='TRUE';
      INPUT_LOAD='(-0.01,0.01)';
      OUTPUT_LOAD='(1.0,-1.0)';
    'DDR0_SA_DQS_DN5':
      PIN_NUMBER='(0,0,0,0,0,0,0,H77,0,0,0,0,0,0,0,0,0,0,0,0,0,0,0,0,0,0,0,0,0,0,0,0,0,0,0,0,0,0,0,0,0,0)';
      BIDIRECTIONAL='TRUE';
      INPUT_LOAD='(-0.01,0.01)';
      OUTPUT_LOAD='(1.0,-1.0)';
    'DDR0_SA_DQS_DN4':
      PIN_NUMBER='(0,0,0,0,0,0,0,A58,0,0,0,0,0,0,0,0,0,0,0,0,0,0,0,0,0,0,0,0,0,0,0,0,0,0,0,0,0,0,0,0,0,0)';
      BIDIRECTIONAL='TRUE';
      INPUT_LOAD='(-0.01,0.01)';
      OUTPUT_LOAD='(1.0,-1.0)';
    'DDR0_SA_DQS_DN3':
      PIN_NUMBER='(0,0,0,0,0,0,0,A64,0,0,0,0,0,0,0,0,0,0,0,0,0,0,0,0,0,0,0,0,0,0,0,0,0,0,0,0,0,0,0,0,0,0)';
      BIDIRECTIONAL='TRUE';
      INPUT_LOAD='(-0.01,0.01)';
      OUTPUT_LOAD='(1.0,-1.0)';
    'DDR0_SA_DQS_DN2':
      PIN_NUMBER='(0,0,0,0,0,0,0,B71,0,0,0,0,0,0,0,0,0,0,0,0,0,0,0,0,0,0,0,0,0,0,0,0,0,0,0,0,0,0,0,0,0,0)';
      BIDIRECTIONAL='TRUE';
      INPUT_LOAD='(-0.01,0.01)';
      OUTPUT_LOAD='(1.0,-1.0)';
    'DDR0_SA_DQS_DN1':
      PIN_NUMBER='(0,0,0,0,0,0,0,H67,0,0,0,0,0,0,0,0,0,0,0,0,0,0,0,0,0,0,0,0,0,0,0,0,0,0,0,0,0,0,0,0,0,0)';
      BIDIRECTIONAL='TRUE';
      INPUT_LOAD='(-0.01,0.01)';
      OUTPUT_LOAD='(1.0,-1.0)';
    'DDR0_SA_DQS_DN0':
      PIN_NUMBER='(0,0,0,0,0,0,0,B77,0,0,0,0,0,0,0,0,0,0,0,0,0,0,0,0,0,0,0,0,0,0,0,0,0,0,0,0,0,0,0,0,0,0)';
      BIDIRECTIONAL='TRUE';
      INPUT_LOAD='(-0.01,0.01)';
      OUTPUT_LOAD='(1.0,-1.0)';
    'DDR0_SA_DQS_DP9':
      PIN_NUMBER='(0,0,0,0,0,0,0,E58,0,0,0,0,0,0,0,0,0,0,0,0,0,0,0,0,0,0,0,0,0,0,0,0,0,0,0,0,0,0,0,0,0,0)';
      BIDIRECTIONAL='TRUE';
      INPUT_LOAD='(-0.01,0.01)';
      OUTPUT_LOAD='(1.0,-1.0)';
    'DDR0_SA_DQS_DP8':
      PIN_NUMBER='(0,0,0,0,0,0,0,E64,0,0,0,0,0,0,0,0,0,0,0,0,0,0,0,0,0,0,0,0,0,0,0,0,0,0,0,0,0,0,0,0,0,0)';
      BIDIRECTIONAL='TRUE';
      INPUT_LOAD='(-0.01,0.01)';
      OUTPUT_LOAD='(1.0,-1.0)';
    'DDR0_SA_DQS_DP7':
      PIN_NUMBER='(0,0,0,0,0,0,0,E70,0,0,0,0,0,0,0,0,0,0,0,0,0,0,0,0,0,0,0,0,0,0,0,0,0,0,0,0,0,0,0,0,0,0)';
      BIDIRECTIONAL='TRUE';
      INPUT_LOAD='(-0.01,0.01)';
      OUTPUT_LOAD='(1.0,-1.0)';
    'DDR0_SA_DQS_DP6':
      PIN_NUMBER='(0,0,0,0,0,0,0,M67,0,0,0,0,0,0,0,0,0,0,0,0,0,0,0,0,0,0,0,0,0,0,0,0,0,0,0,0,0,0,0,0,0,0)';
      BIDIRECTIONAL='TRUE';
      INPUT_LOAD='(-0.01,0.01)';
      OUTPUT_LOAD='(1.0,-1.0)';
    'DDR0_SA_DQS_DP5':
      PIN_NUMBER='(0,0,0,0,0,0,0,F77,0,0,0,0,0,0,0,0,0,0,0,0,0,0,0,0,0,0,0,0,0,0,0,0,0,0,0,0,0,0,0,0,0,0)';
      BIDIRECTIONAL='TRUE';
      INPUT_LOAD='(-0.01,0.01)';
      OUTPUT_LOAD='(1.0,-1.0)';
    'DDR0_SA_DQS_DP4':
      PIN_NUMBER='(0,0,0,0,0,0,0,C58,0,0,0,0,0,0,0,0,0,0,0,0,0,0,0,0,0,0,0,0,0,0,0,0,0,0,0,0,0,0,0,0,0,0)';
      BIDIRECTIONAL='TRUE';
      INPUT_LOAD='(-0.01,0.01)';
      OUTPUT_LOAD='(1.0,-1.0)';
    'DDR0_SA_DQS_DP3':
      PIN_NUMBER='(0,0,0,0,0,0,0,C64,0,0,0,0,0,0,0,0,0,0,0,0,0,0,0,0,0,0,0,0,0,0,0,0,0,0,0,0,0,0,0,0,0,0)';
      BIDIRECTIONAL='TRUE';
      INPUT_LOAD='(-0.01,0.01)';
      OUTPUT_LOAD='(1.0,-1.0)';
    'DDR0_SA_DQS_DP2':
      PIN_NUMBER='(0,0,0,0,0,0,0,C70,0,0,0,0,0,0,0,0,0,0,0,0,0,0,0,0,0,0,0,0,0,0,0,0,0,0,0,0,0,0,0,0,0,0)';
      BIDIRECTIONAL='TRUE';
      INPUT_LOAD='(-0.01,0.01)';
      OUTPUT_LOAD='(1.0,-1.0)';
    'DDR0_SA_DQS_DP1':
      PIN_NUMBER='(0,0,0,0,0,0,0,K67,0,0,0,0,0,0,0,0,0,0,0,0,0,0,0,0,0,0,0,0,0,0,0,0,0,0,0,0,0,0,0,0,0,0)';
      BIDIRECTIONAL='TRUE';
      INPUT_LOAD='(-0.01,0.01)';
      OUTPUT_LOAD='(1.0,-1.0)';
    'DDR0_SA_DQS_DP0':
      PIN_NUMBER='(0,0,0,0,0,0,0,D77,0,0,0,0,0,0,0,0,0,0,0,0,0,0,0,0,0,0,0,0,0,0,0,0,0,0,0,0,0,0,0,0,0,0)';
      BIDIRECTIONAL='TRUE';
      INPUT_LOAD='(-0.01,0.01)';
      OUTPUT_LOAD='(1.0,-1.0)';
    'DDR0_SA_ECC7':
      PIN_NUMBER='(0,0,0,0,0,0,0,E56,0,0,0,0,0,0,0,0,0,0,0,0,0,0,0,0,0,0,0,0,0,0,0,0,0,0,0,0,0,0,0,0,0,0)';
      BIDIRECTIONAL='TRUE';
      INPUT_LOAD='(-0.01,0.01)';
      OUTPUT_LOAD='(1.0,-1.0)';
    'DDR0_SA_ECC6':
      PIN_NUMBER='(0,0,0,0,0,0,0,F57,0,0,0,0,0,0,0,0,0,0,0,0,0,0,0,0,0,0,0,0,0,0,0,0,0,0,0,0,0,0,0,0,0,0)';
      BIDIRECTIONAL='TRUE';
      INPUT_LOAD='(-0.01,0.01)';
      OUTPUT_LOAD='(1.0,-1.0)';
    'DDR0_SA_ECC5':
      PIN_NUMBER='(0,0,0,0,0,0,0,C56,0,0,0,0,0,0,0,0,0,0,0,0,0,0,0,0,0,0,0,0,0,0,0,0,0,0,0,0,0,0,0,0,0,0)';
      BIDIRECTIONAL='TRUE';
      INPUT_LOAD='(-0.01,0.01)';
      OUTPUT_LOAD='(1.0,-1.0)';
    'DDR0_SA_ECC4':
      PIN_NUMBER='(0,0,0,0,0,0,0,B57,0,0,0,0,0,0,0,0,0,0,0,0,0,0,0,0,0,0,0,0,0,0,0,0,0,0,0,0,0,0,0,0,0,0)';
      BIDIRECTIONAL='TRUE';
      INPUT_LOAD='(-0.01,0.01)';
      OUTPUT_LOAD='(1.0,-1.0)';
    'DDR0_SA_ECC3':
      PIN_NUMBER='(0,0,0,0,0,0,0,F59,0,0,0,0,0,0,0,0,0,0,0,0,0,0,0,0,0,0,0,0,0,0,0,0,0,0,0,0,0,0,0,0,0,0)';
      BIDIRECTIONAL='TRUE';
      INPUT_LOAD='(-0.01,0.01)';
      OUTPUT_LOAD='(1.0,-1.0)';
    'DDR0_SA_ECC2':
      PIN_NUMBER='(0,0,0,0,0,0,0,E60,0,0,0,0,0,0,0,0,0,0,0,0,0,0,0,0,0,0,0,0,0,0,0,0,0,0,0,0,0,0,0,0,0,0)';
      BIDIRECTIONAL='TRUE';
      INPUT_LOAD='(-0.01,0.01)';
      OUTPUT_LOAD='(1.0,-1.0)';
    'DDR0_SA_ECC1':
      PIN_NUMBER='(0,0,0,0,0,0,0,B59,0,0,0,0,0,0,0,0,0,0,0,0,0,0,0,0,0,0,0,0,0,0,0,0,0,0,0,0,0,0,0,0,0,0)';
      BIDIRECTIONAL='TRUE';
      INPUT_LOAD='(-0.01,0.01)';
      OUTPUT_LOAD='(1.0,-1.0)';
    'DDR0_SA_ECC0':
      PIN_NUMBER='(0,0,0,0,0,0,0,C60,0,0,0,0,0,0,0,0,0,0,0,0,0,0,0,0,0,0,0,0,0,0,0,0,0,0,0,0,0,0,0,0,0,0)';
      BIDIRECTIONAL='TRUE';
      INPUT_LOAD='(-0.01,0.01)';
      OUTPUT_LOAD='(1.0,-1.0)';
    'DDR0_SA_PAR':
      PIN_NUMBER='(0,0,0,0,0,0,0,E48,0,0,0,0,0,0,0,0,0,0,0,0,0,0,0,0,0,0,0,0,0,0,0,0,0,0,0,0,0,0,0,0,0,0)';
      OUTPUT_LOAD='(1.0,-1.0)';
    'DDR0_SB_CA6':
      PIN_NUMBER='(0,0,0,0,0,0,0,A39,0,0,0,0,0,0,0,0,0,0,0,0,0,0,0,0,0,0,0,0,0,0,0,0,0,0,0,0,0,0,0,0,0,0)';
      OUTPUT_LOAD='(1.0,-1.0)';
    'DDR0_SB_CA5':
      PIN_NUMBER='(0,0,0,0,0,0,0,F40,0,0,0,0,0,0,0,0,0,0,0,0,0,0,0,0,0,0,0,0,0,0,0,0,0,0,0,0,0,0,0,0,0,0)';
      OUTPUT_LOAD='(1.0,-1.0)';
    'DDR0_SB_CA4':
      PIN_NUMBER='(0,0,0,0,0,0,0,B40,0,0,0,0,0,0,0,0,0,0,0,0,0,0,0,0,0,0,0,0,0,0,0,0,0,0,0,0,0,0,0,0,0,0)';
      OUTPUT_LOAD='(1.0,-1.0)';
    'DDR0_SB_CA3':
      PIN_NUMBER='(0,0,0,0,0,0,0,E41,0,0,0,0,0,0,0,0,0,0,0,0,0,0,0,0,0,0,0,0,0,0,0,0,0,0,0,0,0,0,0,0,0,0)';
      OUTPUT_LOAD='(1.0,-1.0)';
    'DDR0_SB_CA2':
      PIN_NUMBER='(0,0,0,0,0,0,0,C41,0,0,0,0,0,0,0,0,0,0,0,0,0,0,0,0,0,0,0,0,0,0,0,0,0,0,0,0,0,0,0,0,0,0)';
      OUTPUT_LOAD='(1.0,-1.0)';
    'DDR0_SB_CA1':
      PIN_NUMBER='(0,0,0,0,0,0,0,F44,0,0,0,0,0,0,0,0,0,0,0,0,0,0,0,0,0,0,0,0,0,0,0,0,0,0,0,0,0,0,0,0,0,0)';
      OUTPUT_LOAD='(1.0,-1.0)';
    'DDR0_SB_CA0':
      PIN_NUMBER='(0,0,0,0,0,0,0,E43,0,0,0,0,0,0,0,0,0,0,0,0,0,0,0,0,0,0,0,0,0,0,0,0,0,0,0,0,0,0,0,0,0,0)';
      OUTPUT_LOAD='(1.0,-1.0)';
    'DDR0_SB_CS_N3':
      PIN_NUMBER='(0,0,0,0,0,0,0,E37,0,0,0,0,0,0,0,0,0,0,0,0,0,0,0,0,0,0,0,0,0,0,0,0,0,0,0,0,0,0,0,0,0,0)';
      OUTPUT_LOAD='(1.0,-1.0)';
    'DDR0_SB_CS_N2':
      PIN_NUMBER='(0,0,0,0,0,0,0,F38,0,0,0,0,0,0,0,0,0,0,0,0,0,0,0,0,0,0,0,0,0,0,0,0,0,0,0,0,0,0,0,0,0,0)';
      OUTPUT_LOAD='(1.0,-1.0)';
    'DDR0_SB_CS_N1':
      PIN_NUMBER='(0,0,0,0,0,0,0,C37,0,0,0,0,0,0,0,0,0,0,0,0,0,0,0,0,0,0,0,0,0,0,0,0,0,0,0,0,0,0,0,0,0,0)';
      OUTPUT_LOAD='(1.0,-1.0)';
    'DDR0_SB_CS_N0':
      PIN_NUMBER='(0,0,0,0,0,0,0,B38,0,0,0,0,0,0,0,0,0,0,0,0,0,0,0,0,0,0,0,0,0,0,0,0,0,0,0,0,0,0,0,0,0,0)';
      OUTPUT_LOAD='(1.0,-1.0)';
    'DDR0_SB_DQ31':
      PIN_NUMBER='(0,0,0,0,0,0,0,E7,0,0,0,0,0,0,0,0,0,0,0,0,0,0,0,0,0,0,0,0,0,0,0,0,0,0,0,0,0,0,0,0,0,0)';
      BIDIRECTIONAL='TRUE';
      INPUT_LOAD='(-0.01,0.01)';
      OUTPUT_LOAD='(1.0,-1.0)';
    'DDR0_SB_DQ30':
      PIN_NUMBER='(0,0,0,0,0,0,0,F8,0,0,0,0,0,0,0,0,0,0,0,0,0,0,0,0,0,0,0,0,0,0,0,0,0,0,0,0,0,0,0,0,0,0)';
      BIDIRECTIONAL='TRUE';
      INPUT_LOAD='(-0.01,0.01)';
      OUTPUT_LOAD='(1.0,-1.0)';
    'DDR0_SB_DQ29':
      PIN_NUMBER='(0,0,0,0,0,0,0,C7,0,0,0,0,0,0,0,0,0,0,0,0,0,0,0,0,0,0,0,0,0,0,0,0,0,0,0,0,0,0,0,0,0,0)';
      BIDIRECTIONAL='TRUE';
      INPUT_LOAD='(-0.01,0.01)';
      OUTPUT_LOAD='(1.0,-1.0)';
    'DDR0_SB_DQ28':
      PIN_NUMBER='(0,0,0,0,0,0,0,B8,0,0,0,0,0,0,0,0,0,0,0,0,0,0,0,0,0,0,0,0,0,0,0,0,0,0,0,0,0,0,0,0,0,0)';
      BIDIRECTIONAL='TRUE';
      INPUT_LOAD='(-0.01,0.01)';
      OUTPUT_LOAD='(1.0,-1.0)';
    'DDR0_SB_DQ27':
      PIN_NUMBER='(0,0,0,0,0,0,0,F10,0,0,0,0,0,0,0,0,0,0,0,0,0,0,0,0,0,0,0,0,0,0,0,0,0,0,0,0,0,0,0,0,0,0)';
      BIDIRECTIONAL='TRUE';
      INPUT_LOAD='(-0.01,0.01)';
      OUTPUT_LOAD='(1.0,-1.0)';
    'DDR0_SB_DQ26':
      PIN_NUMBER='(0,0,0,0,0,0,0,E11,0,0,0,0,0,0,0,0,0,0,0,0,0,0,0,0,0,0,0,0,0,0,0,0,0,0,0,0,0,0,0,0,0,0)';
      BIDIRECTIONAL='TRUE';
      INPUT_LOAD='(-0.01,0.01)';
      OUTPUT_LOAD='(1.0,-1.0)';
    'DDR0_SB_DQ25':
      PIN_NUMBER='(0,0,0,0,0,0,0,B10,0,0,0,0,0,0,0,0,0,0,0,0,0,0,0,0,0,0,0,0,0,0,0,0,0,0,0,0,0,0,0,0,0,0)';
      BIDIRECTIONAL='TRUE';
      INPUT_LOAD='(-0.01,0.01)';
      OUTPUT_LOAD='(1.0,-1.0)';
    'DDR0_SB_DQ24':
      PIN_NUMBER='(0,0,0,0,0,0,0,C11,0,0,0,0,0,0,0,0,0,0,0,0,0,0,0,0,0,0,0,0,0,0,0,0,0,0,0,0,0,0,0,0,0,0)';
      BIDIRECTIONAL='TRUE';
      INPUT_LOAD='(-0.01,0.01)';
      OUTPUT_LOAD='(1.0,-1.0)';
    'DDR0_SB_DQ23':
      PIN_NUMBER='(0,0,0,0,0,0,0,E19,0,0,0,0,0,0,0,0,0,0,0,0,0,0,0,0,0,0,0,0,0,0,0,0,0,0,0,0,0,0,0,0,0,0)';
      BIDIRECTIONAL='TRUE';
      INPUT_LOAD='(-0.01,0.01)';
      OUTPUT_LOAD='(1.0,-1.0)';
    'DDR0_SB_DQ22':
      PIN_NUMBER='(0,0,0,0,0,0,0,F20,0,0,0,0,0,0,0,0,0,0,0,0,0,0,0,0,0,0,0,0,0,0,0,0,0,0,0,0,0,0,0,0,0,0)';
      BIDIRECTIONAL='TRUE';
      INPUT_LOAD='(-0.01,0.01)';
      OUTPUT_LOAD='(1.0,-1.0)';
    'DDR0_SB_DQ21':
      PIN_NUMBER='(0,0,0,0,0,0,0,C19,0,0,0,0,0,0,0,0,0,0,0,0,0,0,0,0,0,0,0,0,0,0,0,0,0,0,0,0,0,0,0,0,0,0)';
      BIDIRECTIONAL='TRUE';
      INPUT_LOAD='(-0.01,0.01)';
      OUTPUT_LOAD='(1.0,-1.0)';
    'DDR0_SB_DQ20':
      PIN_NUMBER='(0,0,0,0,0,0,0,B20,0,0,0,0,0,0,0,0,0,0,0,0,0,0,0,0,0,0,0,0,0,0,0,0,0,0,0,0,0,0,0,0,0,0)';
      BIDIRECTIONAL='TRUE';
      INPUT_LOAD='(-0.01,0.01)';
      OUTPUT_LOAD='(1.0,-1.0)';
    'DDR0_SB_DQ19':
      PIN_NUMBER='(0,0,0,0,0,0,0,F22,0,0,0,0,0,0,0,0,0,0,0,0,0,0,0,0,0,0,0,0,0,0,0,0,0,0,0,0,0,0,0,0,0,0)';
      BIDIRECTIONAL='TRUE';
      INPUT_LOAD='(-0.01,0.01)';
      OUTPUT_LOAD='(1.0,-1.0)';
    'DDR0_SB_DQ18':
      PIN_NUMBER='(0,0,0,0,0,0,0,E23,0,0,0,0,0,0,0,0,0,0,0,0,0,0,0,0,0,0,0,0,0,0,0,0,0,0,0,0,0,0,0,0,0,0)';
      BIDIRECTIONAL='TRUE';
      INPUT_LOAD='(-0.01,0.01)';
      OUTPUT_LOAD='(1.0,-1.0)';
    'DDR0_SB_DQ17':
      PIN_NUMBER='(0,0,0,0,0,0,0,B22,0,0,0,0,0,0,0,0,0,0,0,0,0,0,0,0,0,0,0,0,0,0,0,0,0,0,0,0,0,0,0,0,0,0)';
      BIDIRECTIONAL='TRUE';
      INPUT_LOAD='(-0.01,0.01)';
      OUTPUT_LOAD='(1.0,-1.0)';
    'DDR0_SB_DQ16':
      PIN_NUMBER='(0,0,0,0,0,0,0,C23,0,0,0,0,0,0,0,0,0,0,0,0,0,0,0,0,0,0,0,0,0,0,0,0,0,0,0,0,0,0,0,0,0,0)';
      BIDIRECTIONAL='TRUE';
      INPUT_LOAD='(-0.01,0.01)';
      OUTPUT_LOAD='(1.0,-1.0)';
    'DDR0_SB_DQ15':
      PIN_NUMBER='(0,0,0,0,0,0,0,E25,0,0,0,0,0,0,0,0,0,0,0,0,0,0,0,0,0,0,0,0,0,0,0,0,0,0,0,0,0,0,0,0,0,0)';
      BIDIRECTIONAL='TRUE';
      INPUT_LOAD='(-0.01,0.01)';
      OUTPUT_LOAD='(1.0,-1.0)';
    'DDR0_SB_DQ14':
      PIN_NUMBER='(0,0,0,0,0,0,0,F26,0,0,0,0,0,0,0,0,0,0,0,0,0,0,0,0,0,0,0,0,0,0,0,0,0,0,0,0,0,0,0,0,0,0)';
      BIDIRECTIONAL='TRUE';
      INPUT_LOAD='(-0.01,0.01)';
      OUTPUT_LOAD='(1.0,-1.0)';
    'DDR0_SB_DQ13':
      PIN_NUMBER='(0,0,0,0,0,0,0,C25,0,0,0,0,0,0,0,0,0,0,0,0,0,0,0,0,0,0,0,0,0,0,0,0,0,0,0,0,0,0,0,0,0,0)';
      BIDIRECTIONAL='TRUE';
      INPUT_LOAD='(-0.01,0.01)';
      OUTPUT_LOAD='(1.0,-1.0)';
    'DDR0_SB_DQ12':
      PIN_NUMBER='(0,0,0,0,0,0,0,B26,0,0,0,0,0,0,0,0,0,0,0,0,0,0,0,0,0,0,0,0,0,0,0,0,0,0,0,0,0,0,0,0,0,0)';
      BIDIRECTIONAL='TRUE';
      INPUT_LOAD='(-0.01,0.01)';
      OUTPUT_LOAD='(1.0,-1.0)';
    'DDR0_SB_DQ11':
      PIN_NUMBER='(0,0,0,0,0,0,0,F28,0,0,0,0,0,0,0,0,0,0,0,0,0,0,0,0,0,0,0,0,0,0,0,0,0,0,0,0,0,0,0,0,0,0)';
      BIDIRECTIONAL='TRUE';
      INPUT_LOAD='(-0.01,0.01)';
      OUTPUT_LOAD='(1.0,-1.0)';
    'DDR0_SB_DQ10':
      PIN_NUMBER='(0,0,0,0,0,0,0,E29,0,0,0,0,0,0,0,0,0,0,0,0,0,0,0,0,0,0,0,0,0,0,0,0,0,0,0,0,0,0,0,0,0,0)';
      BIDIRECTIONAL='TRUE';
      INPUT_LOAD='(-0.01,0.01)';
      OUTPUT_LOAD='(1.0,-1.0)';
    'DDR0_SB_DQ9':
      PIN_NUMBER='(0,0,0,0,0,0,0,B28,0,0,0,0,0,0,0,0,0,0,0,0,0,0,0,0,0,0,0,0,0,0,0,0,0,0,0,0,0,0,0,0,0,0)';
      BIDIRECTIONAL='TRUE';
      INPUT_LOAD='(-0.01,0.01)';
      OUTPUT_LOAD='(1.0,-1.0)';
    'DDR0_SB_DQ8':
      PIN_NUMBER='(0,0,0,0,0,0,0,C29,0,0,0,0,0,0,0,0,0,0,0,0,0,0,0,0,0,0,0,0,0,0,0,0,0,0,0,0,0,0,0,0,0,0)';
      BIDIRECTIONAL='TRUE';
      INPUT_LOAD='(-0.01,0.01)';
      OUTPUT_LOAD='(1.0,-1.0)';
    'DDR0_SB_DQ7':
      PIN_NUMBER='(0,0,0,0,0,0,0,M28,0,0,0,0,0,0,0,0,0,0,0,0,0,0,0,0,0,0,0,0,0,0,0,0,0,0,0,0,0,0,0,0,0,0)';
      BIDIRECTIONAL='TRUE';
      INPUT_LOAD='(-0.01,0.01)';
      OUTPUT_LOAD='(1.0,-1.0)';
    'DDR0_SB_DQ6':
      PIN_NUMBER='(0,0,0,0,0,0,0,N29,0,0,0,0,0,0,0,0,0,0,0,0,0,0,0,0,0,0,0,0,0,0,0,0,0,0,0,0,0,0,0,0,0,0)';
      BIDIRECTIONAL='TRUE';
      INPUT_LOAD='(-0.01,0.01)';
      OUTPUT_LOAD='(1.0,-1.0)';
    'DDR0_SB_DQ5':
      PIN_NUMBER='(0,0,0,0,0,0,0,K28,0,0,0,0,0,0,0,0,0,0,0,0,0,0,0,0,0,0,0,0,0,0,0,0,0,0,0,0,0,0,0,0,0,0)';
      BIDIRECTIONAL='TRUE';
      INPUT_LOAD='(-0.01,0.01)';
      OUTPUT_LOAD='(1.0,-1.0)';
    'DDR0_SB_DQ4':
      PIN_NUMBER='(0,0,0,0,0,0,0,J29,0,0,0,0,0,0,0,0,0,0,0,0,0,0,0,0,0,0,0,0,0,0,0,0,0,0,0,0,0,0,0,0,0,0)';
      BIDIRECTIONAL='TRUE';
      INPUT_LOAD='(-0.01,0.01)';
      OUTPUT_LOAD='(1.0,-1.0)';
    'DDR0_SB_DQ3':
      PIN_NUMBER='(0,0,0,0,0,0,0,N31,0,0,0,0,0,0,0,0,0,0,0,0,0,0,0,0,0,0,0,0,0,0,0,0,0,0,0,0,0,0,0,0,0,0)';
      BIDIRECTIONAL='TRUE';
      INPUT_LOAD='(-0.01,0.01)';
      OUTPUT_LOAD='(1.0,-1.0)';
    'DDR0_SB_DQ2':
      PIN_NUMBER='(0,0,0,0,0,0,0,M32,0,0,0,0,0,0,0,0,0,0,0,0,0,0,0,0,0,0,0,0,0,0,0,0,0,0,0,0,0,0,0,0,0,0)';
      BIDIRECTIONAL='TRUE';
      INPUT_LOAD='(-0.01,0.01)';
      OUTPUT_LOAD='(1.0,-1.0)';
    'DDR0_SB_DQ1':
      PIN_NUMBER='(0,0,0,0,0,0,0,J31,0,0,0,0,0,0,0,0,0,0,0,0,0,0,0,0,0,0,0,0,0,0,0,0,0,0,0,0,0,0,0,0,0,0)';
      BIDIRECTIONAL='TRUE';
      INPUT_LOAD='(-0.01,0.01)';
      OUTPUT_LOAD='(1.0,-1.0)';
    'DDR0_SB_DQ0':
      PIN_NUMBER='(0,0,0,0,0,0,0,K32,0,0,0,0,0,0,0,0,0,0,0,0,0,0,0,0,0,0,0,0,0,0,0,0,0,0,0,0,0,0,0,0,0,0)';
      BIDIRECTIONAL='TRUE';
      INPUT_LOAD='(-0.01,0.01)';
      OUTPUT_LOAD='(1.0,-1.0)';
    'DDR0_SB_DQS_DN9':
      PIN_NUMBER='(0,0,0,0,0,0,0,A33,0,0,0,0,0,0,0,0,0,0,0,0,0,0,0,0,0,0,0,0,0,0,0,0,0,0,0,0,0,0,0,0,0,0)';
      BIDIRECTIONAL='TRUE';
      INPUT_LOAD='(-0.01,0.01)';
      OUTPUT_LOAD='(1.0,-1.0)';
    'DDR0_SB_DQS_DN8':
      PIN_NUMBER='(0,0,0,0,0,0,0,G9,0,0,0,0,0,0,0,0,0,0,0,0,0,0,0,0,0,0,0,0,0,0,0,0,0,0,0,0,0,0,0,0,0,0)';
      BIDIRECTIONAL='TRUE';
      INPUT_LOAD='(-0.01,0.01)';
      OUTPUT_LOAD='(1.0,-1.0)';
    'DDR0_SB_DQS_DN7':
      PIN_NUMBER='(0,0,0,0,0,0,0,G21,0,0,0,0,0,0,0,0,0,0,0,0,0,0,0,0,0,0,0,0,0,0,0,0,0,0,0,0,0,0,0,0,0,0)';
      BIDIRECTIONAL='TRUE';
      INPUT_LOAD='(-0.01,0.01)';
      OUTPUT_LOAD='(1.0,-1.0)';
    'DDR0_SB_DQS_DN6':
      PIN_NUMBER='(0,0,0,0,0,0,0,G27,0,0,0,0,0,0,0,0,0,0,0,0,0,0,0,0,0,0,0,0,0,0,0,0,0,0,0,0,0,0,0,0,0,0)';
      BIDIRECTIONAL='TRUE';
      INPUT_LOAD='(-0.01,0.01)';
      OUTPUT_LOAD='(1.0,-1.0)';
    'DDR0_SB_DQS_DN5':
      PIN_NUMBER='(0,0,0,0,0,0,0,M30,0,0,0,0,0,0,0,0,0,0,0,0,0,0,0,0,0,0,0,0,0,0,0,0,0,0,0,0,0,0,0,0,0,0)';
      BIDIRECTIONAL='TRUE';
      INPUT_LOAD='(-0.01,0.01)';
      OUTPUT_LOAD='(1.0,-1.0)';
    'DDR0_SB_DQS_DN4':
      PIN_NUMBER='(0,0,0,0,0,0,0,G33,0,0,0,0,0,0,0,0,0,0,0,0,0,0,0,0,0,0,0,0,0,0,0,0,0,0,0,0,0,0,0,0,0,0)';
      BIDIRECTIONAL='TRUE';
      INPUT_LOAD='(-0.01,0.01)';
      OUTPUT_LOAD='(1.0,-1.0)';
    'DDR0_SB_DQS_DN3':
      PIN_NUMBER='(0,0,0,0,0,0,0,A9,0,0,0,0,0,0,0,0,0,0,0,0,0,0,0,0,0,0,0,0,0,0,0,0,0,0,0,0,0,0,0,0,0,0)';
      BIDIRECTIONAL='TRUE';
      INPUT_LOAD='(-0.01,0.01)';
      OUTPUT_LOAD='(1.0,-1.0)';
    'DDR0_SB_DQS_DN2':
      PIN_NUMBER='(0,0,0,0,0,0,0,A21,0,0,0,0,0,0,0,0,0,0,0,0,0,0,0,0,0,0,0,0,0,0,0,0,0,0,0,0,0,0,0,0,0,0)';
      BIDIRECTIONAL='TRUE';
      INPUT_LOAD='(-0.01,0.01)';
      OUTPUT_LOAD='(1.0,-1.0)';
    'DDR0_SB_DQS_DN1':
      PIN_NUMBER='(0,0,0,0,0,0,0,A27,0,0,0,0,0,0,0,0,0,0,0,0,0,0,0,0,0,0,0,0,0,0,0,0,0,0,0,0,0,0,0,0,0,0)';
      BIDIRECTIONAL='TRUE';
      INPUT_LOAD='(-0.01,0.01)';
      OUTPUT_LOAD='(1.0,-1.0)';
    'DDR0_SB_DQS_DN0':
      PIN_NUMBER='(0,0,0,0,0,0,0,H30,0,0,0,0,0,0,0,0,0,0,0,0,0,0,0,0,0,0,0,0,0,0,0,0,0,0,0,0,0,0,0,0,0,0)';
      BIDIRECTIONAL='TRUE';
      INPUT_LOAD='(-0.01,0.01)';
      OUTPUT_LOAD='(1.0,-1.0)';
    'DDR0_SB_DQS_DP9':
      PIN_NUMBER='(0,0,0,0,0,0,0,C33,0,0,0,0,0,0,0,0,0,0,0,0,0,0,0,0,0,0,0,0,0,0,0,0,0,0,0,0,0,0,0,0,0,0)';
      BIDIRECTIONAL='TRUE';
      INPUT_LOAD='(-0.01,0.01)';
      OUTPUT_LOAD='(1.0,-1.0)';
    'DDR0_SB_DQS_DP8':
      PIN_NUMBER='(0,0,0,0,0,0,0,E9,0,0,0,0,0,0,0,0,0,0,0,0,0,0,0,0,0,0,0,0,0,0,0,0,0,0,0,0,0,0,0,0,0,0)';
      BIDIRECTIONAL='TRUE';
      INPUT_LOAD='(-0.01,0.01)';
      OUTPUT_LOAD='(1.0,-1.0)';
    'DDR0_SB_DQS_DP7':
      PIN_NUMBER='(0,0,0,0,0,0,0,E21,0,0,0,0,0,0,0,0,0,0,0,0,0,0,0,0,0,0,0,0,0,0,0,0,0,0,0,0,0,0,0,0,0,0)';
      BIDIRECTIONAL='TRUE';
      INPUT_LOAD='(-0.01,0.01)';
      OUTPUT_LOAD='(1.0,-1.0)';
    'DDR0_SB_DQS_DP6':
      PIN_NUMBER='(0,0,0,0,0,0,0,E27,0,0,0,0,0,0,0,0,0,0,0,0,0,0,0,0,0,0,0,0,0,0,0,0,0,0,0,0,0,0,0,0,0,0)';
      BIDIRECTIONAL='TRUE';
      INPUT_LOAD='(-0.01,0.01)';
      OUTPUT_LOAD='(1.0,-1.0)';
    'DDR0_SB_DQS_DP5':
      PIN_NUMBER='(0,0,0,0,0,0,0,P30,0,0,0,0,0,0,0,0,0,0,0,0,0,0,0,0,0,0,0,0,0,0,0,0,0,0,0,0,0,0,0,0,0,0)';
      BIDIRECTIONAL='TRUE';
      INPUT_LOAD='(-0.01,0.01)';
      OUTPUT_LOAD='(1.0,-1.0)';
    'DDR0_SB_DQS_DP4':
      PIN_NUMBER='(0,0,0,0,0,0,0,E33,0,0,0,0,0,0,0,0,0,0,0,0,0,0,0,0,0,0,0,0,0,0,0,0,0,0,0,0,0,0,0,0,0,0)';
      BIDIRECTIONAL='TRUE';
      INPUT_LOAD='(-0.01,0.01)';
      OUTPUT_LOAD='(1.0,-1.0)';
    'DDR0_SB_DQS_DP3':
      PIN_NUMBER='(0,0,0,0,0,0,0,C9,0,0,0,0,0,0,0,0,0,0,0,0,0,0,0,0,0,0,0,0,0,0,0,0,0,0,0,0,0,0,0,0,0,0)';
      BIDIRECTIONAL='TRUE';
      INPUT_LOAD='(-0.01,0.01)';
      OUTPUT_LOAD='(1.0,-1.0)';
    'DDR0_SB_DQS_DP2':
      PIN_NUMBER='(0,0,0,0,0,0,0,C21,0,0,0,0,0,0,0,0,0,0,0,0,0,0,0,0,0,0,0,0,0,0,0,0,0,0,0,0,0,0,0,0,0,0)';
      BIDIRECTIONAL='TRUE';
      INPUT_LOAD='(-0.01,0.01)';
      OUTPUT_LOAD='(1.0,-1.0)';
    'DDR0_SB_DQS_DP1':
      PIN_NUMBER='(0,0,0,0,0,0,0,C27,0,0,0,0,0,0,0,0,0,0,0,0,0,0,0,0,0,0,0,0,0,0,0,0,0,0,0,0,0,0,0,0,0,0)';
      BIDIRECTIONAL='TRUE';
      INPUT_LOAD='(-0.01,0.01)';
      OUTPUT_LOAD='(1.0,-1.0)';
    'DDR0_SB_DQS_DP0':
      PIN_NUMBER='(0,0,0,0,0,0,0,K30,0,0,0,0,0,0,0,0,0,0,0,0,0,0,0,0,0,0,0,0,0,0,0,0,0,0,0,0,0,0,0,0,0,0)';
      BIDIRECTIONAL='TRUE';
      INPUT_LOAD='(-0.01,0.01)';
      OUTPUT_LOAD='(1.0,-1.0)';
    'DDR0_SB_ECC7':
      PIN_NUMBER='(0,0,0,0,0,0,0,F34,0,0,0,0,0,0,0,0,0,0,0,0,0,0,0,0,0,0,0,0,0,0,0,0,0,0,0,0,0,0,0,0,0,0)';
      BIDIRECTIONAL='TRUE';
      INPUT_LOAD='(-0.01,0.01)';
      OUTPUT_LOAD='(1.0,-1.0)';
    'DDR0_SB_ECC6':
      PIN_NUMBER='(0,0,0,0,0,0,0,E35,0,0,0,0,0,0,0,0,0,0,0,0,0,0,0,0,0,0,0,0,0,0,0,0,0,0,0,0,0,0,0,0,0,0)';
      BIDIRECTIONAL='TRUE';
      INPUT_LOAD='(-0.01,0.01)';
      OUTPUT_LOAD='(1.0,-1.0)';
    'DDR0_SB_ECC5':
      PIN_NUMBER='(0,0,0,0,0,0,0,B34,0,0,0,0,0,0,0,0,0,0,0,0,0,0,0,0,0,0,0,0,0,0,0,0,0,0,0,0,0,0,0,0,0,0)';
      BIDIRECTIONAL='TRUE';
      INPUT_LOAD='(-0.01,0.01)';
      OUTPUT_LOAD='(1.0,-1.0)';
    'DDR0_SB_ECC4':
      PIN_NUMBER='(0,0,0,0,0,0,0,C35,0,0,0,0,0,0,0,0,0,0,0,0,0,0,0,0,0,0,0,0,0,0,0,0,0,0,0,0,0,0,0,0,0,0)';
      BIDIRECTIONAL='TRUE';
      INPUT_LOAD='(-0.01,0.01)';
      OUTPUT_LOAD='(1.0,-1.0)';
    'DDR0_SB_ECC3':
      PIN_NUMBER='(0,0,0,0,0,0,0,E31,0,0,0,0,0,0,0,0,0,0,0,0,0,0,0,0,0,0,0,0,0,0,0,0,0,0,0,0,0,0,0,0,0,0)';
      BIDIRECTIONAL='TRUE';
      INPUT_LOAD='(-0.01,0.01)';
      OUTPUT_LOAD='(1.0,-1.0)';
    'DDR0_SB_ECC2':
      PIN_NUMBER='(0,0,0,0,0,0,0,F32,0,0,0,0,0,0,0,0,0,0,0,0,0,0,0,0,0,0,0,0,0,0,0,0,0,0,0,0,0,0,0,0,0,0)';
      BIDIRECTIONAL='TRUE';
      INPUT_LOAD='(-0.01,0.01)';
      OUTPUT_LOAD='(1.0,-1.0)';
    'DDR0_SB_ECC1':
      PIN_NUMBER='(0,0,0,0,0,0,0,C31,0,0,0,0,0,0,0,0,0,0,0,0,0,0,0,0,0,0,0,0,0,0,0,0,0,0,0,0,0,0,0,0,0,0)';
      BIDIRECTIONAL='TRUE';
      INPUT_LOAD='(-0.01,0.01)';
      OUTPUT_LOAD='(1.0,-1.0)';
    'DDR0_SB_ECC0':
      PIN_NUMBER='(0,0,0,0,0,0,0,B32,0,0,0,0,0,0,0,0,0,0,0,0,0,0,0,0,0,0,0,0,0,0,0,0,0,0,0,0,0,0,0,0,0,0)';
      BIDIRECTIONAL='TRUE';
      INPUT_LOAD='(-0.01,0.01)';
      OUTPUT_LOAD='(1.0,-1.0)';
    'DDR0_SB_PAR':
      PIN_NUMBER='(0,0,0,0,0,0,0,G39,0,0,0,0,0,0,0,0,0,0,0,0,0,0,0,0,0,0,0,0,0,0,0,0,0,0,0,0,0,0,0,0,0,0)';
      OUTPUT_LOAD='(1.0,-1.0)';
    '-DDR1_ALERT':
      PIN_NUMBER='(0,0,0,0,0,0,0,0,AV49,0,0,0,0,0,0,0,0,0,0,0,0,0,0,0,0,0,0,0,0,0,0,0,0,0,0,0,0,0,0,0,0,0)';
      INPUT_LOAD='(-0.01,0.01)';
    'DDR1_A_RSP1':
      PIN_NUMBER='(0,0,0,0,0,0,0,0,AK47,0,0,0,0,0,0,0,0,0,0,0,0,0,0,0,0,0,0,0,0,0,0,0,0,0,0,0,0,0,0,0,0,0)';
      INPUT_LOAD='(-0.01,0.01)';
    'DDR1_A_RSP0':
      PIN_NUMBER='(0,0,0,0,0,0,0,0,AL48,0,0,0,0,0,0,0,0,0,0,0,0,0,0,0,0,0,0,0,0,0,0,0,0,0,0,0,0,0,0,0,0,0)';
      INPUT_LOAD='(-0.01,0.01)';
    'DDR1_B_RSP1':
      PIN_NUMBER='(0,0,0,0,0,0,0,0,AP47,0,0,0,0,0,0,0,0,0,0,0,0,0,0,0,0,0,0,0,0,0,0,0,0,0,0,0,0,0,0,0,0,0)';
      INPUT_LOAD='(-0.01,0.01)';
    'DDR1_B_RSP0':
      PIN_NUMBER='(0,0,0,0,0,0,0,0,AN48,0,0,0,0,0,0,0,0,0,0,0,0,0,0,0,0,0,0,0,0,0,0,0,0,0,0,0,0,0,0,0,0,0)';
      INPUT_LOAD='(-0.01,0.01)';
    'DDR1_CLK_DN1':
      PIN_NUMBER='(0,0,0,0,0,0,0,0,W45,0,0,0,0,0,0,0,0,0,0,0,0,0,0,0,0,0,0,0,0,0,0,0,0,0,0,0,0,0,0,0,0,0)';
      OUTPUT_LOAD='(1.0,-1.0)';
    'DDR1_CLK_DN0':
      PIN_NUMBER='(0,0,0,0,0,0,0,0,R45,0,0,0,0,0,0,0,0,0,0,0,0,0,0,0,0,0,0,0,0,0,0,0,0,0,0,0,0,0,0,0,0,0)';
      OUTPUT_LOAD='(1.0,-1.0)';
    'DDR1_CLK_DP1':
      PIN_NUMBER='(0,0,0,0,0,0,0,0,AA45,0,0,0,0,0,0,0,0,0,0,0,0,0,0,0,0,0,0,0,0,0,0,0,0,0,0,0,0,0,0,0,0,0)';
      OUTPUT_LOAD='(1.0,-1.0)';
    'DDR1_CLK_DP0':
      PIN_NUMBER='(0,0,0,0,0,0,0,0,U45,0,0,0,0,0,0,0,0,0,0,0,0,0,0,0,0,0,0,0,0,0,0,0,0,0,0,0,0,0,0,0,0,0)';
      OUTPUT_LOAD='(1.0,-1.0)';
    'DDR1_SA_CA6':
      PIN_NUMBER='(0,0,0,0,0,0,0,0,Y44,0,0,0,0,0,0,0,0,0,0,0,0,0,0,0,0,0,0,0,0,0,0,0,0,0,0,0,0,0,0,0,0,0)';
      OUTPUT_LOAD='(1.0,-1.0)';
    'DDR1_SA_CA5':
      PIN_NUMBER='(0,0,0,0,0,0,0,0,M47,0,0,0,0,0,0,0,0,0,0,0,0,0,0,0,0,0,0,0,0,0,0,0,0,0,0,0,0,0,0,0,0,0)';
      OUTPUT_LOAD='(1.0,-1.0)';
    'DDR1_SA_CA4':
      PIN_NUMBER='(0,0,0,0,0,0,0,0,K47,0,0,0,0,0,0,0,0,0,0,0,0,0,0,0,0,0,0,0,0,0,0,0,0,0,0,0,0,0,0,0,0,0)';
      OUTPUT_LOAD='(1.0,-1.0)';
    'DDR1_SA_CA3':
      PIN_NUMBER='(0,0,0,0,0,0,0,0,N48,0,0,0,0,0,0,0,0,0,0,0,0,0,0,0,0,0,0,0,0,0,0,0,0,0,0,0,0,0,0,0,0,0)';
      OUTPUT_LOAD='(1.0,-1.0)';
    'DDR1_SA_CA2':
      PIN_NUMBER='(0,0,0,0,0,0,0,0,J48,0,0,0,0,0,0,0,0,0,0,0,0,0,0,0,0,0,0,0,0,0,0,0,0,0,0,0,0,0,0,0,0,0)';
      OUTPUT_LOAD='(1.0,-1.0)';
    'DDR1_SA_CA1':
      PIN_NUMBER='(0,0,0,0,0,0,0,0,P49,0,0,0,0,0,0,0,0,0,0,0,0,0,0,0,0,0,0,0,0,0,0,0,0,0,0,0,0,0,0,0,0,0)';
      OUTPUT_LOAD='(1.0,-1.0)';
    'DDR1_SA_CA0':
      PIN_NUMBER='(0,0,0,0,0,0,0,0,H49,0,0,0,0,0,0,0,0,0,0,0,0,0,0,0,0,0,0,0,0,0,0,0,0,0,0,0,0,0,0,0,0,0)';
      OUTPUT_LOAD='(1.0,-1.0)';
    'DDR1_SA_CS_N3':
      PIN_NUMBER='(0,0,0,0,0,0,0,0,N50,0,0,0,0,0,0,0,0,0,0,0,0,0,0,0,0,0,0,0,0,0,0,0,0,0,0,0,0,0,0,0,0,0)';
      OUTPUT_LOAD='(1.0,-1.0)';
    'DDR1_SA_CS_N2':
      PIN_NUMBER='(0,0,0,0,0,0,0,0,M51,0,0,0,0,0,0,0,0,0,0,0,0,0,0,0,0,0,0,0,0,0,0,0,0,0,0,0,0,0,0,0,0,0)';
      OUTPUT_LOAD='(1.0,-1.0)';
    'DDR1_SA_CS_N1':
      PIN_NUMBER='(0,0,0,0,0,0,0,0,J50,0,0,0,0,0,0,0,0,0,0,0,0,0,0,0,0,0,0,0,0,0,0,0,0,0,0,0,0,0,0,0,0,0)';
      OUTPUT_LOAD='(1.0,-1.0)';
    'DDR1_SA_CS_N0':
      PIN_NUMBER='(0,0,0,0,0,0,0,0,K51,0,0,0,0,0,0,0,0,0,0,0,0,0,0,0,0,0,0,0,0,0,0,0,0,0,0,0,0,0,0,0,0,0)';
      OUTPUT_LOAD='(1.0,-1.0)';
    'DDR1_SA_DQ31':
      PIN_NUMBER='(0,0,0,0,0,0,0,0,W56,0,0,0,0,0,0,0,0,0,0,0,0,0,0,0,0,0,0,0,0,0,0,0,0,0,0,0,0,0,0,0,0,0)';
      BIDIRECTIONAL='TRUE';
      INPUT_LOAD='(-0.01,0.01)';
      OUTPUT_LOAD='(1.0,-1.0)';
    'DDR1_SA_DQ30':
      PIN_NUMBER='(0,0,0,0,0,0,0,0,Y57,0,0,0,0,0,0,0,0,0,0,0,0,0,0,0,0,0,0,0,0,0,0,0,0,0,0,0,0,0,0,0,0,0)';
      BIDIRECTIONAL='TRUE';
      INPUT_LOAD='(-0.01,0.01)';
      OUTPUT_LOAD='(1.0,-1.0)';
    'DDR1_SA_DQ29':
      PIN_NUMBER='(0,0,0,0,0,0,0,0,U56,0,0,0,0,0,0,0,0,0,0,0,0,0,0,0,0,0,0,0,0,0,0,0,0,0,0,0,0,0,0,0,0,0)';
      BIDIRECTIONAL='TRUE';
      INPUT_LOAD='(-0.01,0.01)';
      OUTPUT_LOAD='(1.0,-1.0)';
    'DDR1_SA_DQ28':
      PIN_NUMBER='(0,0,0,0,0,0,0,0,T57,0,0,0,0,0,0,0,0,0,0,0,0,0,0,0,0,0,0,0,0,0,0,0,0,0,0,0,0,0,0,0,0,0)';
      BIDIRECTIONAL='TRUE';
      INPUT_LOAD='(-0.01,0.01)';
      OUTPUT_LOAD='(1.0,-1.0)';
    'DDR1_SA_DQ27':
      PIN_NUMBER='(0,0,0,0,0,0,0,0,Y59,0,0,0,0,0,0,0,0,0,0,0,0,0,0,0,0,0,0,0,0,0,0,0,0,0,0,0,0,0,0,0,0,0)';
      BIDIRECTIONAL='TRUE';
      INPUT_LOAD='(-0.01,0.01)';
      OUTPUT_LOAD='(1.0,-1.0)';
    'DDR1_SA_DQ26':
      PIN_NUMBER='(0,0,0,0,0,0,0,0,W60,0,0,0,0,0,0,0,0,0,0,0,0,0,0,0,0,0,0,0,0,0,0,0,0,0,0,0,0,0,0,0,0,0)';
      BIDIRECTIONAL='TRUE';
      INPUT_LOAD='(-0.01,0.01)';
      OUTPUT_LOAD='(1.0,-1.0)';
    'DDR1_SA_DQ25':
      PIN_NUMBER='(0,0,0,0,0,0,0,0,T59,0,0,0,0,0,0,0,0,0,0,0,0,0,0,0,0,0,0,0,0,0,0,0,0,0,0,0,0,0,0,0,0,0)';
      BIDIRECTIONAL='TRUE';
      INPUT_LOAD='(-0.01,0.01)';
      OUTPUT_LOAD='(1.0,-1.0)';
    'DDR1_SA_DQ24':
      PIN_NUMBER='(0,0,0,0,0,0,0,0,U60,0,0,0,0,0,0,0,0,0,0,0,0,0,0,0,0,0,0,0,0,0,0,0,0,0,0,0,0,0,0,0,0,0)';
      BIDIRECTIONAL='TRUE';
      INPUT_LOAD='(-0.01,0.01)';
      OUTPUT_LOAD='(1.0,-1.0)';
    'DDR1_SA_DQ23':
      PIN_NUMBER='(0,0,0,0,0,0,0,0,M59,0,0,0,0,0,0,0,0,0,0,0,0,0,0,0,0,0,0,0,0,0,0,0,0,0,0,0,0,0,0,0,0,0)';
      BIDIRECTIONAL='TRUE';
      INPUT_LOAD='(-0.01,0.01)';
      OUTPUT_LOAD='(1.0,-1.0)';
    'DDR1_SA_DQ22':
      PIN_NUMBER='(0,0,0,0,0,0,0,0,N60,0,0,0,0,0,0,0,0,0,0,0,0,0,0,0,0,0,0,0,0,0,0,0,0,0,0,0,0,0,0,0,0,0)';
      BIDIRECTIONAL='TRUE';
      INPUT_LOAD='(-0.01,0.01)';
      OUTPUT_LOAD='(1.0,-1.0)';
    'DDR1_SA_DQ21':
      PIN_NUMBER='(0,0,0,0,0,0,0,0,K59,0,0,0,0,0,0,0,0,0,0,0,0,0,0,0,0,0,0,0,0,0,0,0,0,0,0,0,0,0,0,0,0,0)';
      BIDIRECTIONAL='TRUE';
      INPUT_LOAD='(-0.01,0.01)';
      OUTPUT_LOAD='(1.0,-1.0)';
    'DDR1_SA_DQ20':
      PIN_NUMBER='(0,0,0,0,0,0,0,0,J60,0,0,0,0,0,0,0,0,0,0,0,0,0,0,0,0,0,0,0,0,0,0,0,0,0,0,0,0,0,0,0,0,0)';
      BIDIRECTIONAL='TRUE';
      INPUT_LOAD='(-0.01,0.01)';
      OUTPUT_LOAD='(1.0,-1.0)';
    'DDR1_SA_DQ19':
      PIN_NUMBER='(0,0,0,0,0,0,0,0,N62,0,0,0,0,0,0,0,0,0,0,0,0,0,0,0,0,0,0,0,0,0,0,0,0,0,0,0,0,0,0,0,0,0)';
      BIDIRECTIONAL='TRUE';
      INPUT_LOAD='(-0.01,0.01)';
      OUTPUT_LOAD='(1.0,-1.0)';
    'DDR1_SA_DQ18':
      PIN_NUMBER='(0,0,0,0,0,0,0,0,M63,0,0,0,0,0,0,0,0,0,0,0,0,0,0,0,0,0,0,0,0,0,0,0,0,0,0,0,0,0,0,0,0,0)';
      BIDIRECTIONAL='TRUE';
      INPUT_LOAD='(-0.01,0.01)';
      OUTPUT_LOAD='(1.0,-1.0)';
    'DDR1_SA_DQ17':
      PIN_NUMBER='(0,0,0,0,0,0,0,0,J62,0,0,0,0,0,0,0,0,0,0,0,0,0,0,0,0,0,0,0,0,0,0,0,0,0,0,0,0,0,0,0,0,0)';
      BIDIRECTIONAL='TRUE';
      INPUT_LOAD='(-0.01,0.01)';
      OUTPUT_LOAD='(1.0,-1.0)';
    'DDR1_SA_DQ16':
      PIN_NUMBER='(0,0,0,0,0,0,0,0,K63,0,0,0,0,0,0,0,0,0,0,0,0,0,0,0,0,0,0,0,0,0,0,0,0,0,0,0,0,0,0,0,0,0)';
      BIDIRECTIONAL='TRUE';
      INPUT_LOAD='(-0.01,0.01)';
      OUTPUT_LOAD='(1.0,-1.0)';
    'DDR1_SA_DQ15':
      PIN_NUMBER='(0,0,0,0,0,0,0,0,W68,0,0,0,0,0,0,0,0,0,0,0,0,0,0,0,0,0,0,0,0,0,0,0,0,0,0,0,0,0,0,0,0,0)';
      BIDIRECTIONAL='TRUE';
      INPUT_LOAD='(-0.01,0.01)';
      OUTPUT_LOAD='(1.0,-1.0)';
    'DDR1_SA_DQ14':
      PIN_NUMBER='(0,0,0,0,0,0,0,0,Y69,0,0,0,0,0,0,0,0,0,0,0,0,0,0,0,0,0,0,0,0,0,0,0,0,0,0,0,0,0,0,0,0,0)';
      BIDIRECTIONAL='TRUE';
      INPUT_LOAD='(-0.01,0.01)';
      OUTPUT_LOAD='(1.0,-1.0)';
    'DDR1_SA_DQ13':
      PIN_NUMBER='(0,0,0,0,0,0,0,0,U68,0,0,0,0,0,0,0,0,0,0,0,0,0,0,0,0,0,0,0,0,0,0,0,0,0,0,0,0,0,0,0,0,0)';
      BIDIRECTIONAL='TRUE';
      INPUT_LOAD='(-0.01,0.01)';
      OUTPUT_LOAD='(1.0,-1.0)';
    'DDR1_SA_DQ12':
      PIN_NUMBER='(0,0,0,0,0,0,0,0,T69,0,0,0,0,0,0,0,0,0,0,0,0,0,0,0,0,0,0,0,0,0,0,0,0,0,0,0,0,0,0,0,0,0)';
      BIDIRECTIONAL='TRUE';
      INPUT_LOAD='(-0.01,0.01)';
      OUTPUT_LOAD='(1.0,-1.0)';
    'DDR1_SA_DQ11':
      PIN_NUMBER='(0,0,0,0,0,0,0,0,Y71,0,0,0,0,0,0,0,0,0,0,0,0,0,0,0,0,0,0,0,0,0,0,0,0,0,0,0,0,0,0,0,0,0)';
      BIDIRECTIONAL='TRUE';
      INPUT_LOAD='(-0.01,0.01)';
      OUTPUT_LOAD='(1.0,-1.0)';
    'DDR1_SA_DQ10':
      PIN_NUMBER='(0,0,0,0,0,0,0,0,W72,0,0,0,0,0,0,0,0,0,0,0,0,0,0,0,0,0,0,0,0,0,0,0,0,0,0,0,0,0,0,0,0,0)';
      BIDIRECTIONAL='TRUE';
      INPUT_LOAD='(-0.01,0.01)';
      OUTPUT_LOAD='(1.0,-1.0)';
    'DDR1_SA_DQ9':
      PIN_NUMBER='(0,0,0,0,0,0,0,0,T71,0,0,0,0,0,0,0,0,0,0,0,0,0,0,0,0,0,0,0,0,0,0,0,0,0,0,0,0,0,0,0,0,0)';
      BIDIRECTIONAL='TRUE';
      INPUT_LOAD='(-0.01,0.01)';
      OUTPUT_LOAD='(1.0,-1.0)';
    'DDR1_SA_DQ8':
      PIN_NUMBER='(0,0,0,0,0,0,0,0,U72,0,0,0,0,0,0,0,0,0,0,0,0,0,0,0,0,0,0,0,0,0,0,0,0,0,0,0,0,0,0,0,0,0)';
      BIDIRECTIONAL='TRUE';
      INPUT_LOAD='(-0.01,0.01)';
      OUTPUT_LOAD='(1.0,-1.0)';
    'DDR1_SA_DQ7':
      PIN_NUMBER='(0,0,0,0,0,0,0,0,M71,0,0,0,0,0,0,0,0,0,0,0,0,0,0,0,0,0,0,0,0,0,0,0,0,0,0,0,0,0,0,0,0,0)';
      BIDIRECTIONAL='TRUE';
      INPUT_LOAD='(-0.01,0.01)';
      OUTPUT_LOAD='(1.0,-1.0)';
    'DDR1_SA_DQ6':
      PIN_NUMBER='(0,0,0,0,0,0,0,0,N72,0,0,0,0,0,0,0,0,0,0,0,0,0,0,0,0,0,0,0,0,0,0,0,0,0,0,0,0,0,0,0,0,0)';
      BIDIRECTIONAL='TRUE';
      INPUT_LOAD='(-0.01,0.01)';
      OUTPUT_LOAD='(1.0,-1.0)';
    'DDR1_SA_DQ5':
      PIN_NUMBER='(0,0,0,0,0,0,0,0,K71,0,0,0,0,0,0,0,0,0,0,0,0,0,0,0,0,0,0,0,0,0,0,0,0,0,0,0,0,0,0,0,0,0)';
      BIDIRECTIONAL='TRUE';
      INPUT_LOAD='(-0.01,0.01)';
      OUTPUT_LOAD='(1.0,-1.0)';
    'DDR1_SA_DQ4':
      PIN_NUMBER='(0,0,0,0,0,0,0,0,J72,0,0,0,0,0,0,0,0,0,0,0,0,0,0,0,0,0,0,0,0,0,0,0,0,0,0,0,0,0,0,0,0,0)';
      BIDIRECTIONAL='TRUE';
      INPUT_LOAD='(-0.01,0.01)';
      OUTPUT_LOAD='(1.0,-1.0)';
    'DDR1_SA_DQ3':
      PIN_NUMBER='(0,0,0,0,0,0,0,0,N74,0,0,0,0,0,0,0,0,0,0,0,0,0,0,0,0,0,0,0,0,0,0,0,0,0,0,0,0,0,0,0,0,0)';
      BIDIRECTIONAL='TRUE';
      INPUT_LOAD='(-0.01,0.01)';
      OUTPUT_LOAD='(1.0,-1.0)';
    'DDR1_SA_DQ2':
      PIN_NUMBER='(0,0,0,0,0,0,0,0,M75,0,0,0,0,0,0,0,0,0,0,0,0,0,0,0,0,0,0,0,0,0,0,0,0,0,0,0,0,0,0,0,0,0)';
      BIDIRECTIONAL='TRUE';
      INPUT_LOAD='(-0.01,0.01)';
      OUTPUT_LOAD='(1.0,-1.0)';
    'DDR1_SA_DQ1':
      PIN_NUMBER='(0,0,0,0,0,0,0,0,J74,0,0,0,0,0,0,0,0,0,0,0,0,0,0,0,0,0,0,0,0,0,0,0,0,0,0,0,0,0,0,0,0,0)';
      BIDIRECTIONAL='TRUE';
      INPUT_LOAD='(-0.01,0.01)';
      OUTPUT_LOAD='(1.0,-1.0)';
    'DDR1_SA_DQ0':
      PIN_NUMBER='(0,0,0,0,0,0,0,0,K75,0,0,0,0,0,0,0,0,0,0,0,0,0,0,0,0,0,0,0,0,0,0,0,0,0,0,0,0,0,0,0,0,0)';
      BIDIRECTIONAL='TRUE';
      INPUT_LOAD='(-0.01,0.01)';
      OUTPUT_LOAD='(1.0,-1.0)';
    'DDR1_SA_DQS_DN9':
      PIN_NUMBER='(0,0,0,0,0,0,0,0,M55,0,0,0,0,0,0,0,0,0,0,0,0,0,0,0,0,0,0,0,0,0,0,0,0,0,0,0,0,0,0,0,0,0)';
      BIDIRECTIONAL='TRUE';
      INPUT_LOAD='(-0.01,0.01)';
      OUTPUT_LOAD='(1.0,-1.0)';
    'DDR1_SA_DQS_DN8':
      PIN_NUMBER='(0,0,0,0,0,0,0,0,AA58,0,0,0,0,0,0,0,0,0,0,0,0,0,0,0,0,0,0,0,0,0,0,0,0,0,0,0,0,0,0,0,0,0)';
      BIDIRECTIONAL='TRUE';
      INPUT_LOAD='(-0.01,0.01)';
      OUTPUT_LOAD='(1.0,-1.0)';
    'DDR1_SA_DQS_DN7':
      PIN_NUMBER='(0,0,0,0,0,0,0,0,M61,0,0,0,0,0,0,0,0,0,0,0,0,0,0,0,0,0,0,0,0,0,0,0,0,0,0,0,0,0,0,0,0,0)';
      BIDIRECTIONAL='TRUE';
      INPUT_LOAD='(-0.01,0.01)';
      OUTPUT_LOAD='(1.0,-1.0)';
    'DDR1_SA_DQS_DN6':
      PIN_NUMBER='(0,0,0,0,0,0,0,0,AA70,0,0,0,0,0,0,0,0,0,0,0,0,0,0,0,0,0,0,0,0,0,0,0,0,0,0,0,0,0,0,0,0,0)';
      BIDIRECTIONAL='TRUE';
      INPUT_LOAD='(-0.01,0.01)';
      OUTPUT_LOAD='(1.0,-1.0)';
    'DDR1_SA_DQS_DN5':
      PIN_NUMBER='(0,0,0,0,0,0,0,0,M73,0,0,0,0,0,0,0,0,0,0,0,0,0,0,0,0,0,0,0,0,0,0,0,0,0,0,0,0,0,0,0,0,0)';
      BIDIRECTIONAL='TRUE';
      INPUT_LOAD='(-0.01,0.01)';
      OUTPUT_LOAD='(1.0,-1.0)';
    'DDR1_SA_DQS_DN4':
      PIN_NUMBER='(0,0,0,0,0,0,0,0,H55,0,0,0,0,0,0,0,0,0,0,0,0,0,0,0,0,0,0,0,0,0,0,0,0,0,0,0,0,0,0,0,0,0)';
      BIDIRECTIONAL='TRUE';
      INPUT_LOAD='(-0.01,0.01)';
      OUTPUT_LOAD='(1.0,-1.0)';
    'DDR1_SA_DQS_DN3':
      PIN_NUMBER='(0,0,0,0,0,0,0,0,R58,0,0,0,0,0,0,0,0,0,0,0,0,0,0,0,0,0,0,0,0,0,0,0,0,0,0,0,0,0,0,0,0,0)';
      BIDIRECTIONAL='TRUE';
      INPUT_LOAD='(-0.01,0.01)';
      OUTPUT_LOAD='(1.0,-1.0)';
    'DDR1_SA_DQS_DN2':
      PIN_NUMBER='(0,0,0,0,0,0,0,0,H61,0,0,0,0,0,0,0,0,0,0,0,0,0,0,0,0,0,0,0,0,0,0,0,0,0,0,0,0,0,0,0,0,0)';
      BIDIRECTIONAL='TRUE';
      INPUT_LOAD='(-0.01,0.01)';
      OUTPUT_LOAD='(1.0,-1.0)';
    'DDR1_SA_DQS_DN1':
      PIN_NUMBER='(0,0,0,0,0,0,0,0,R70,0,0,0,0,0,0,0,0,0,0,0,0,0,0,0,0,0,0,0,0,0,0,0,0,0,0,0,0,0,0,0,0,0)';
      BIDIRECTIONAL='TRUE';
      INPUT_LOAD='(-0.01,0.01)';
      OUTPUT_LOAD='(1.0,-1.0)';
    'DDR1_SA_DQS_DN0':
      PIN_NUMBER='(0,0,0,0,0,0,0,0,H73,0,0,0,0,0,0,0,0,0,0,0,0,0,0,0,0,0,0,0,0,0,0,0,0,0,0,0,0,0,0,0,0,0)';
      BIDIRECTIONAL='TRUE';
      INPUT_LOAD='(-0.01,0.01)';
      OUTPUT_LOAD='(1.0,-1.0)';
    'DDR1_SA_DQS_DP9':
      PIN_NUMBER='(0,0,0,0,0,0,0,0,P55,0,0,0,0,0,0,0,0,0,0,0,0,0,0,0,0,0,0,0,0,0,0,0,0,0,0,0,0,0,0,0,0,0)';
      BIDIRECTIONAL='TRUE';
      INPUT_LOAD='(-0.01,0.01)';
      OUTPUT_LOAD='(1.0,-1.0)';
    'DDR1_SA_DQS_DP8':
      PIN_NUMBER='(0,0,0,0,0,0,0,0,W58,0,0,0,0,0,0,0,0,0,0,0,0,0,0,0,0,0,0,0,0,0,0,0,0,0,0,0,0,0,0,0,0,0)';
      BIDIRECTIONAL='TRUE';
      INPUT_LOAD='(-0.01,0.01)';
      OUTPUT_LOAD='(1.0,-1.0)';
    'DDR1_SA_DQS_DP7':
      PIN_NUMBER='(0,0,0,0,0,0,0,0,P61,0,0,0,0,0,0,0,0,0,0,0,0,0,0,0,0,0,0,0,0,0,0,0,0,0,0,0,0,0,0,0,0,0)';
      BIDIRECTIONAL='TRUE';
      INPUT_LOAD='(-0.01,0.01)';
      OUTPUT_LOAD='(1.0,-1.0)';
    'DDR1_SA_DQS_DP6':
      PIN_NUMBER='(0,0,0,0,0,0,0,0,W70,0,0,0,0,0,0,0,0,0,0,0,0,0,0,0,0,0,0,0,0,0,0,0,0,0,0,0,0,0,0,0,0,0)';
      BIDIRECTIONAL='TRUE';
      INPUT_LOAD='(-0.01,0.01)';
      OUTPUT_LOAD='(1.0,-1.0)';
    'DDR1_SA_DQS_DP5':
      PIN_NUMBER='(0,0,0,0,0,0,0,0,P73,0,0,0,0,0,0,0,0,0,0,0,0,0,0,0,0,0,0,0,0,0,0,0,0,0,0,0,0,0,0,0,0,0)';
      BIDIRECTIONAL='TRUE';
      INPUT_LOAD='(-0.01,0.01)';
      OUTPUT_LOAD='(1.0,-1.0)';
    'DDR1_SA_DQS_DP4':
      PIN_NUMBER='(0,0,0,0,0,0,0,0,K55,0,0,0,0,0,0,0,0,0,0,0,0,0,0,0,0,0,0,0,0,0,0,0,0,0,0,0,0,0,0,0,0,0)';
      BIDIRECTIONAL='TRUE';
      INPUT_LOAD='(-0.01,0.01)';
      OUTPUT_LOAD='(1.0,-1.0)';
    'DDR1_SA_DQS_DP3':
      PIN_NUMBER='(0,0,0,0,0,0,0,0,U58,0,0,0,0,0,0,0,0,0,0,0,0,0,0,0,0,0,0,0,0,0,0,0,0,0,0,0,0,0,0,0,0,0)';
      BIDIRECTIONAL='TRUE';
      INPUT_LOAD='(-0.01,0.01)';
      OUTPUT_LOAD='(1.0,-1.0)';
    'DDR1_SA_DQS_DP2':
      PIN_NUMBER='(0,0,0,0,0,0,0,0,K61,0,0,0,0,0,0,0,0,0,0,0,0,0,0,0,0,0,0,0,0,0,0,0,0,0,0,0,0,0,0,0,0,0)';
      BIDIRECTIONAL='TRUE';
      INPUT_LOAD='(-0.01,0.01)';
      OUTPUT_LOAD='(1.0,-1.0)';
    'DDR1_SA_DQS_DP1':
      PIN_NUMBER='(0,0,0,0,0,0,0,0,U70,0,0,0,0,0,0,0,0,0,0,0,0,0,0,0,0,0,0,0,0,0,0,0,0,0,0,0,0,0,0,0,0,0)';
      BIDIRECTIONAL='TRUE';
      INPUT_LOAD='(-0.01,0.01)';
      OUTPUT_LOAD='(1.0,-1.0)';
    'DDR1_SA_DQS_DP0':
      PIN_NUMBER='(0,0,0,0,0,0,0,0,K73,0,0,0,0,0,0,0,0,0,0,0,0,0,0,0,0,0,0,0,0,0,0,0,0,0,0,0,0,0,0,0,0,0)';
      BIDIRECTIONAL='TRUE';
      INPUT_LOAD='(-0.01,0.01)';
      OUTPUT_LOAD='(1.0,-1.0)';
    'DDR1_SA_ECC7':
      PIN_NUMBER='(0,0,0,0,0,0,0,0,M53,0,0,0,0,0,0,0,0,0,0,0,0,0,0,0,0,0,0,0,0,0,0,0,0,0,0,0,0,0,0,0,0,0)';
      BIDIRECTIONAL='TRUE';
      INPUT_LOAD='(-0.01,0.01)';
      OUTPUT_LOAD='(1.0,-1.0)';
    'DDR1_SA_ECC6':
      PIN_NUMBER='(0,0,0,0,0,0,0,0,N54,0,0,0,0,0,0,0,0,0,0,0,0,0,0,0,0,0,0,0,0,0,0,0,0,0,0,0,0,0,0,0,0,0)';
      BIDIRECTIONAL='TRUE';
      INPUT_LOAD='(-0.01,0.01)';
      OUTPUT_LOAD='(1.0,-1.0)';
    'DDR1_SA_ECC5':
      PIN_NUMBER='(0,0,0,0,0,0,0,0,K53,0,0,0,0,0,0,0,0,0,0,0,0,0,0,0,0,0,0,0,0,0,0,0,0,0,0,0,0,0,0,0,0,0)';
      BIDIRECTIONAL='TRUE';
      INPUT_LOAD='(-0.01,0.01)';
      OUTPUT_LOAD='(1.0,-1.0)';
    'DDR1_SA_ECC4':
      PIN_NUMBER='(0,0,0,0,0,0,0,0,J54,0,0,0,0,0,0,0,0,0,0,0,0,0,0,0,0,0,0,0,0,0,0,0,0,0,0,0,0,0,0,0,0,0)';
      BIDIRECTIONAL='TRUE';
      INPUT_LOAD='(-0.01,0.01)';
      OUTPUT_LOAD='(1.0,-1.0)';
    'DDR1_SA_ECC3':
      PIN_NUMBER='(0,0,0,0,0,0,0,0,N56,0,0,0,0,0,0,0,0,0,0,0,0,0,0,0,0,0,0,0,0,0,0,0,0,0,0,0,0,0,0,0,0,0)';
      BIDIRECTIONAL='TRUE';
      INPUT_LOAD='(-0.01,0.01)';
      OUTPUT_LOAD='(1.0,-1.0)';
    'DDR1_SA_ECC2':
      PIN_NUMBER='(0,0,0,0,0,0,0,0,M57,0,0,0,0,0,0,0,0,0,0,0,0,0,0,0,0,0,0,0,0,0,0,0,0,0,0,0,0,0,0,0,0,0)';
      BIDIRECTIONAL='TRUE';
      INPUT_LOAD='(-0.01,0.01)';
      OUTPUT_LOAD='(1.0,-1.0)';
    'DDR1_SA_ECC1':
      PIN_NUMBER='(0,0,0,0,0,0,0,0,J56,0,0,0,0,0,0,0,0,0,0,0,0,0,0,0,0,0,0,0,0,0,0,0,0,0,0,0,0,0,0,0,0,0)';
      BIDIRECTIONAL='TRUE';
      INPUT_LOAD='(-0.01,0.01)';
      OUTPUT_LOAD='(1.0,-1.0)';
    'DDR1_SA_ECC0':
      PIN_NUMBER='(0,0,0,0,0,0,0,0,K57,0,0,0,0,0,0,0,0,0,0,0,0,0,0,0,0,0,0,0,0,0,0,0,0,0,0,0,0,0,0,0,0,0)';
      BIDIRECTIONAL='TRUE';
      INPUT_LOAD='(-0.01,0.01)';
      OUTPUT_LOAD='(1.0,-1.0)';
    'DDR1_SA_PAR':
      PIN_NUMBER='(0,0,0,0,0,0,0,0,W43,0,0,0,0,0,0,0,0,0,0,0,0,0,0,0,0,0,0,0,0,0,0,0,0,0,0,0,0,0,0,0,0,0)';
      OUTPUT_LOAD='(1.0,-1.0)';
    'DDR1_SB_CA6':
      PIN_NUMBER='(0,0,0,0,0,0,0,0,H42,0,0,0,0,0,0,0,0,0,0,0,0,0,0,0,0,0,0,0,0,0,0,0,0,0,0,0,0,0,0,0,0,0)';
      OUTPUT_LOAD='(1.0,-1.0)';
    'DDR1_SB_CA5':
      PIN_NUMBER='(0,0,0,0,0,0,0,0,N43,0,0,0,0,0,0,0,0,0,0,0,0,0,0,0,0,0,0,0,0,0,0,0,0,0,0,0,0,0,0,0,0,0)';
      OUTPUT_LOAD='(1.0,-1.0)';
    'DDR1_SB_CA4':
      PIN_NUMBER='(0,0,0,0,0,0,0,0,J43,0,0,0,0,0,0,0,0,0,0,0,0,0,0,0,0,0,0,0,0,0,0,0,0,0,0,0,0,0,0,0,0,0)';
      OUTPUT_LOAD='(1.0,-1.0)';
    'DDR1_SB_CA3':
      PIN_NUMBER='(0,0,0,0,0,0,0,0,M44,0,0,0,0,0,0,0,0,0,0,0,0,0,0,0,0,0,0,0,0,0,0,0,0,0,0,0,0,0,0,0,0,0)';
      OUTPUT_LOAD='(1.0,-1.0)';
    'DDR1_SB_CA2':
      PIN_NUMBER='(0,0,0,0,0,0,0,0,K44,0,0,0,0,0,0,0,0,0,0,0,0,0,0,0,0,0,0,0,0,0,0,0,0,0,0,0,0,0,0,0,0,0)';
      OUTPUT_LOAD='(1.0,-1.0)';
    'DDR1_SB_CA1':
      PIN_NUMBER='(0,0,0,0,0,0,0,0,U43,0,0,0,0,0,0,0,0,0,0,0,0,0,0,0,0,0,0,0,0,0,0,0,0,0,0,0,0,0,0,0,0,0)';
      OUTPUT_LOAD='(1.0,-1.0)';
    'DDR1_SB_CA0':
      PIN_NUMBER='(0,0,0,0,0,0,0,0,T44,0,0,0,0,0,0,0,0,0,0,0,0,0,0,0,0,0,0,0,0,0,0,0,0,0,0,0,0,0,0,0,0,0)';
      OUTPUT_LOAD='(1.0,-1.0)';
    'DDR1_SB_CS_N3':
      PIN_NUMBER='(0,0,0,0,0,0,0,0,M40,0,0,0,0,0,0,0,0,0,0,0,0,0,0,0,0,0,0,0,0,0,0,0,0,0,0,0,0,0,0,0,0,0)';
      OUTPUT_LOAD='(1.0,-1.0)';
    'DDR1_SB_CS_N2':
      PIN_NUMBER='(0,0,0,0,0,0,0,0,N41,0,0,0,0,0,0,0,0,0,0,0,0,0,0,0,0,0,0,0,0,0,0,0,0,0,0,0,0,0,0,0,0,0)';
      OUTPUT_LOAD='(1.0,-1.0)';
    'DDR1_SB_CS_N1':
      PIN_NUMBER='(0,0,0,0,0,0,0,0,K40,0,0,0,0,0,0,0,0,0,0,0,0,0,0,0,0,0,0,0,0,0,0,0,0,0,0,0,0,0,0,0,0,0)';
      OUTPUT_LOAD='(1.0,-1.0)';
    'DDR1_SB_CS_N0':
      PIN_NUMBER='(0,0,0,0,0,0,0,0,J41,0,0,0,0,0,0,0,0,0,0,0,0,0,0,0,0,0,0,0,0,0,0,0,0,0,0,0,0,0,0,0,0,0)';
      OUTPUT_LOAD='(1.0,-1.0)';
    'DDR1_SB_DQ31':
      PIN_NUMBER='(0,0,0,0,0,0,0,0,F14,0,0,0,0,0,0,0,0,0,0,0,0,0,0,0,0,0,0,0,0,0,0,0,0,0,0,0,0,0,0,0,0,0)';
      BIDIRECTIONAL='TRUE';
      INPUT_LOAD='(-0.01,0.01)';
      OUTPUT_LOAD='(1.0,-1.0)';
    'DDR1_SB_DQ30':
      PIN_NUMBER='(0,0,0,0,0,0,0,0,B14,0,0,0,0,0,0,0,0,0,0,0,0,0,0,0,0,0,0,0,0,0,0,0,0,0,0,0,0,0,0,0,0,0)';
      BIDIRECTIONAL='TRUE';
      INPUT_LOAD='(-0.01,0.01)';
      OUTPUT_LOAD='(1.0,-1.0)';
    'DDR1_SB_DQ29':
      PIN_NUMBER='(0,0,0,0,0,0,0,0,E13,0,0,0,0,0,0,0,0,0,0,0,0,0,0,0,0,0,0,0,0,0,0,0,0,0,0,0,0,0,0,0,0,0)';
      BIDIRECTIONAL='TRUE';
      INPUT_LOAD='(-0.01,0.01)';
      OUTPUT_LOAD='(1.0,-1.0)';
    'DDR1_SB_DQ28':
      PIN_NUMBER='(0,0,0,0,0,0,0,0,C13,0,0,0,0,0,0,0,0,0,0,0,0,0,0,0,0,0,0,0,0,0,0,0,0,0,0,0,0,0,0,0,0,0)';
      BIDIRECTIONAL='TRUE';
      INPUT_LOAD='(-0.01,0.01)';
      OUTPUT_LOAD='(1.0,-1.0)';
    'DDR1_SB_DQ27':
      PIN_NUMBER='(0,0,0,0,0,0,0,0,F16,0,0,0,0,0,0,0,0,0,0,0,0,0,0,0,0,0,0,0,0,0,0,0,0,0,0,0,0,0,0,0,0,0)';
      BIDIRECTIONAL='TRUE';
      INPUT_LOAD='(-0.01,0.01)';
      OUTPUT_LOAD='(1.0,-1.0)';
    'DDR1_SB_DQ26':
      PIN_NUMBER='(0,0,0,0,0,0,0,0,E17,0,0,0,0,0,0,0,0,0,0,0,0,0,0,0,0,0,0,0,0,0,0,0,0,0,0,0,0,0,0,0,0,0)';
      BIDIRECTIONAL='TRUE';
      INPUT_LOAD='(-0.01,0.01)';
      OUTPUT_LOAD='(1.0,-1.0)';
    'DDR1_SB_DQ25':
      PIN_NUMBER='(0,0,0,0,0,0,0,0,B16,0,0,0,0,0,0,0,0,0,0,0,0,0,0,0,0,0,0,0,0,0,0,0,0,0,0,0,0,0,0,0,0,0)';
      BIDIRECTIONAL='TRUE';
      INPUT_LOAD='(-0.01,0.01)';
      OUTPUT_LOAD='(1.0,-1.0)';
    'DDR1_SB_DQ24':
      PIN_NUMBER='(0,0,0,0,0,0,0,0,C17,0,0,0,0,0,0,0,0,0,0,0,0,0,0,0,0,0,0,0,0,0,0,0,0,0,0,0,0,0,0,0,0,0)';
      BIDIRECTIONAL='TRUE';
      INPUT_LOAD='(-0.01,0.01)';
      OUTPUT_LOAD='(1.0,-1.0)';
    'DDR1_SB_DQ23':
      PIN_NUMBER='(0,0,0,0,0,0,0,0,M16,0,0,0,0,0,0,0,0,0,0,0,0,0,0,0,0,0,0,0,0,0,0,0,0,0,0,0,0,0,0,0,0,0)';
      BIDIRECTIONAL='TRUE';
      INPUT_LOAD='(-0.01,0.01)';
      OUTPUT_LOAD='(1.0,-1.0)';
    'DDR1_SB_DQ22':
      PIN_NUMBER='(0,0,0,0,0,0,0,0,N17,0,0,0,0,0,0,0,0,0,0,0,0,0,0,0,0,0,0,0,0,0,0,0,0,0,0,0,0,0,0,0,0,0)';
      BIDIRECTIONAL='TRUE';
      INPUT_LOAD='(-0.01,0.01)';
      OUTPUT_LOAD='(1.0,-1.0)';
    'DDR1_SB_DQ21':
      PIN_NUMBER='(0,0,0,0,0,0,0,0,K16,0,0,0,0,0,0,0,0,0,0,0,0,0,0,0,0,0,0,0,0,0,0,0,0,0,0,0,0,0,0,0,0,0)';
      BIDIRECTIONAL='TRUE';
      INPUT_LOAD='(-0.01,0.01)';
      OUTPUT_LOAD='(1.0,-1.0)';
    'DDR1_SB_DQ20':
      PIN_NUMBER='(0,0,0,0,0,0,0,0,J17,0,0,0,0,0,0,0,0,0,0,0,0,0,0,0,0,0,0,0,0,0,0,0,0,0,0,0,0,0,0,0,0,0)';
      BIDIRECTIONAL='TRUE';
      INPUT_LOAD='(-0.01,0.01)';
      OUTPUT_LOAD='(1.0,-1.0)';
    'DDR1_SB_DQ19':
      PIN_NUMBER='(0,0,0,0,0,0,0,0,N19,0,0,0,0,0,0,0,0,0,0,0,0,0,0,0,0,0,0,0,0,0,0,0,0,0,0,0,0,0,0,0,0,0)';
      BIDIRECTIONAL='TRUE';
      INPUT_LOAD='(-0.01,0.01)';
      OUTPUT_LOAD='(1.0,-1.0)';
    'DDR1_SB_DQ18':
      PIN_NUMBER='(0,0,0,0,0,0,0,0,M20,0,0,0,0,0,0,0,0,0,0,0,0,0,0,0,0,0,0,0,0,0,0,0,0,0,0,0,0,0,0,0,0,0)';
      BIDIRECTIONAL='TRUE';
      INPUT_LOAD='(-0.01,0.01)';
      OUTPUT_LOAD='(1.0,-1.0)';
    'DDR1_SB_DQ17':
      PIN_NUMBER='(0,0,0,0,0,0,0,0,J19,0,0,0,0,0,0,0,0,0,0,0,0,0,0,0,0,0,0,0,0,0,0,0,0,0,0,0,0,0,0,0,0,0)';
      BIDIRECTIONAL='TRUE';
      INPUT_LOAD='(-0.01,0.01)';
      OUTPUT_LOAD='(1.0,-1.0)';
    'DDR1_SB_DQ16':
      PIN_NUMBER='(0,0,0,0,0,0,0,0,K20,0,0,0,0,0,0,0,0,0,0,0,0,0,0,0,0,0,0,0,0,0,0,0,0,0,0,0,0,0,0,0,0,0)';
      BIDIRECTIONAL='TRUE';
      INPUT_LOAD='(-0.01,0.01)';
      OUTPUT_LOAD='(1.0,-1.0)';
    'DDR1_SB_DQ15':
      PIN_NUMBER='(0,0,0,0,0,0,0,0,M22,0,0,0,0,0,0,0,0,0,0,0,0,0,0,0,0,0,0,0,0,0,0,0,0,0,0,0,0,0,0,0,0,0)';
      BIDIRECTIONAL='TRUE';
      INPUT_LOAD='(-0.01,0.01)';
      OUTPUT_LOAD='(1.0,-1.0)';
    'DDR1_SB_DQ14':
      PIN_NUMBER='(0,0,0,0,0,0,0,0,N23,0,0,0,0,0,0,0,0,0,0,0,0,0,0,0,0,0,0,0,0,0,0,0,0,0,0,0,0,0,0,0,0,0)';
      BIDIRECTIONAL='TRUE';
      INPUT_LOAD='(-0.01,0.01)';
      OUTPUT_LOAD='(1.0,-1.0)';
    'DDR1_SB_DQ13':
      PIN_NUMBER='(0,0,0,0,0,0,0,0,K22,0,0,0,0,0,0,0,0,0,0,0,0,0,0,0,0,0,0,0,0,0,0,0,0,0,0,0,0,0,0,0,0,0)';
      BIDIRECTIONAL='TRUE';
      INPUT_LOAD='(-0.01,0.01)';
      OUTPUT_LOAD='(1.0,-1.0)';
    'DDR1_SB_DQ12':
      PIN_NUMBER='(0,0,0,0,0,0,0,0,J23,0,0,0,0,0,0,0,0,0,0,0,0,0,0,0,0,0,0,0,0,0,0,0,0,0,0,0,0,0,0,0,0,0)';
      BIDIRECTIONAL='TRUE';
      INPUT_LOAD='(-0.01,0.01)';
      OUTPUT_LOAD='(1.0,-1.0)';
    'DDR1_SB_DQ11':
      PIN_NUMBER='(0,0,0,0,0,0,0,0,N25,0,0,0,0,0,0,0,0,0,0,0,0,0,0,0,0,0,0,0,0,0,0,0,0,0,0,0,0,0,0,0,0,0)';
      BIDIRECTIONAL='TRUE';
      INPUT_LOAD='(-0.01,0.01)';
      OUTPUT_LOAD='(1.0,-1.0)';
    'DDR1_SB_DQ10':
      PIN_NUMBER='(0,0,0,0,0,0,0,0,M26,0,0,0,0,0,0,0,0,0,0,0,0,0,0,0,0,0,0,0,0,0,0,0,0,0,0,0,0,0,0,0,0,0)';
      BIDIRECTIONAL='TRUE';
      INPUT_LOAD='(-0.01,0.01)';
      OUTPUT_LOAD='(1.0,-1.0)';
    'DDR1_SB_DQ9':
      PIN_NUMBER='(0,0,0,0,0,0,0,0,J25,0,0,0,0,0,0,0,0,0,0,0,0,0,0,0,0,0,0,0,0,0,0,0,0,0,0,0,0,0,0,0,0,0)';
      BIDIRECTIONAL='TRUE';
      INPUT_LOAD='(-0.01,0.01)';
      OUTPUT_LOAD='(1.0,-1.0)';
    'DDR1_SB_DQ8':
      PIN_NUMBER='(0,0,0,0,0,0,0,0,K26,0,0,0,0,0,0,0,0,0,0,0,0,0,0,0,0,0,0,0,0,0,0,0,0,0,0,0,0,0,0,0,0,0)';
      BIDIRECTIONAL='TRUE';
      INPUT_LOAD='(-0.01,0.01)';
      OUTPUT_LOAD='(1.0,-1.0)';
    'DDR1_SB_DQ7':
      PIN_NUMBER='(0,0,0,0,0,0,0,0,W25,0,0,0,0,0,0,0,0,0,0,0,0,0,0,0,0,0,0,0,0,0,0,0,0,0,0,0,0,0,0,0,0,0)';
      BIDIRECTIONAL='TRUE';
      INPUT_LOAD='(-0.01,0.01)';
      OUTPUT_LOAD='(1.0,-1.0)';
    'DDR1_SB_DQ6':
      PIN_NUMBER='(0,0,0,0,0,0,0,0,Y26,0,0,0,0,0,0,0,0,0,0,0,0,0,0,0,0,0,0,0,0,0,0,0,0,0,0,0,0,0,0,0,0,0)';
      BIDIRECTIONAL='TRUE';
      INPUT_LOAD='(-0.01,0.01)';
      OUTPUT_LOAD='(1.0,-1.0)';
    'DDR1_SB_DQ5':
      PIN_NUMBER='(0,0,0,0,0,0,0,0,U25,0,0,0,0,0,0,0,0,0,0,0,0,0,0,0,0,0,0,0,0,0,0,0,0,0,0,0,0,0,0,0,0,0)';
      BIDIRECTIONAL='TRUE';
      INPUT_LOAD='(-0.01,0.01)';
      OUTPUT_LOAD='(1.0,-1.0)';
    'DDR1_SB_DQ4':
      PIN_NUMBER='(0,0,0,0,0,0,0,0,T26,0,0,0,0,0,0,0,0,0,0,0,0,0,0,0,0,0,0,0,0,0,0,0,0,0,0,0,0,0,0,0,0,0)';
      BIDIRECTIONAL='TRUE';
      INPUT_LOAD='(-0.01,0.01)';
      OUTPUT_LOAD='(1.0,-1.0)';
    'DDR1_SB_DQ3':
      PIN_NUMBER='(0,0,0,0,0,0,0,0,Y28,0,0,0,0,0,0,0,0,0,0,0,0,0,0,0,0,0,0,0,0,0,0,0,0,0,0,0,0,0,0,0,0,0)';
      BIDIRECTIONAL='TRUE';
      INPUT_LOAD='(-0.01,0.01)';
      OUTPUT_LOAD='(1.0,-1.0)';
    'DDR1_SB_DQ2':
      PIN_NUMBER='(0,0,0,0,0,0,0,0,W29,0,0,0,0,0,0,0,0,0,0,0,0,0,0,0,0,0,0,0,0,0,0,0,0,0,0,0,0,0,0,0,0,0)';
      BIDIRECTIONAL='TRUE';
      INPUT_LOAD='(-0.01,0.01)';
      OUTPUT_LOAD='(1.0,-1.0)';
    'DDR1_SB_DQ1':
      PIN_NUMBER='(0,0,0,0,0,0,0,0,T28,0,0,0,0,0,0,0,0,0,0,0,0,0,0,0,0,0,0,0,0,0,0,0,0,0,0,0,0,0,0,0,0,0)';
      BIDIRECTIONAL='TRUE';
      INPUT_LOAD='(-0.01,0.01)';
      OUTPUT_LOAD='(1.0,-1.0)';
    'DDR1_SB_DQ0':
      PIN_NUMBER='(0,0,0,0,0,0,0,0,U29,0,0,0,0,0,0,0,0,0,0,0,0,0,0,0,0,0,0,0,0,0,0,0,0,0,0,0,0,0,0,0,0,0)';
      BIDIRECTIONAL='TRUE';
      INPUT_LOAD='(-0.01,0.01)';
      OUTPUT_LOAD='(1.0,-1.0)';
    'DDR1_SB_DQS_DN9':
      PIN_NUMBER='(0,0,0,0,0,0,0,0,K36,0,0,0,0,0,0,0,0,0,0,0,0,0,0,0,0,0,0,0,0,0,0,0,0,0,0,0,0,0,0,0,0,0)';
      BIDIRECTIONAL='TRUE';
      INPUT_LOAD='(-0.01,0.01)';
      OUTPUT_LOAD='(1.0,-1.0)';
    'DDR1_SB_DQS_DN8':
      PIN_NUMBER='(0,0,0,0,0,0,0,0,E15,0,0,0,0,0,0,0,0,0,0,0,0,0,0,0,0,0,0,0,0,0,0,0,0,0,0,0,0,0,0,0,0,0)';
      BIDIRECTIONAL='TRUE';
      INPUT_LOAD='(-0.01,0.01)';
      OUTPUT_LOAD='(1.0,-1.0)';
    'DDR1_SB_DQS_DN7':
      PIN_NUMBER='(0,0,0,0,0,0,0,0,M18,0,0,0,0,0,0,0,0,0,0,0,0,0,0,0,0,0,0,0,0,0,0,0,0,0,0,0,0,0,0,0,0,0)';
      BIDIRECTIONAL='TRUE';
      INPUT_LOAD='(-0.01,0.01)';
      OUTPUT_LOAD='(1.0,-1.0)';
    'DDR1_SB_DQS_DN6':
      PIN_NUMBER='(0,0,0,0,0,0,0,0,M24,0,0,0,0,0,0,0,0,0,0,0,0,0,0,0,0,0,0,0,0,0,0,0,0,0,0,0,0,0,0,0,0,0)';
      BIDIRECTIONAL='TRUE';
      INPUT_LOAD='(-0.01,0.01)';
      OUTPUT_LOAD='(1.0,-1.0)';
    'DDR1_SB_DQS_DN5':
      PIN_NUMBER='(0,0,0,0,0,0,0,0,W27,0,0,0,0,0,0,0,0,0,0,0,0,0,0,0,0,0,0,0,0,0,0,0,0,0,0,0,0,0,0,0,0,0)';
      BIDIRECTIONAL='TRUE';
      INPUT_LOAD='(-0.01,0.01)';
      OUTPUT_LOAD='(1.0,-1.0)';
    'DDR1_SB_DQS_DN4':
      PIN_NUMBER='(0,0,0,0,0,0,0,0,P36,0,0,0,0,0,0,0,0,0,0,0,0,0,0,0,0,0,0,0,0,0,0,0,0,0,0,0,0,0,0,0,0,0)';
      BIDIRECTIONAL='TRUE';
      INPUT_LOAD='(-0.01,0.01)';
      OUTPUT_LOAD='(1.0,-1.0)';
    'DDR1_SB_DQS_DN3':
      PIN_NUMBER='(0,0,0,0,0,0,0,0,A15,0,0,0,0,0,0,0,0,0,0,0,0,0,0,0,0,0,0,0,0,0,0,0,0,0,0,0,0,0,0,0,0,0)';
      BIDIRECTIONAL='TRUE';
      INPUT_LOAD='(-0.01,0.01)';
      OUTPUT_LOAD='(1.0,-1.0)';
    'DDR1_SB_DQS_DN2':
      PIN_NUMBER='(0,0,0,0,0,0,0,0,H18,0,0,0,0,0,0,0,0,0,0,0,0,0,0,0,0,0,0,0,0,0,0,0,0,0,0,0,0,0,0,0,0,0)';
      BIDIRECTIONAL='TRUE';
      INPUT_LOAD='(-0.01,0.01)';
      OUTPUT_LOAD='(1.0,-1.0)';
    'DDR1_SB_DQS_DN1':
      PIN_NUMBER='(0,0,0,0,0,0,0,0,H24,0,0,0,0,0,0,0,0,0,0,0,0,0,0,0,0,0,0,0,0,0,0,0,0,0,0,0,0,0,0,0,0,0)';
      BIDIRECTIONAL='TRUE';
      INPUT_LOAD='(-0.01,0.01)';
      OUTPUT_LOAD='(1.0,-1.0)';
    'DDR1_SB_DQS_DN0':
      PIN_NUMBER='(0,0,0,0,0,0,0,0,R27,0,0,0,0,0,0,0,0,0,0,0,0,0,0,0,0,0,0,0,0,0,0,0,0,0,0,0,0,0,0,0,0,0)';
      BIDIRECTIONAL='TRUE';
      INPUT_LOAD='(-0.01,0.01)';
      OUTPUT_LOAD='(1.0,-1.0)';
    'DDR1_SB_DQS_DP9':
      PIN_NUMBER='(0,0,0,0,0,0,0,0,H36,0,0,0,0,0,0,0,0,0,0,0,0,0,0,0,0,0,0,0,0,0,0,0,0,0,0,0,0,0,0,0,0,0)';
      BIDIRECTIONAL='TRUE';
      INPUT_LOAD='(-0.01,0.01)';
      OUTPUT_LOAD='(1.0,-1.0)';
    'DDR1_SB_DQS_DP8':
      PIN_NUMBER='(0,0,0,0,0,0,0,0,G15,0,0,0,0,0,0,0,0,0,0,0,0,0,0,0,0,0,0,0,0,0,0,0,0,0,0,0,0,0,0,0,0,0)';
      BIDIRECTIONAL='TRUE';
      INPUT_LOAD='(-0.01,0.01)';
      OUTPUT_LOAD='(1.0,-1.0)';
    'DDR1_SB_DQS_DP7':
      PIN_NUMBER='(0,0,0,0,0,0,0,0,P18,0,0,0,0,0,0,0,0,0,0,0,0,0,0,0,0,0,0,0,0,0,0,0,0,0,0,0,0,0,0,0,0,0)';
      BIDIRECTIONAL='TRUE';
      INPUT_LOAD='(-0.01,0.01)';
      OUTPUT_LOAD='(1.0,-1.0)';
    'DDR1_SB_DQS_DP6':
      PIN_NUMBER='(0,0,0,0,0,0,0,0,P24,0,0,0,0,0,0,0,0,0,0,0,0,0,0,0,0,0,0,0,0,0,0,0,0,0,0,0,0,0,0,0,0,0)';
      BIDIRECTIONAL='TRUE';
      INPUT_LOAD='(-0.01,0.01)';
      OUTPUT_LOAD='(1.0,-1.0)';
    'DDR1_SB_DQS_DP5':
      PIN_NUMBER='(0,0,0,0,0,0,0,0,AA27,0,0,0,0,0,0,0,0,0,0,0,0,0,0,0,0,0,0,0,0,0,0,0,0,0,0,0,0,0,0,0,0,0)';
      BIDIRECTIONAL='TRUE';
      INPUT_LOAD='(-0.01,0.01)';
      OUTPUT_LOAD='(1.0,-1.0)';
    'DDR1_SB_DQS_DP4':
      PIN_NUMBER='(0,0,0,0,0,0,0,0,M36,0,0,0,0,0,0,0,0,0,0,0,0,0,0,0,0,0,0,0,0,0,0,0,0,0,0,0,0,0,0,0,0,0)';
      BIDIRECTIONAL='TRUE';
      INPUT_LOAD='(-0.01,0.01)';
      OUTPUT_LOAD='(1.0,-1.0)';
    'DDR1_SB_DQS_DP3':
      PIN_NUMBER='(0,0,0,0,0,0,0,0,C15,0,0,0,0,0,0,0,0,0,0,0,0,0,0,0,0,0,0,0,0,0,0,0,0,0,0,0,0,0,0,0,0,0)';
      BIDIRECTIONAL='TRUE';
      INPUT_LOAD='(-0.01,0.01)';
      OUTPUT_LOAD='(1.0,-1.0)';
    'DDR1_SB_DQS_DP2':
      PIN_NUMBER='(0,0,0,0,0,0,0,0,K18,0,0,0,0,0,0,0,0,0,0,0,0,0,0,0,0,0,0,0,0,0,0,0,0,0,0,0,0,0,0,0,0,0)';
      BIDIRECTIONAL='TRUE';
      INPUT_LOAD='(-0.01,0.01)';
      OUTPUT_LOAD='(1.0,-1.0)';
    'DDR1_SB_DQS_DP1':
      PIN_NUMBER='(0,0,0,0,0,0,0,0,K24,0,0,0,0,0,0,0,0,0,0,0,0,0,0,0,0,0,0,0,0,0,0,0,0,0,0,0,0,0,0,0,0,0)';
      BIDIRECTIONAL='TRUE';
      INPUT_LOAD='(-0.01,0.01)';
      OUTPUT_LOAD='(1.0,-1.0)';
    'DDR1_SB_DQS_DP0':
      PIN_NUMBER='(0,0,0,0,0,0,0,0,U27,0,0,0,0,0,0,0,0,0,0,0,0,0,0,0,0,0,0,0,0,0,0,0,0,0,0,0,0,0,0,0,0,0)';
      BIDIRECTIONAL='TRUE';
      INPUT_LOAD='(-0.01,0.01)';
      OUTPUT_LOAD='(1.0,-1.0)';
    'DDR1_SB_ECC7':
      PIN_NUMBER='(0,0,0,0,0,0,0,0,N37,0,0,0,0,0,0,0,0,0,0,0,0,0,0,0,0,0,0,0,0,0,0,0,0,0,0,0,0,0,0,0,0,0)';
      BIDIRECTIONAL='TRUE';
      INPUT_LOAD='(-0.01,0.01)';
      OUTPUT_LOAD='(1.0,-1.0)';
    'DDR1_SB_ECC6':
      PIN_NUMBER='(0,0,0,0,0,0,0,0,M38,0,0,0,0,0,0,0,0,0,0,0,0,0,0,0,0,0,0,0,0,0,0,0,0,0,0,0,0,0,0,0,0,0)';
      BIDIRECTIONAL='TRUE';
      INPUT_LOAD='(-0.01,0.01)';
      OUTPUT_LOAD='(1.0,-1.0)';
    'DDR1_SB_ECC5':
      PIN_NUMBER='(0,0,0,0,0,0,0,0,J37,0,0,0,0,0,0,0,0,0,0,0,0,0,0,0,0,0,0,0,0,0,0,0,0,0,0,0,0,0,0,0,0,0)';
      BIDIRECTIONAL='TRUE';
      INPUT_LOAD='(-0.01,0.01)';
      OUTPUT_LOAD='(1.0,-1.0)';
    'DDR1_SB_ECC4':
      PIN_NUMBER='(0,0,0,0,0,0,0,0,K38,0,0,0,0,0,0,0,0,0,0,0,0,0,0,0,0,0,0,0,0,0,0,0,0,0,0,0,0,0,0,0,0,0)';
      BIDIRECTIONAL='TRUE';
      INPUT_LOAD='(-0.01,0.01)';
      OUTPUT_LOAD='(1.0,-1.0)';
    'DDR1_SB_ECC3':
      PIN_NUMBER='(0,0,0,0,0,0,0,0,M34,0,0,0,0,0,0,0,0,0,0,0,0,0,0,0,0,0,0,0,0,0,0,0,0,0,0,0,0,0,0,0,0,0)';
      BIDIRECTIONAL='TRUE';
      INPUT_LOAD='(-0.01,0.01)';
      OUTPUT_LOAD='(1.0,-1.0)';
    'DDR1_SB_ECC2':
      PIN_NUMBER='(0,0,0,0,0,0,0,0,N35,0,0,0,0,0,0,0,0,0,0,0,0,0,0,0,0,0,0,0,0,0,0,0,0,0,0,0,0,0,0,0,0,0)';
      BIDIRECTIONAL='TRUE';
      INPUT_LOAD='(-0.01,0.01)';
      OUTPUT_LOAD='(1.0,-1.0)';
    'DDR1_SB_ECC1':
      PIN_NUMBER='(0,0,0,0,0,0,0,0,K34,0,0,0,0,0,0,0,0,0,0,0,0,0,0,0,0,0,0,0,0,0,0,0,0,0,0,0,0,0,0,0,0,0)';
      BIDIRECTIONAL='TRUE';
      INPUT_LOAD='(-0.01,0.01)';
      OUTPUT_LOAD='(1.0,-1.0)';
    'DDR1_SB_ECC0':
      PIN_NUMBER='(0,0,0,0,0,0,0,0,J35,0,0,0,0,0,0,0,0,0,0,0,0,0,0,0,0,0,0,0,0,0,0,0,0,0,0,0,0,0,0,0,0,0)';
      BIDIRECTIONAL='TRUE';
      INPUT_LOAD='(-0.01,0.01)';
      OUTPUT_LOAD='(1.0,-1.0)';
    'DDR1_SB_PAR':
      PIN_NUMBER='(0,0,0,0,0,0,0,0,P42,0,0,0,0,0,0,0,0,0,0,0,0,0,0,0,0,0,0,0,0,0,0,0,0,0,0,0,0,0,0,0,0,0)';
      OUTPUT_LOAD='(1.0,-1.0)';
    '-DDR2_ALERT':
      PIN_NUMBER='(0,0,0,0,0,0,0,0,0,AT47,0,0,0,0,0,0,0,0,0,0,0,0,0,0,0,0,0,0,0,0,0,0,0,0,0,0,0,0,0,0,0,0)';
      INPUT_LOAD='(-0.01,0.01)';
    'DDR2_A_RSP1':
      PIN_NUMBER='(0,0,0,0,0,0,0,0,0,AD47,0,0,0,0,0,0,0,0,0,0,0,0,0,0,0,0,0,0,0,0,0,0,0,0,0,0,0,0,0,0,0,0)';
      INPUT_LOAD='(-0.01,0.01)';
    'DDR2_A_RSP0':
      PIN_NUMBER='(0,0,0,0,0,0,0,0,0,AC48,0,0,0,0,0,0,0,0,0,0,0,0,0,0,0,0,0,0,0,0,0,0,0,0,0,0,0,0,0,0,0,0)';
      INPUT_LOAD='(-0.01,0.01)';
    'DDR2_B_RSP1':
      PIN_NUMBER='(0,0,0,0,0,0,0,0,0,AF47,0,0,0,0,0,0,0,0,0,0,0,0,0,0,0,0,0,0,0,0,0,0,0,0,0,0,0,0,0,0,0,0)';
      INPUT_LOAD='(-0.01,0.01)';
    'DDR2_B_RSP0':
      PIN_NUMBER='(0,0,0,0,0,0,0,0,0,AG48,0,0,0,0,0,0,0,0,0,0,0,0,0,0,0,0,0,0,0,0,0,0,0,0,0,0,0,0,0,0,0,0)';
      INPUT_LOAD='(-0.01,0.01)';
    'DDR2_CLK_DN1':
      PIN_NUMBER='(0,0,0,0,0,0,0,0,0,AF49,0,0,0,0,0,0,0,0,0,0,0,0,0,0,0,0,0,0,0,0,0,0,0,0,0,0,0,0,0,0,0,0)';
      OUTPUT_LOAD='(1.0,-1.0)';
    'DDR2_CLK_DN0':
      PIN_NUMBER='(0,0,0,0,0,0,0,0,0,AB49,0,0,0,0,0,0,0,0,0,0,0,0,0,0,0,0,0,0,0,0,0,0,0,0,0,0,0,0,0,0,0,0)';
      OUTPUT_LOAD='(1.0,-1.0)';
    'DDR2_CLK_DP1':
      PIN_NUMBER='(0,0,0,0,0,0,0,0,0,AH49,0,0,0,0,0,0,0,0,0,0,0,0,0,0,0,0,0,0,0,0,0,0,0,0,0,0,0,0,0,0,0,0)';
      OUTPUT_LOAD='(1.0,-1.0)';
    'DDR2_CLK_DP0':
      PIN_NUMBER='(0,0,0,0,0,0,0,0,0,AD49,0,0,0,0,0,0,0,0,0,0,0,0,0,0,0,0,0,0,0,0,0,0,0,0,0,0,0,0,0,0,0,0)';
      OUTPUT_LOAD='(1.0,-1.0)';
    'DDR2_SA_CA6':
      PIN_NUMBER='(0,0,0,0,0,0,0,0,0,U48,0,0,0,0,0,0,0,0,0,0,0,0,0,0,0,0,0,0,0,0,0,0,0,0,0,0,0,0,0,0,0,0)';
      OUTPUT_LOAD='(1.0,-1.0)';
    'DDR2_SA_CA5':
      PIN_NUMBER='(0,0,0,0,0,0,0,0,0,W50,0,0,0,0,0,0,0,0,0,0,0,0,0,0,0,0,0,0,0,0,0,0,0,0,0,0,0,0,0,0,0,0)';
      OUTPUT_LOAD='(1.0,-1.0)';
    'DDR2_SA_CA4':
      PIN_NUMBER='(0,0,0,0,0,0,0,0,0,U50,0,0,0,0,0,0,0,0,0,0,0,0,0,0,0,0,0,0,0,0,0,0,0,0,0,0,0,0,0,0,0,0)';
      OUTPUT_LOAD='(1.0,-1.0)';
    'DDR2_SA_CA3':
      PIN_NUMBER='(0,0,0,0,0,0,0,0,0,Y51,0,0,0,0,0,0,0,0,0,0,0,0,0,0,0,0,0,0,0,0,0,0,0,0,0,0,0,0,0,0,0,0)';
      OUTPUT_LOAD='(1.0,-1.0)';
    'DDR2_SA_CA2':
      PIN_NUMBER='(0,0,0,0,0,0,0,0,0,T51,0,0,0,0,0,0,0,0,0,0,0,0,0,0,0,0,0,0,0,0,0,0,0,0,0,0,0,0,0,0,0,0)';
      OUTPUT_LOAD='(1.0,-1.0)';
    'DDR2_SA_CA1':
      PIN_NUMBER='(0,0,0,0,0,0,0,0,0,AA52,0,0,0,0,0,0,0,0,0,0,0,0,0,0,0,0,0,0,0,0,0,0,0,0,0,0,0,0,0,0,0,0)';
      OUTPUT_LOAD='(1.0,-1.0)';
    'DDR2_SA_CA0':
      PIN_NUMBER='(0,0,0,0,0,0,0,0,0,R52,0,0,0,0,0,0,0,0,0,0,0,0,0,0,0,0,0,0,0,0,0,0,0,0,0,0,0,0,0,0,0,0)';
      OUTPUT_LOAD='(1.0,-1.0)';
    'DDR2_SA_CS_N3':
      PIN_NUMBER='(0,0,0,0,0,0,0,0,0,Y53,0,0,0,0,0,0,0,0,0,0,0,0,0,0,0,0,0,0,0,0,0,0,0,0,0,0,0,0,0,0,0,0)';
      OUTPUT_LOAD='(1.0,-1.0)';
    'DDR2_SA_CS_N2':
      PIN_NUMBER='(0,0,0,0,0,0,0,0,0,W54,0,0,0,0,0,0,0,0,0,0,0,0,0,0,0,0,0,0,0,0,0,0,0,0,0,0,0,0,0,0,0,0)';
      OUTPUT_LOAD='(1.0,-1.0)';
    'DDR2_SA_CS_N1':
      PIN_NUMBER='(0,0,0,0,0,0,0,0,0,T53,0,0,0,0,0,0,0,0,0,0,0,0,0,0,0,0,0,0,0,0,0,0,0,0,0,0,0,0,0,0,0,0)';
      OUTPUT_LOAD='(1.0,-1.0)';
    'DDR2_SA_CS_N0':
      PIN_NUMBER='(0,0,0,0,0,0,0,0,0,U54,0,0,0,0,0,0,0,0,0,0,0,0,0,0,0,0,0,0,0,0,0,0,0,0,0,0,0,0,0,0,0,0)';
      OUTPUT_LOAD='(1.0,-1.0)';
    'DDR2_SA_DQ31':
      PIN_NUMBER='(0,0,0,0,0,0,0,0,0,AF59,0,0,0,0,0,0,0,0,0,0,0,0,0,0,0,0,0,0,0,0,0,0,0,0,0,0,0,0,0,0,0,0)';
      BIDIRECTIONAL='TRUE';
      INPUT_LOAD='(-0.01,0.01)';
      OUTPUT_LOAD='(1.0,-1.0)';
    'DDR2_SA_DQ30':
      PIN_NUMBER='(0,0,0,0,0,0,0,0,0,AG60,0,0,0,0,0,0,0,0,0,0,0,0,0,0,0,0,0,0,0,0,0,0,0,0,0,0,0,0,0,0,0,0)';
      BIDIRECTIONAL='TRUE';
      INPUT_LOAD='(-0.01,0.01)';
      OUTPUT_LOAD='(1.0,-1.0)';
    'DDR2_SA_DQ29':
      PIN_NUMBER='(0,0,0,0,0,0,0,0,0,AD59,0,0,0,0,0,0,0,0,0,0,0,0,0,0,0,0,0,0,0,0,0,0,0,0,0,0,0,0,0,0,0,0)';
      BIDIRECTIONAL='TRUE';
      INPUT_LOAD='(-0.01,0.01)';
      OUTPUT_LOAD='(1.0,-1.0)';
    'DDR2_SA_DQ28':
      PIN_NUMBER='(0,0,0,0,0,0,0,0,0,AC60,0,0,0,0,0,0,0,0,0,0,0,0,0,0,0,0,0,0,0,0,0,0,0,0,0,0,0,0,0,0,0,0)';
      BIDIRECTIONAL='TRUE';
      INPUT_LOAD='(-0.01,0.01)';
      OUTPUT_LOAD='(1.0,-1.0)';
    'DDR2_SA_DQ27':
      PIN_NUMBER='(0,0,0,0,0,0,0,0,0,AG62,0,0,0,0,0,0,0,0,0,0,0,0,0,0,0,0,0,0,0,0,0,0,0,0,0,0,0,0,0,0,0,0)';
      BIDIRECTIONAL='TRUE';
      INPUT_LOAD='(-0.01,0.01)';
      OUTPUT_LOAD='(1.0,-1.0)';
    'DDR2_SA_DQ26':
      PIN_NUMBER='(0,0,0,0,0,0,0,0,0,AF63,0,0,0,0,0,0,0,0,0,0,0,0,0,0,0,0,0,0,0,0,0,0,0,0,0,0,0,0,0,0,0,0)';
      BIDIRECTIONAL='TRUE';
      INPUT_LOAD='(-0.01,0.01)';
      OUTPUT_LOAD='(1.0,-1.0)';
    'DDR2_SA_DQ25':
      PIN_NUMBER='(0,0,0,0,0,0,0,0,0,AC62,0,0,0,0,0,0,0,0,0,0,0,0,0,0,0,0,0,0,0,0,0,0,0,0,0,0,0,0,0,0,0,0)';
      BIDIRECTIONAL='TRUE';
      INPUT_LOAD='(-0.01,0.01)';
      OUTPUT_LOAD='(1.0,-1.0)';
    'DDR2_SA_DQ24':
      PIN_NUMBER='(0,0,0,0,0,0,0,0,0,AD63,0,0,0,0,0,0,0,0,0,0,0,0,0,0,0,0,0,0,0,0,0,0,0,0,0,0,0,0,0,0,0,0)';
      BIDIRECTIONAL='TRUE';
      INPUT_LOAD='(-0.01,0.01)';
      OUTPUT_LOAD='(1.0,-1.0)';
    'DDR2_SA_DQ23':
      PIN_NUMBER='(0,0,0,0,0,0,0,0,0,W62,0,0,0,0,0,0,0,0,0,0,0,0,0,0,0,0,0,0,0,0,0,0,0,0,0,0,0,0,0,0,0,0)';
      BIDIRECTIONAL='TRUE';
      INPUT_LOAD='(-0.01,0.01)';
      OUTPUT_LOAD='(1.0,-1.0)';
    'DDR2_SA_DQ22':
      PIN_NUMBER='(0,0,0,0,0,0,0,0,0,Y63,0,0,0,0,0,0,0,0,0,0,0,0,0,0,0,0,0,0,0,0,0,0,0,0,0,0,0,0,0,0,0,0)';
      BIDIRECTIONAL='TRUE';
      INPUT_LOAD='(-0.01,0.01)';
      OUTPUT_LOAD='(1.0,-1.0)';
    'DDR2_SA_DQ21':
      PIN_NUMBER='(0,0,0,0,0,0,0,0,0,U62,0,0,0,0,0,0,0,0,0,0,0,0,0,0,0,0,0,0,0,0,0,0,0,0,0,0,0,0,0,0,0,0)';
      BIDIRECTIONAL='TRUE';
      INPUT_LOAD='(-0.01,0.01)';
      OUTPUT_LOAD='(1.0,-1.0)';
    'DDR2_SA_DQ20':
      PIN_NUMBER='(0,0,0,0,0,0,0,0,0,T63,0,0,0,0,0,0,0,0,0,0,0,0,0,0,0,0,0,0,0,0,0,0,0,0,0,0,0,0,0,0,0,0)';
      BIDIRECTIONAL='TRUE';
      INPUT_LOAD='(-0.01,0.01)';
      OUTPUT_LOAD='(1.0,-1.0)';
    'DDR2_SA_DQ19':
      PIN_NUMBER='(0,0,0,0,0,0,0,0,0,Y65,0,0,0,0,0,0,0,0,0,0,0,0,0,0,0,0,0,0,0,0,0,0,0,0,0,0,0,0,0,0,0,0)';
      BIDIRECTIONAL='TRUE';
      INPUT_LOAD='(-0.01,0.01)';
      OUTPUT_LOAD='(1.0,-1.0)';
    'DDR2_SA_DQ18':
      PIN_NUMBER='(0,0,0,0,0,0,0,0,0,W66,0,0,0,0,0,0,0,0,0,0,0,0,0,0,0,0,0,0,0,0,0,0,0,0,0,0,0,0,0,0,0,0)';
      BIDIRECTIONAL='TRUE';
      INPUT_LOAD='(-0.01,0.01)';
      OUTPUT_LOAD='(1.0,-1.0)';
    'DDR2_SA_DQ17':
      PIN_NUMBER='(0,0,0,0,0,0,0,0,0,T65,0,0,0,0,0,0,0,0,0,0,0,0,0,0,0,0,0,0,0,0,0,0,0,0,0,0,0,0,0,0,0,0)';
      BIDIRECTIONAL='TRUE';
      INPUT_LOAD='(-0.01,0.01)';
      OUTPUT_LOAD='(1.0,-1.0)';
    'DDR2_SA_DQ16':
      PIN_NUMBER='(0,0,0,0,0,0,0,0,0,U66,0,0,0,0,0,0,0,0,0,0,0,0,0,0,0,0,0,0,0,0,0,0,0,0,0,0,0,0,0,0,0,0)';
      BIDIRECTIONAL='TRUE';
      INPUT_LOAD='(-0.01,0.01)';
      OUTPUT_LOAD='(1.0,-1.0)';
    'DDR2_SA_DQ15':
      PIN_NUMBER='(0,0,0,0,0,0,0,0,0,AF65,0,0,0,0,0,0,0,0,0,0,0,0,0,0,0,0,0,0,0,0,0,0,0,0,0,0,0,0,0,0,0,0)';
      BIDIRECTIONAL='TRUE';
      INPUT_LOAD='(-0.01,0.01)';
      OUTPUT_LOAD='(1.0,-1.0)';
    'DDR2_SA_DQ14':
      PIN_NUMBER='(0,0,0,0,0,0,0,0,0,AG66,0,0,0,0,0,0,0,0,0,0,0,0,0,0,0,0,0,0,0,0,0,0,0,0,0,0,0,0,0,0,0,0)';
      BIDIRECTIONAL='TRUE';
      INPUT_LOAD='(-0.01,0.01)';
      OUTPUT_LOAD='(1.0,-1.0)';
    'DDR2_SA_DQ13':
      PIN_NUMBER='(0,0,0,0,0,0,0,0,0,AD65,0,0,0,0,0,0,0,0,0,0,0,0,0,0,0,0,0,0,0,0,0,0,0,0,0,0,0,0,0,0,0,0)';
      BIDIRECTIONAL='TRUE';
      INPUT_LOAD='(-0.01,0.01)';
      OUTPUT_LOAD='(1.0,-1.0)';
    'DDR2_SA_DQ12':
      PIN_NUMBER='(0,0,0,0,0,0,0,0,0,AC66,0,0,0,0,0,0,0,0,0,0,0,0,0,0,0,0,0,0,0,0,0,0,0,0,0,0,0,0,0,0,0,0)';
      BIDIRECTIONAL='TRUE';
      INPUT_LOAD='(-0.01,0.01)';
      OUTPUT_LOAD='(1.0,-1.0)';
    'DDR2_SA_DQ11':
      PIN_NUMBER='(0,0,0,0,0,0,0,0,0,AG68,0,0,0,0,0,0,0,0,0,0,0,0,0,0,0,0,0,0,0,0,0,0,0,0,0,0,0,0,0,0,0,0)';
      BIDIRECTIONAL='TRUE';
      INPUT_LOAD='(-0.01,0.01)';
      OUTPUT_LOAD='(1.0,-1.0)';
    'DDR2_SA_DQ10':
      PIN_NUMBER='(0,0,0,0,0,0,0,0,0,AF69,0,0,0,0,0,0,0,0,0,0,0,0,0,0,0,0,0,0,0,0,0,0,0,0,0,0,0,0,0,0,0,0)';
      BIDIRECTIONAL='TRUE';
      INPUT_LOAD='(-0.01,0.01)';
      OUTPUT_LOAD='(1.0,-1.0)';
    'DDR2_SA_DQ9':
      PIN_NUMBER='(0,0,0,0,0,0,0,0,0,AC68,0,0,0,0,0,0,0,0,0,0,0,0,0,0,0,0,0,0,0,0,0,0,0,0,0,0,0,0,0,0,0,0)';
      BIDIRECTIONAL='TRUE';
      INPUT_LOAD='(-0.01,0.01)';
      OUTPUT_LOAD='(1.0,-1.0)';
    'DDR2_SA_DQ8':
      PIN_NUMBER='(0,0,0,0,0,0,0,0,0,AD69,0,0,0,0,0,0,0,0,0,0,0,0,0,0,0,0,0,0,0,0,0,0,0,0,0,0,0,0,0,0,0,0)';
      BIDIRECTIONAL='TRUE';
      INPUT_LOAD='(-0.01,0.01)';
      OUTPUT_LOAD='(1.0,-1.0)';
    'DDR2_SA_DQ7':
      PIN_NUMBER='(0,0,0,0,0,0,0,0,0,W74,0,0,0,0,0,0,0,0,0,0,0,0,0,0,0,0,0,0,0,0,0,0,0,0,0,0,0,0,0,0,0,0)';
      BIDIRECTIONAL='TRUE';
      INPUT_LOAD='(-0.01,0.01)';
      OUTPUT_LOAD='(1.0,-1.0)';
    'DDR2_SA_DQ6':
      PIN_NUMBER='(0,0,0,0,0,0,0,0,0,Y75,0,0,0,0,0,0,0,0,0,0,0,0,0,0,0,0,0,0,0,0,0,0,0,0,0,0,0,0,0,0,0,0)';
      BIDIRECTIONAL='TRUE';
      INPUT_LOAD='(-0.01,0.01)';
      OUTPUT_LOAD='(1.0,-1.0)';
    'DDR2_SA_DQ5':
      PIN_NUMBER='(0,0,0,0,0,0,0,0,0,U74,0,0,0,0,0,0,0,0,0,0,0,0,0,0,0,0,0,0,0,0,0,0,0,0,0,0,0,0,0,0,0,0)';
      BIDIRECTIONAL='TRUE';
      INPUT_LOAD='(-0.01,0.01)';
      OUTPUT_LOAD='(1.0,-1.0)';
    'DDR2_SA_DQ4':
      PIN_NUMBER='(0,0,0,0,0,0,0,0,0,T75,0,0,0,0,0,0,0,0,0,0,0,0,0,0,0,0,0,0,0,0,0,0,0,0,0,0,0,0,0,0,0,0)';
      BIDIRECTIONAL='TRUE';
      INPUT_LOAD='(-0.01,0.01)';
      OUTPUT_LOAD='(1.0,-1.0)';
    'DDR2_SA_DQ3':
      PIN_NUMBER='(0,0,0,0,0,0,0,0,0,Y77,0,0,0,0,0,0,0,0,0,0,0,0,0,0,0,0,0,0,0,0,0,0,0,0,0,0,0,0,0,0,0,0)';
      BIDIRECTIONAL='TRUE';
      INPUT_LOAD='(-0.01,0.01)';
      OUTPUT_LOAD='(1.0,-1.0)';
    'DDR2_SA_DQ2':
      PIN_NUMBER='(0,0,0,0,0,0,0,0,0,W78,0,0,0,0,0,0,0,0,0,0,0,0,0,0,0,0,0,0,0,0,0,0,0,0,0,0,0,0,0,0,0,0)';
      BIDIRECTIONAL='TRUE';
      INPUT_LOAD='(-0.01,0.01)';
      OUTPUT_LOAD='(1.0,-1.0)';
    'DDR2_SA_DQ1':
      PIN_NUMBER='(0,0,0,0,0,0,0,0,0,T77,0,0,0,0,0,0,0,0,0,0,0,0,0,0,0,0,0,0,0,0,0,0,0,0,0,0,0,0,0,0,0,0)';
      BIDIRECTIONAL='TRUE';
      INPUT_LOAD='(-0.01,0.01)';
      OUTPUT_LOAD='(1.0,-1.0)';
    'DDR2_SA_DQ0':
      PIN_NUMBER='(0,0,0,0,0,0,0,0,0,U78,0,0,0,0,0,0,0,0,0,0,0,0,0,0,0,0,0,0,0,0,0,0,0,0,0,0,0,0,0,0,0,0)';
      BIDIRECTIONAL='TRUE';
      INPUT_LOAD='(-0.01,0.01)';
      OUTPUT_LOAD='(1.0,-1.0)';
    'DDR2_SA_DQS_DN9':
      PIN_NUMBER='(0,0,0,0,0,0,0,0,0,AH55,0,0,0,0,0,0,0,0,0,0,0,0,0,0,0,0,0,0,0,0,0,0,0,0,0,0,0,0,0,0,0,0)';
      BIDIRECTIONAL='TRUE';
      INPUT_LOAD='(-0.01,0.01)';
      OUTPUT_LOAD='(1.0,-1.0)';
    'DDR2_SA_DQS_DN8':
      PIN_NUMBER='(0,0,0,0,0,0,0,0,0,AF61,0,0,0,0,0,0,0,0,0,0,0,0,0,0,0,0,0,0,0,0,0,0,0,0,0,0,0,0,0,0,0,0)';
      BIDIRECTIONAL='TRUE';
      INPUT_LOAD='(-0.01,0.01)';
      OUTPUT_LOAD='(1.0,-1.0)';
    'DDR2_SA_DQS_DN7':
      PIN_NUMBER='(0,0,0,0,0,0,0,0,0,AA64,0,0,0,0,0,0,0,0,0,0,0,0,0,0,0,0,0,0,0,0,0,0,0,0,0,0,0,0,0,0,0,0)';
      BIDIRECTIONAL='TRUE';
      INPUT_LOAD='(-0.01,0.01)';
      OUTPUT_LOAD='(1.0,-1.0)';
    'DDR2_SA_DQS_DN6':
      PIN_NUMBER='(0,0,0,0,0,0,0,0,0,AH67,0,0,0,0,0,0,0,0,0,0,0,0,0,0,0,0,0,0,0,0,0,0,0,0,0,0,0,0,0,0,0,0)';
      BIDIRECTIONAL='TRUE';
      INPUT_LOAD='(-0.01,0.01)';
      OUTPUT_LOAD='(1.0,-1.0)';
    'DDR2_SA_DQS_DN5':
      PIN_NUMBER='(0,0,0,0,0,0,0,0,0,W76,0,0,0,0,0,0,0,0,0,0,0,0,0,0,0,0,0,0,0,0,0,0,0,0,0,0,0,0,0,0,0,0)';
      BIDIRECTIONAL='TRUE';
      INPUT_LOAD='(-0.01,0.01)';
      OUTPUT_LOAD='(1.0,-1.0)';
    'DDR2_SA_DQS_DN4':
      PIN_NUMBER='(0,0,0,0,0,0,0,0,0,AD55,0,0,0,0,0,0,0,0,0,0,0,0,0,0,0,0,0,0,0,0,0,0,0,0,0,0,0,0,0,0,0,0)';
      BIDIRECTIONAL='TRUE';
      INPUT_LOAD='(-0.01,0.01)';
      OUTPUT_LOAD='(1.0,-1.0)';
    'DDR2_SA_DQS_DN3':
      PIN_NUMBER='(0,0,0,0,0,0,0,0,0,AB61,0,0,0,0,0,0,0,0,0,0,0,0,0,0,0,0,0,0,0,0,0,0,0,0,0,0,0,0,0,0,0,0)';
      BIDIRECTIONAL='TRUE';
      INPUT_LOAD='(-0.01,0.01)';
      OUTPUT_LOAD='(1.0,-1.0)';
    'DDR2_SA_DQS_DN2':
      PIN_NUMBER='(0,0,0,0,0,0,0,0,0,R64,0,0,0,0,0,0,0,0,0,0,0,0,0,0,0,0,0,0,0,0,0,0,0,0,0,0,0,0,0,0,0,0)';
      BIDIRECTIONAL='TRUE';
      INPUT_LOAD='(-0.01,0.01)';
      OUTPUT_LOAD='(1.0,-1.0)';
    'DDR2_SA_DQS_DN1':
      PIN_NUMBER='(0,0,0,0,0,0,0,0,0,AB67,0,0,0,0,0,0,0,0,0,0,0,0,0,0,0,0,0,0,0,0,0,0,0,0,0,0,0,0,0,0,0,0)';
      BIDIRECTIONAL='TRUE';
      INPUT_LOAD='(-0.01,0.01)';
      OUTPUT_LOAD='(1.0,-1.0)';
    'DDR2_SA_DQS_DN0':
      PIN_NUMBER='(0,0,0,0,0,0,0,0,0,R76,0,0,0,0,0,0,0,0,0,0,0,0,0,0,0,0,0,0,0,0,0,0,0,0,0,0,0,0,0,0,0,0)';
      BIDIRECTIONAL='TRUE';
      INPUT_LOAD='(-0.01,0.01)';
      OUTPUT_LOAD='(1.0,-1.0)';
    'DDR2_SA_DQS_DP9':
      PIN_NUMBER='(0,0,0,0,0,0,0,0,0,AF55,0,0,0,0,0,0,0,0,0,0,0,0,0,0,0,0,0,0,0,0,0,0,0,0,0,0,0,0,0,0,0,0)';
      BIDIRECTIONAL='TRUE';
      INPUT_LOAD='(-0.01,0.01)';
      OUTPUT_LOAD='(1.0,-1.0)';
    'DDR2_SA_DQS_DP8':
      PIN_NUMBER='(0,0,0,0,0,0,0,0,0,AH61,0,0,0,0,0,0,0,0,0,0,0,0,0,0,0,0,0,0,0,0,0,0,0,0,0,0,0,0,0,0,0,0)';
      BIDIRECTIONAL='TRUE';
      INPUT_LOAD='(-0.01,0.01)';
      OUTPUT_LOAD='(1.0,-1.0)';
    'DDR2_SA_DQS_DP7':
      PIN_NUMBER='(0,0,0,0,0,0,0,0,0,W64,0,0,0,0,0,0,0,0,0,0,0,0,0,0,0,0,0,0,0,0,0,0,0,0,0,0,0,0,0,0,0,0)';
      BIDIRECTIONAL='TRUE';
      INPUT_LOAD='(-0.01,0.01)';
      OUTPUT_LOAD='(1.0,-1.0)';
    'DDR2_SA_DQS_DP6':
      PIN_NUMBER='(0,0,0,0,0,0,0,0,0,AF67,0,0,0,0,0,0,0,0,0,0,0,0,0,0,0,0,0,0,0,0,0,0,0,0,0,0,0,0,0,0,0,0)';
      BIDIRECTIONAL='TRUE';
      INPUT_LOAD='(-0.01,0.01)';
      OUTPUT_LOAD='(1.0,-1.0)';
    'DDR2_SA_DQS_DP5':
      PIN_NUMBER='(0,0,0,0,0,0,0,0,0,AA76,0,0,0,0,0,0,0,0,0,0,0,0,0,0,0,0,0,0,0,0,0,0,0,0,0,0,0,0,0,0,0,0)';
      BIDIRECTIONAL='TRUE';
      INPUT_LOAD='(-0.01,0.01)';
      OUTPUT_LOAD='(1.0,-1.0)';
    'DDR2_SA_DQS_DP4':
      PIN_NUMBER='(0,0,0,0,0,0,0,0,0,AB55,0,0,0,0,0,0,0,0,0,0,0,0,0,0,0,0,0,0,0,0,0,0,0,0,0,0,0,0,0,0,0,0)';
      BIDIRECTIONAL='TRUE';
      INPUT_LOAD='(-0.01,0.01)';
      OUTPUT_LOAD='(1.0,-1.0)';
    'DDR2_SA_DQS_DP3':
      PIN_NUMBER='(0,0,0,0,0,0,0,0,0,AD61,0,0,0,0,0,0,0,0,0,0,0,0,0,0,0,0,0,0,0,0,0,0,0,0,0,0,0,0,0,0,0,0)';
      BIDIRECTIONAL='TRUE';
      INPUT_LOAD='(-0.01,0.01)';
      OUTPUT_LOAD='(1.0,-1.0)';
    'DDR2_SA_DQS_DP2':
      PIN_NUMBER='(0,0,0,0,0,0,0,0,0,U64,0,0,0,0,0,0,0,0,0,0,0,0,0,0,0,0,0,0,0,0,0,0,0,0,0,0,0,0,0,0,0,0)';
      BIDIRECTIONAL='TRUE';
      INPUT_LOAD='(-0.01,0.01)';
      OUTPUT_LOAD='(1.0,-1.0)';
    'DDR2_SA_DQS_DP1':
      PIN_NUMBER='(0,0,0,0,0,0,0,0,0,AD67,0,0,0,0,0,0,0,0,0,0,0,0,0,0,0,0,0,0,0,0,0,0,0,0,0,0,0,0,0,0,0,0)';
      BIDIRECTIONAL='TRUE';
      INPUT_LOAD='(-0.01,0.01)';
      OUTPUT_LOAD='(1.0,-1.0)';
    'DDR2_SA_DQS_DP0':
      PIN_NUMBER='(0,0,0,0,0,0,0,0,0,U76,0,0,0,0,0,0,0,0,0,0,0,0,0,0,0,0,0,0,0,0,0,0,0,0,0,0,0,0,0,0,0,0)';
      BIDIRECTIONAL='TRUE';
      INPUT_LOAD='(-0.01,0.01)';
      OUTPUT_LOAD='(1.0,-1.0)';
    'DDR2_SA_ECC7':
      PIN_NUMBER='(0,0,0,0,0,0,0,0,0,AF53,0,0,0,0,0,0,0,0,0,0,0,0,0,0,0,0,0,0,0,0,0,0,0,0,0,0,0,0,0,0,0,0)';
      BIDIRECTIONAL='TRUE';
      INPUT_LOAD='(-0.01,0.01)';
      OUTPUT_LOAD='(1.0,-1.0)';
    'DDR2_SA_ECC6':
      PIN_NUMBER='(0,0,0,0,0,0,0,0,0,AG54,0,0,0,0,0,0,0,0,0,0,0,0,0,0,0,0,0,0,0,0,0,0,0,0,0,0,0,0,0,0,0,0)';
      BIDIRECTIONAL='TRUE';
      INPUT_LOAD='(-0.01,0.01)';
      OUTPUT_LOAD='(1.0,-1.0)';
    'DDR2_SA_ECC5':
      PIN_NUMBER='(0,0,0,0,0,0,0,0,0,AD53,0,0,0,0,0,0,0,0,0,0,0,0,0,0,0,0,0,0,0,0,0,0,0,0,0,0,0,0,0,0,0,0)';
      BIDIRECTIONAL='TRUE';
      INPUT_LOAD='(-0.01,0.01)';
      OUTPUT_LOAD='(1.0,-1.0)';
    'DDR2_SA_ECC4':
      PIN_NUMBER='(0,0,0,0,0,0,0,0,0,AC54,0,0,0,0,0,0,0,0,0,0,0,0,0,0,0,0,0,0,0,0,0,0,0,0,0,0,0,0,0,0,0,0)';
      BIDIRECTIONAL='TRUE';
      INPUT_LOAD='(-0.01,0.01)';
      OUTPUT_LOAD='(1.0,-1.0)';
    'DDR2_SA_ECC3':
      PIN_NUMBER='(0,0,0,0,0,0,0,0,0,AG56,0,0,0,0,0,0,0,0,0,0,0,0,0,0,0,0,0,0,0,0,0,0,0,0,0,0,0,0,0,0,0,0)';
      BIDIRECTIONAL='TRUE';
      INPUT_LOAD='(-0.01,0.01)';
      OUTPUT_LOAD='(1.0,-1.0)';
    'DDR2_SA_ECC2':
      PIN_NUMBER='(0,0,0,0,0,0,0,0,0,AF57,0,0,0,0,0,0,0,0,0,0,0,0,0,0,0,0,0,0,0,0,0,0,0,0,0,0,0,0,0,0,0,0)';
      BIDIRECTIONAL='TRUE';
      INPUT_LOAD='(-0.01,0.01)';
      OUTPUT_LOAD='(1.0,-1.0)';
    'DDR2_SA_ECC1':
      PIN_NUMBER='(0,0,0,0,0,0,0,0,0,AC56,0,0,0,0,0,0,0,0,0,0,0,0,0,0,0,0,0,0,0,0,0,0,0,0,0,0,0,0,0,0,0,0)';
      BIDIRECTIONAL='TRUE';
      INPUT_LOAD='(-0.01,0.01)';
      OUTPUT_LOAD='(1.0,-1.0)';
    'DDR2_SA_ECC0':
      PIN_NUMBER='(0,0,0,0,0,0,0,0,0,AD57,0,0,0,0,0,0,0,0,0,0,0,0,0,0,0,0,0,0,0,0,0,0,0,0,0,0,0,0,0,0,0,0)';
      BIDIRECTIONAL='TRUE';
      INPUT_LOAD='(-0.01,0.01)';
      OUTPUT_LOAD='(1.0,-1.0)';
    'DDR2_SA_PAR':
      PIN_NUMBER='(0,0,0,0,0,0,0,0,0,T47,0,0,0,0,0,0,0,0,0,0,0,0,0,0,0,0,0,0,0,0,0,0,0,0,0,0,0,0,0,0,0,0)';
      OUTPUT_LOAD='(1.0,-1.0)';
    'DDR2_SB_CA6':
      PIN_NUMBER='(0,0,0,0,0,0,0,0,0,R39,0,0,0,0,0,0,0,0,0,0,0,0,0,0,0,0,0,0,0,0,0,0,0,0,0,0,0,0,0,0,0,0)';
      OUTPUT_LOAD='(1.0,-1.0)';
    'DDR2_SB_CA5':
      PIN_NUMBER='(0,0,0,0,0,0,0,0,0,Y40,0,0,0,0,0,0,0,0,0,0,0,0,0,0,0,0,0,0,0,0,0,0,0,0,0,0,0,0,0,0,0,0)';
      OUTPUT_LOAD='(1.0,-1.0)';
    'DDR2_SB_CA4':
      PIN_NUMBER='(0,0,0,0,0,0,0,0,0,T40,0,0,0,0,0,0,0,0,0,0,0,0,0,0,0,0,0,0,0,0,0,0,0,0,0,0,0,0,0,0,0,0)';
      OUTPUT_LOAD='(1.0,-1.0)';
    'DDR2_SB_CA3':
      PIN_NUMBER='(0,0,0,0,0,0,0,0,0,W41,0,0,0,0,0,0,0,0,0,0,0,0,0,0,0,0,0,0,0,0,0,0,0,0,0,0,0,0,0,0,0,0)';
      OUTPUT_LOAD='(1.0,-1.0)';
    'DDR2_SB_CA2':
      PIN_NUMBER='(0,0,0,0,0,0,0,0,0,U41,0,0,0,0,0,0,0,0,0,0,0,0,0,0,0,0,0,0,0,0,0,0,0,0,0,0,0,0,0,0,0,0)';
      OUTPUT_LOAD='(1.0,-1.0)';
    'DDR2_SB_CA1':
      PIN_NUMBER='(0,0,0,0,0,0,0,0,0,Y47,0,0,0,0,0,0,0,0,0,0,0,0,0,0,0,0,0,0,0,0,0,0,0,0,0,0,0,0,0,0,0,0)';
      OUTPUT_LOAD='(1.0,-1.0)';
    'DDR2_SB_CA0':
      PIN_NUMBER='(0,0,0,0,0,0,0,0,0,W48,0,0,0,0,0,0,0,0,0,0,0,0,0,0,0,0,0,0,0,0,0,0,0,0,0,0,0,0,0,0,0,0)';
      OUTPUT_LOAD='(1.0,-1.0)';
    'DDR2_SB_CS_N3':
      PIN_NUMBER='(0,0,0,0,0,0,0,0,0,W37,0,0,0,0,0,0,0,0,0,0,0,0,0,0,0,0,0,0,0,0,0,0,0,0,0,0,0,0,0,0,0,0)';
      OUTPUT_LOAD='(1.0,-1.0)';
    'DDR2_SB_CS_N2':
      PIN_NUMBER='(0,0,0,0,0,0,0,0,0,Y38,0,0,0,0,0,0,0,0,0,0,0,0,0,0,0,0,0,0,0,0,0,0,0,0,0,0,0,0,0,0,0,0)';
      OUTPUT_LOAD='(1.0,-1.0)';
    'DDR2_SB_CS_N1':
      PIN_NUMBER='(0,0,0,0,0,0,0,0,0,U37,0,0,0,0,0,0,0,0,0,0,0,0,0,0,0,0,0,0,0,0,0,0,0,0,0,0,0,0,0,0,0,0)';
      OUTPUT_LOAD='(1.0,-1.0)';
    'DDR2_SB_CS_N0':
      PIN_NUMBER='(0,0,0,0,0,0,0,0,0,T38,0,0,0,0,0,0,0,0,0,0,0,0,0,0,0,0,0,0,0,0,0,0,0,0,0,0,0,0,0,0,0,0)';
      OUTPUT_LOAD='(1.0,-1.0)';
    'DDR2_SB_DQ31':
      PIN_NUMBER='(0,0,0,0,0,0,0,0,0,AJ17,0,0,0,0,0,0,0,0,0,0,0,0,0,0,0,0,0,0,0,0,0,0,0,0,0,0,0,0,0,0,0,0)';
      BIDIRECTIONAL='TRUE';
      INPUT_LOAD='(-0.01,0.01)';
      OUTPUT_LOAD='(1.0,-1.0)';
    'DDR2_SB_DQ30':
      PIN_NUMBER='(0,0,0,0,0,0,0,0,0,AC17,0,0,0,0,0,0,0,0,0,0,0,0,0,0,0,0,0,0,0,0,0,0,0,0,0,0,0,0,0,0,0,0)';
      BIDIRECTIONAL='TRUE';
      INPUT_LOAD='(-0.01,0.01)';
      OUTPUT_LOAD='(1.0,-1.0)';
    'DDR2_SB_DQ29':
      PIN_NUMBER='(0,0,0,0,0,0,0,0,0,AG17,0,0,0,0,0,0,0,0,0,0,0,0,0,0,0,0,0,0,0,0,0,0,0,0,0,0,0,0,0,0,0,0)';
      BIDIRECTIONAL='TRUE';
      INPUT_LOAD='(-0.01,0.01)';
      OUTPUT_LOAD='(1.0,-1.0)';
    'DDR2_SB_DQ28':
      PIN_NUMBER='(0,0,0,0,0,0,0,0,0,AA17,0,0,0,0,0,0,0,0,0,0,0,0,0,0,0,0,0,0,0,0,0,0,0,0,0,0,0,0,0,0,0,0)';
      BIDIRECTIONAL='TRUE';
      INPUT_LOAD='(-0.01,0.01)';
      OUTPUT_LOAD='(1.0,-1.0)';
    'DDR2_SB_DQ27':
      PIN_NUMBER='(0,0,0,0,0,0,0,0,0,AG19,0,0,0,0,0,0,0,0,0,0,0,0,0,0,0,0,0,0,0,0,0,0,0,0,0,0,0,0,0,0,0,0)';
      BIDIRECTIONAL='TRUE';
      INPUT_LOAD='(-0.01,0.01)';
      OUTPUT_LOAD='(1.0,-1.0)';
    'DDR2_SB_DQ26':
      PIN_NUMBER='(0,0,0,0,0,0,0,0,0,AF20,0,0,0,0,0,0,0,0,0,0,0,0,0,0,0,0,0,0,0,0,0,0,0,0,0,0,0,0,0,0,0,0)';
      BIDIRECTIONAL='TRUE';
      INPUT_LOAD='(-0.01,0.01)';
      OUTPUT_LOAD='(1.0,-1.0)';
    'DDR2_SB_DQ25':
      PIN_NUMBER='(0,0,0,0,0,0,0,0,0,AC19,0,0,0,0,0,0,0,0,0,0,0,0,0,0,0,0,0,0,0,0,0,0,0,0,0,0,0,0,0,0,0,0)';
      BIDIRECTIONAL='TRUE';
      INPUT_LOAD='(-0.01,0.01)';
      OUTPUT_LOAD='(1.0,-1.0)';
    'DDR2_SB_DQ24':
      PIN_NUMBER='(0,0,0,0,0,0,0,0,0,AD20,0,0,0,0,0,0,0,0,0,0,0,0,0,0,0,0,0,0,0,0,0,0,0,0,0,0,0,0,0,0,0,0)';
      BIDIRECTIONAL='TRUE';
      INPUT_LOAD='(-0.01,0.01)';
      OUTPUT_LOAD='(1.0,-1.0)';
    'DDR2_SB_DQ23':
      PIN_NUMBER='(0,0,0,0,0,0,0,0,0,W19,0,0,0,0,0,0,0,0,0,0,0,0,0,0,0,0,0,0,0,0,0,0,0,0,0,0,0,0,0,0,0,0)';
      BIDIRECTIONAL='TRUE';
      INPUT_LOAD='(-0.01,0.01)';
      OUTPUT_LOAD='(1.0,-1.0)';
    'DDR2_SB_DQ22':
      PIN_NUMBER='(0,0,0,0,0,0,0,0,0,Y20,0,0,0,0,0,0,0,0,0,0,0,0,0,0,0,0,0,0,0,0,0,0,0,0,0,0,0,0,0,0,0,0)';
      BIDIRECTIONAL='TRUE';
      INPUT_LOAD='(-0.01,0.01)';
      OUTPUT_LOAD='(1.0,-1.0)';
    'DDR2_SB_DQ21':
      PIN_NUMBER='(0,0,0,0,0,0,0,0,0,U19,0,0,0,0,0,0,0,0,0,0,0,0,0,0,0,0,0,0,0,0,0,0,0,0,0,0,0,0,0,0,0,0)';
      BIDIRECTIONAL='TRUE';
      INPUT_LOAD='(-0.01,0.01)';
      OUTPUT_LOAD='(1.0,-1.0)';
    'DDR2_SB_DQ20':
      PIN_NUMBER='(0,0,0,0,0,0,0,0,0,T20,0,0,0,0,0,0,0,0,0,0,0,0,0,0,0,0,0,0,0,0,0,0,0,0,0,0,0,0,0,0,0,0)';
      BIDIRECTIONAL='TRUE';
      INPUT_LOAD='(-0.01,0.01)';
      OUTPUT_LOAD='(1.0,-1.0)';
    'DDR2_SB_DQ19':
      PIN_NUMBER='(0,0,0,0,0,0,0,0,0,Y22,0,0,0,0,0,0,0,0,0,0,0,0,0,0,0,0,0,0,0,0,0,0,0,0,0,0,0,0,0,0,0,0)';
      BIDIRECTIONAL='TRUE';
      INPUT_LOAD='(-0.01,0.01)';
      OUTPUT_LOAD='(1.0,-1.0)';
    'DDR2_SB_DQ18':
      PIN_NUMBER='(0,0,0,0,0,0,0,0,0,W23,0,0,0,0,0,0,0,0,0,0,0,0,0,0,0,0,0,0,0,0,0,0,0,0,0,0,0,0,0,0,0,0)';
      BIDIRECTIONAL='TRUE';
      INPUT_LOAD='(-0.01,0.01)';
      OUTPUT_LOAD='(1.0,-1.0)';
    'DDR2_SB_DQ17':
      PIN_NUMBER='(0,0,0,0,0,0,0,0,0,T22,0,0,0,0,0,0,0,0,0,0,0,0,0,0,0,0,0,0,0,0,0,0,0,0,0,0,0,0,0,0,0,0)';
      BIDIRECTIONAL='TRUE';
      INPUT_LOAD='(-0.01,0.01)';
      OUTPUT_LOAD='(1.0,-1.0)';
    'DDR2_SB_DQ16':
      PIN_NUMBER='(0,0,0,0,0,0,0,0,0,U23,0,0,0,0,0,0,0,0,0,0,0,0,0,0,0,0,0,0,0,0,0,0,0,0,0,0,0,0,0,0,0,0)';
      BIDIRECTIONAL='TRUE';
      INPUT_LOAD='(-0.01,0.01)';
      OUTPUT_LOAD='(1.0,-1.0)';
    'DDR2_SB_DQ15':
      PIN_NUMBER='(0,0,0,0,0,0,0,0,0,AF28,0,0,0,0,0,0,0,0,0,0,0,0,0,0,0,0,0,0,0,0,0,0,0,0,0,0,0,0,0,0,0,0)';
      BIDIRECTIONAL='TRUE';
      INPUT_LOAD='(-0.01,0.01)';
      OUTPUT_LOAD='(1.0,-1.0)';
    'DDR2_SB_DQ14':
      PIN_NUMBER='(0,0,0,0,0,0,0,0,0,AG29,0,0,0,0,0,0,0,0,0,0,0,0,0,0,0,0,0,0,0,0,0,0,0,0,0,0,0,0,0,0,0,0)';
      BIDIRECTIONAL='TRUE';
      INPUT_LOAD='(-0.01,0.01)';
      OUTPUT_LOAD='(1.0,-1.0)';
    'DDR2_SB_DQ13':
      PIN_NUMBER='(0,0,0,0,0,0,0,0,0,AD28,0,0,0,0,0,0,0,0,0,0,0,0,0,0,0,0,0,0,0,0,0,0,0,0,0,0,0,0,0,0,0,0)';
      BIDIRECTIONAL='TRUE';
      INPUT_LOAD='(-0.01,0.01)';
      OUTPUT_LOAD='(1.0,-1.0)';
    'DDR2_SB_DQ12':
      PIN_NUMBER='(0,0,0,0,0,0,0,0,0,AC29,0,0,0,0,0,0,0,0,0,0,0,0,0,0,0,0,0,0,0,0,0,0,0,0,0,0,0,0,0,0,0,0)';
      BIDIRECTIONAL='TRUE';
      INPUT_LOAD='(-0.01,0.01)';
      OUTPUT_LOAD='(1.0,-1.0)';
    'DDR2_SB_DQ11':
      PIN_NUMBER='(0,0,0,0,0,0,0,0,0,AG31,0,0,0,0,0,0,0,0,0,0,0,0,0,0,0,0,0,0,0,0,0,0,0,0,0,0,0,0,0,0,0,0)';
      BIDIRECTIONAL='TRUE';
      INPUT_LOAD='(-0.01,0.01)';
      OUTPUT_LOAD='(1.0,-1.0)';
    'DDR2_SB_DQ10':
      PIN_NUMBER='(0,0,0,0,0,0,0,0,0,AF32,0,0,0,0,0,0,0,0,0,0,0,0,0,0,0,0,0,0,0,0,0,0,0,0,0,0,0,0,0,0,0,0)';
      BIDIRECTIONAL='TRUE';
      INPUT_LOAD='(-0.01,0.01)';
      OUTPUT_LOAD='(1.0,-1.0)';
    'DDR2_SB_DQ9':
      PIN_NUMBER='(0,0,0,0,0,0,0,0,0,AC31,0,0,0,0,0,0,0,0,0,0,0,0,0,0,0,0,0,0,0,0,0,0,0,0,0,0,0,0,0,0,0,0)';
      BIDIRECTIONAL='TRUE';
      INPUT_LOAD='(-0.01,0.01)';
      OUTPUT_LOAD='(1.0,-1.0)';
    'DDR2_SB_DQ8':
      PIN_NUMBER='(0,0,0,0,0,0,0,0,0,AD32,0,0,0,0,0,0,0,0,0,0,0,0,0,0,0,0,0,0,0,0,0,0,0,0,0,0,0,0,0,0,0,0)';
      BIDIRECTIONAL='TRUE';
      INPUT_LOAD='(-0.01,0.01)';
      OUTPUT_LOAD='(1.0,-1.0)';
    'DDR2_SB_DQ7':
      PIN_NUMBER='(0,0,0,0,0,0,0,0,0,AF34,0,0,0,0,0,0,0,0,0,0,0,0,0,0,0,0,0,0,0,0,0,0,0,0,0,0,0,0,0,0,0,0)';
      BIDIRECTIONAL='TRUE';
      INPUT_LOAD='(-0.01,0.01)';
      OUTPUT_LOAD='(1.0,-1.0)';
    'DDR2_SB_DQ6':
      PIN_NUMBER='(0,0,0,0,0,0,0,0,0,AG35,0,0,0,0,0,0,0,0,0,0,0,0,0,0,0,0,0,0,0,0,0,0,0,0,0,0,0,0,0,0,0,0)';
      BIDIRECTIONAL='TRUE';
      INPUT_LOAD='(-0.01,0.01)';
      OUTPUT_LOAD='(1.0,-1.0)';
    'DDR2_SB_DQ5':
      PIN_NUMBER='(0,0,0,0,0,0,0,0,0,AD34,0,0,0,0,0,0,0,0,0,0,0,0,0,0,0,0,0,0,0,0,0,0,0,0,0,0,0,0,0,0,0,0)';
      BIDIRECTIONAL='TRUE';
      INPUT_LOAD='(-0.01,0.01)';
      OUTPUT_LOAD='(1.0,-1.0)';
    'DDR2_SB_DQ4':
      PIN_NUMBER='(0,0,0,0,0,0,0,0,0,AC35,0,0,0,0,0,0,0,0,0,0,0,0,0,0,0,0,0,0,0,0,0,0,0,0,0,0,0,0,0,0,0,0)';
      BIDIRECTIONAL='TRUE';
      INPUT_LOAD='(-0.01,0.01)';
      OUTPUT_LOAD='(1.0,-1.0)';
    'DDR2_SB_DQ3':
      PIN_NUMBER='(0,0,0,0,0,0,0,0,0,AG37,0,0,0,0,0,0,0,0,0,0,0,0,0,0,0,0,0,0,0,0,0,0,0,0,0,0,0,0,0,0,0,0)';
      BIDIRECTIONAL='TRUE';
      INPUT_LOAD='(-0.01,0.01)';
      OUTPUT_LOAD='(1.0,-1.0)';
    'DDR2_SB_DQ2':
      PIN_NUMBER='(0,0,0,0,0,0,0,0,0,AF38,0,0,0,0,0,0,0,0,0,0,0,0,0,0,0,0,0,0,0,0,0,0,0,0,0,0,0,0,0,0,0,0)';
      BIDIRECTIONAL='TRUE';
      INPUT_LOAD='(-0.01,0.01)';
      OUTPUT_LOAD='(1.0,-1.0)';
    'DDR2_SB_DQ1':
      PIN_NUMBER='(0,0,0,0,0,0,0,0,0,AC37,0,0,0,0,0,0,0,0,0,0,0,0,0,0,0,0,0,0,0,0,0,0,0,0,0,0,0,0,0,0,0,0)';
      BIDIRECTIONAL='TRUE';
      INPUT_LOAD='(-0.01,0.01)';
      OUTPUT_LOAD='(1.0,-1.0)';
    'DDR2_SB_DQ0':
      PIN_NUMBER='(0,0,0,0,0,0,0,0,0,AD38,0,0,0,0,0,0,0,0,0,0,0,0,0,0,0,0,0,0,0,0,0,0,0,0,0,0,0,0,0,0,0,0)';
      BIDIRECTIONAL='TRUE';
      INPUT_LOAD='(-0.01,0.01)';
      OUTPUT_LOAD='(1.0,-1.0)';
    'DDR2_SB_DQS_DN9':
      PIN_NUMBER='(0,0,0,0,0,0,0,0,0,R33,0,0,0,0,0,0,0,0,0,0,0,0,0,0,0,0,0,0,0,0,0,0,0,0,0,0,0,0,0,0,0,0)';
      BIDIRECTIONAL='TRUE';
      INPUT_LOAD='(-0.01,0.01)';
      OUTPUT_LOAD='(1.0,-1.0)';
    'DDR2_SB_DQS_DN8':
      PIN_NUMBER='(0,0,0,0,0,0,0,0,0,AF18,0,0,0,0,0,0,0,0,0,0,0,0,0,0,0,0,0,0,0,0,0,0,0,0,0,0,0,0,0,0,0,0)';
      BIDIRECTIONAL='TRUE';
      INPUT_LOAD='(-0.01,0.01)';
      OUTPUT_LOAD='(1.0,-1.0)';
    'DDR2_SB_DQS_DN7':
      PIN_NUMBER='(0,0,0,0,0,0,0,0,0,W21,0,0,0,0,0,0,0,0,0,0,0,0,0,0,0,0,0,0,0,0,0,0,0,0,0,0,0,0,0,0,0,0)';
      BIDIRECTIONAL='TRUE';
      INPUT_LOAD='(-0.01,0.01)';
      OUTPUT_LOAD='(1.0,-1.0)';
    'DDR2_SB_DQS_DN6':
      PIN_NUMBER='(0,0,0,0,0,0,0,0,0,AF30,0,0,0,0,0,0,0,0,0,0,0,0,0,0,0,0,0,0,0,0,0,0,0,0,0,0,0,0,0,0,0,0)';
      BIDIRECTIONAL='TRUE';
      INPUT_LOAD='(-0.01,0.01)';
      OUTPUT_LOAD='(1.0,-1.0)';
    'DDR2_SB_DQS_DN5':
      PIN_NUMBER='(0,0,0,0,0,0,0,0,0,AF36,0,0,0,0,0,0,0,0,0,0,0,0,0,0,0,0,0,0,0,0,0,0,0,0,0,0,0,0,0,0,0,0)';
      BIDIRECTIONAL='TRUE';
      INPUT_LOAD='(-0.01,0.01)';
      OUTPUT_LOAD='(1.0,-1.0)';
    'DDR2_SB_DQS_DN4':
      PIN_NUMBER='(0,0,0,0,0,0,0,0,0,W33,0,0,0,0,0,0,0,0,0,0,0,0,0,0,0,0,0,0,0,0,0,0,0,0,0,0,0,0,0,0,0,0)';
      BIDIRECTIONAL='TRUE';
      INPUT_LOAD='(-0.01,0.01)';
      OUTPUT_LOAD='(1.0,-1.0)';
    'DDR2_SB_DQS_DN3':
      PIN_NUMBER='(0,0,0,0,0,0,0,0,0,AB18,0,0,0,0,0,0,0,0,0,0,0,0,0,0,0,0,0,0,0,0,0,0,0,0,0,0,0,0,0,0,0,0)';
      BIDIRECTIONAL='TRUE';
      INPUT_LOAD='(-0.01,0.01)';
      OUTPUT_LOAD='(1.0,-1.0)';
    'DDR2_SB_DQS_DN2':
      PIN_NUMBER='(0,0,0,0,0,0,0,0,0,R21,0,0,0,0,0,0,0,0,0,0,0,0,0,0,0,0,0,0,0,0,0,0,0,0,0,0,0,0,0,0,0,0)';
      BIDIRECTIONAL='TRUE';
      INPUT_LOAD='(-0.01,0.01)';
      OUTPUT_LOAD='(1.0,-1.0)';
    'DDR2_SB_DQS_DN1':
      PIN_NUMBER='(0,0,0,0,0,0,0,0,0,AB30,0,0,0,0,0,0,0,0,0,0,0,0,0,0,0,0,0,0,0,0,0,0,0,0,0,0,0,0,0,0,0,0)';
      BIDIRECTIONAL='TRUE';
      INPUT_LOAD='(-0.01,0.01)';
      OUTPUT_LOAD='(1.0,-1.0)';
    'DDR2_SB_DQS_DN0':
      PIN_NUMBER='(0,0,0,0,0,0,0,0,0,AB36,0,0,0,0,0,0,0,0,0,0,0,0,0,0,0,0,0,0,0,0,0,0,0,0,0,0,0,0,0,0,0,0)';
      BIDIRECTIONAL='TRUE';
      INPUT_LOAD='(-0.01,0.01)';
      OUTPUT_LOAD='(1.0,-1.0)';
    'DDR2_SB_DQS_DP9':
      PIN_NUMBER='(0,0,0,0,0,0,0,0,0,U33,0,0,0,0,0,0,0,0,0,0,0,0,0,0,0,0,0,0,0,0,0,0,0,0,0,0,0,0,0,0,0,0)';
      BIDIRECTIONAL='TRUE';
      INPUT_LOAD='(-0.01,0.01)';
      OUTPUT_LOAD='(1.0,-1.0)';
    'DDR2_SB_DQS_DP8':
      PIN_NUMBER='(0,0,0,0,0,0,0,0,0,AH18,0,0,0,0,0,0,0,0,0,0,0,0,0,0,0,0,0,0,0,0,0,0,0,0,0,0,0,0,0,0,0,0)';
      BIDIRECTIONAL='TRUE';
      INPUT_LOAD='(-0.01,0.01)';
      OUTPUT_LOAD='(1.0,-1.0)';
    'DDR2_SB_DQS_DP7':
      PIN_NUMBER='(0,0,0,0,0,0,0,0,0,AA21,0,0,0,0,0,0,0,0,0,0,0,0,0,0,0,0,0,0,0,0,0,0,0,0,0,0,0,0,0,0,0,0)';
      BIDIRECTIONAL='TRUE';
      INPUT_LOAD='(-0.01,0.01)';
      OUTPUT_LOAD='(1.0,-1.0)';
    'DDR2_SB_DQS_DP6':
      PIN_NUMBER='(0,0,0,0,0,0,0,0,0,AH30,0,0,0,0,0,0,0,0,0,0,0,0,0,0,0,0,0,0,0,0,0,0,0,0,0,0,0,0,0,0,0,0)';
      BIDIRECTIONAL='TRUE';
      INPUT_LOAD='(-0.01,0.01)';
      OUTPUT_LOAD='(1.0,-1.0)';
    'DDR2_SB_DQS_DP5':
      PIN_NUMBER='(0,0,0,0,0,0,0,0,0,AH36,0,0,0,0,0,0,0,0,0,0,0,0,0,0,0,0,0,0,0,0,0,0,0,0,0,0,0,0,0,0,0,0)';
      BIDIRECTIONAL='TRUE';
      INPUT_LOAD='(-0.01,0.01)';
      OUTPUT_LOAD='(1.0,-1.0)';
    'DDR2_SB_DQS_DP4':
      PIN_NUMBER='(0,0,0,0,0,0,0,0,0,AA33,0,0,0,0,0,0,0,0,0,0,0,0,0,0,0,0,0,0,0,0,0,0,0,0,0,0,0,0,0,0,0,0)';
      BIDIRECTIONAL='TRUE';
      INPUT_LOAD='(-0.01,0.01)';
      OUTPUT_LOAD='(1.0,-1.0)';
    'DDR2_SB_DQS_DP3':
      PIN_NUMBER='(0,0,0,0,0,0,0,0,0,AD18,0,0,0,0,0,0,0,0,0,0,0,0,0,0,0,0,0,0,0,0,0,0,0,0,0,0,0,0,0,0,0,0)';
      BIDIRECTIONAL='TRUE';
      INPUT_LOAD='(-0.01,0.01)';
      OUTPUT_LOAD='(1.0,-1.0)';
    'DDR2_SB_DQS_DP2':
      PIN_NUMBER='(0,0,0,0,0,0,0,0,0,U21,0,0,0,0,0,0,0,0,0,0,0,0,0,0,0,0,0,0,0,0,0,0,0,0,0,0,0,0,0,0,0,0)';
      BIDIRECTIONAL='TRUE';
      INPUT_LOAD='(-0.01,0.01)';
      OUTPUT_LOAD='(1.0,-1.0)';
    'DDR2_SB_DQS_DP1':
      PIN_NUMBER='(0,0,0,0,0,0,0,0,0,AD30,0,0,0,0,0,0,0,0,0,0,0,0,0,0,0,0,0,0,0,0,0,0,0,0,0,0,0,0,0,0,0,0)';
      BIDIRECTIONAL='TRUE';
      INPUT_LOAD='(-0.01,0.01)';
      OUTPUT_LOAD='(1.0,-1.0)';
    'DDR2_SB_DQS_DP0':
      PIN_NUMBER='(0,0,0,0,0,0,0,0,0,AD36,0,0,0,0,0,0,0,0,0,0,0,0,0,0,0,0,0,0,0,0,0,0,0,0,0,0,0,0,0,0,0,0)';
      BIDIRECTIONAL='TRUE';
      INPUT_LOAD='(-0.01,0.01)';
      OUTPUT_LOAD='(1.0,-1.0)';
    'DDR2_SB_ECC7':
      PIN_NUMBER='(0,0,0,0,0,0,0,0,0,Y34,0,0,0,0,0,0,0,0,0,0,0,0,0,0,0,0,0,0,0,0,0,0,0,0,0,0,0,0,0,0,0,0)';
      BIDIRECTIONAL='TRUE';
      INPUT_LOAD='(-0.01,0.01)';
      OUTPUT_LOAD='(1.0,-1.0)';
    'DDR2_SB_ECC6':
      PIN_NUMBER='(0,0,0,0,0,0,0,0,0,W35,0,0,0,0,0,0,0,0,0,0,0,0,0,0,0,0,0,0,0,0,0,0,0,0,0,0,0,0,0,0,0,0)';
      BIDIRECTIONAL='TRUE';
      INPUT_LOAD='(-0.01,0.01)';
      OUTPUT_LOAD='(1.0,-1.0)';
    'DDR2_SB_ECC5':
      PIN_NUMBER='(0,0,0,0,0,0,0,0,0,T34,0,0,0,0,0,0,0,0,0,0,0,0,0,0,0,0,0,0,0,0,0,0,0,0,0,0,0,0,0,0,0,0)';
      BIDIRECTIONAL='TRUE';
      INPUT_LOAD='(-0.01,0.01)';
      OUTPUT_LOAD='(1.0,-1.0)';
    'DDR2_SB_ECC4':
      PIN_NUMBER='(0,0,0,0,0,0,0,0,0,U35,0,0,0,0,0,0,0,0,0,0,0,0,0,0,0,0,0,0,0,0,0,0,0,0,0,0,0,0,0,0,0,0)';
      BIDIRECTIONAL='TRUE';
      INPUT_LOAD='(-0.01,0.01)';
      OUTPUT_LOAD='(1.0,-1.0)';
    'DDR2_SB_ECC3':
      PIN_NUMBER='(0,0,0,0,0,0,0,0,0,W31,0,0,0,0,0,0,0,0,0,0,0,0,0,0,0,0,0,0,0,0,0,0,0,0,0,0,0,0,0,0,0,0)';
      BIDIRECTIONAL='TRUE';
      INPUT_LOAD='(-0.01,0.01)';
      OUTPUT_LOAD='(1.0,-1.0)';
    'DDR2_SB_ECC2':
      PIN_NUMBER='(0,0,0,0,0,0,0,0,0,Y32,0,0,0,0,0,0,0,0,0,0,0,0,0,0,0,0,0,0,0,0,0,0,0,0,0,0,0,0,0,0,0,0)';
      BIDIRECTIONAL='TRUE';
      INPUT_LOAD='(-0.01,0.01)';
      OUTPUT_LOAD='(1.0,-1.0)';
    'DDR2_SB_ECC1':
      PIN_NUMBER='(0,0,0,0,0,0,0,0,0,U31,0,0,0,0,0,0,0,0,0,0,0,0,0,0,0,0,0,0,0,0,0,0,0,0,0,0,0,0,0,0,0,0)';
      BIDIRECTIONAL='TRUE';
      INPUT_LOAD='(-0.01,0.01)';
      OUTPUT_LOAD='(1.0,-1.0)';
    'DDR2_SB_ECC0':
      PIN_NUMBER='(0,0,0,0,0,0,0,0,0,T32,0,0,0,0,0,0,0,0,0,0,0,0,0,0,0,0,0,0,0,0,0,0,0,0,0,0,0,0,0,0,0,0)';
      BIDIRECTIONAL='TRUE';
      INPUT_LOAD='(-0.01,0.01)';
      OUTPUT_LOAD='(1.0,-1.0)';
    'DDR2_SB_PAR':
      PIN_NUMBER='(0,0,0,0,0,0,0,0,0,AA39,0,0,0,0,0,0,0,0,0,0,0,0,0,0,0,0,0,0,0,0,0,0,0,0,0,0,0,0,0,0,0,0)';
      OUTPUT_LOAD='(1.0,-1.0)';
    '-DDR3_ALERT':
      PIN_NUMBER='(0,0,0,0,0,0,0,0,0,0,AV47,0,0,0,0,0,0,0,0,0,0,0,0,0,0,0,0,0,0,0,0,0,0,0,0,0,0,0,0,0,0,0)';
      INPUT_LOAD='(-0.01,0.01)';
    'DDR3_A_RSP1':
      PIN_NUMBER='(0,0,0,0,0,0,0,0,0,0,AC50,0,0,0,0,0,0,0,0,0,0,0,0,0,0,0,0,0,0,0,0,0,0,0,0,0,0,0,0,0,0,0)';
      INPUT_LOAD='(-0.01,0.01)';
    'DDR3_A_RSP0':
      PIN_NUMBER='(0,0,0,0,0,0,0,0,0,0,AD51,0,0,0,0,0,0,0,0,0,0,0,0,0,0,0,0,0,0,0,0,0,0,0,0,0,0,0,0,0,0,0)';
      INPUT_LOAD='(-0.01,0.01)';
    'DDR3_B_RSP1':
      PIN_NUMBER='(0,0,0,0,0,0,0,0,0,0,AG50,0,0,0,0,0,0,0,0,0,0,0,0,0,0,0,0,0,0,0,0,0,0,0,0,0,0,0,0,0,0,0)';
      INPUT_LOAD='(-0.01,0.01)';
    'DDR3_B_RSP0':
      PIN_NUMBER='(0,0,0,0,0,0,0,0,0,0,AF51,0,0,0,0,0,0,0,0,0,0,0,0,0,0,0,0,0,0,0,0,0,0,0,0,0,0,0,0,0,0,0)';
      INPUT_LOAD='(-0.01,0.01)';
    'DDR3_CLK_DN1':
      PIN_NUMBER='(0,0,0,0,0,0,0,0,0,0,AN45,0,0,0,0,0,0,0,0,0,0,0,0,0,0,0,0,0,0,0,0,0,0,0,0,0,0,0,0,0,0,0)';
      OUTPUT_LOAD='(1.0,-1.0)';
    'DDR3_CLK_DN0':
      PIN_NUMBER='(0,0,0,0,0,0,0,0,0,0,AJ45,0,0,0,0,0,0,0,0,0,0,0,0,0,0,0,0,0,0,0,0,0,0,0,0,0,0,0,0,0,0,0)';
      OUTPUT_LOAD='(1.0,-1.0)';
    'DDR3_CLK_DP1':
      PIN_NUMBER='(0,0,0,0,0,0,0,0,0,0,AR45,0,0,0,0,0,0,0,0,0,0,0,0,0,0,0,0,0,0,0,0,0,0,0,0,0,0,0,0,0,0,0)';
      OUTPUT_LOAD='(1.0,-1.0)';
    'DDR3_CLK_DP0':
      PIN_NUMBER='(0,0,0,0,0,0,0,0,0,0,AL45,0,0,0,0,0,0,0,0,0,0,0,0,0,0,0,0,0,0,0,0,0,0,0,0,0,0,0,0,0,0,0)';
      OUTPUT_LOAD='(1.0,-1.0)';
    'DDR3_SA_CA6':
      PIN_NUMBER='(0,0,0,0,0,0,0,0,0,0,AN43,0,0,0,0,0,0,0,0,0,0,0,0,0,0,0,0,0,0,0,0,0,0,0,0,0,0,0,0,0,0,0)';
      OUTPUT_LOAD='(1.0,-1.0)';
    'DDR3_SA_CA5':
      PIN_NUMBER='(0,0,0,0,0,0,0,0,0,0,AN50,0,0,0,0,0,0,0,0,0,0,0,0,0,0,0,0,0,0,0,0,0,0,0,0,0,0,0,0,0,0,0)';
      OUTPUT_LOAD='(1.0,-1.0)';
    'DDR3_SA_CA4':
      PIN_NUMBER='(0,0,0,0,0,0,0,0,0,0,AL50,0,0,0,0,0,0,0,0,0,0,0,0,0,0,0,0,0,0,0,0,0,0,0,0,0,0,0,0,0,0,0)';
      OUTPUT_LOAD='(1.0,-1.0)';
    'DDR3_SA_CA3':
      PIN_NUMBER='(0,0,0,0,0,0,0,0,0,0,AP51,0,0,0,0,0,0,0,0,0,0,0,0,0,0,0,0,0,0,0,0,0,0,0,0,0,0,0,0,0,0,0)';
      OUTPUT_LOAD='(1.0,-1.0)';
    'DDR3_SA_CA2':
      PIN_NUMBER='(0,0,0,0,0,0,0,0,0,0,AK51,0,0,0,0,0,0,0,0,0,0,0,0,0,0,0,0,0,0,0,0,0,0,0,0,0,0,0,0,0,0,0)';
      OUTPUT_LOAD='(1.0,-1.0)';
    'DDR3_SA_CA1':
      PIN_NUMBER='(0,0,0,0,0,0,0,0,0,0,AR52,0,0,0,0,0,0,0,0,0,0,0,0,0,0,0,0,0,0,0,0,0,0,0,0,0,0,0,0,0,0,0)';
      OUTPUT_LOAD='(1.0,-1.0)';
    'DDR3_SA_CA0':
      PIN_NUMBER='(0,0,0,0,0,0,0,0,0,0,AJ52,0,0,0,0,0,0,0,0,0,0,0,0,0,0,0,0,0,0,0,0,0,0,0,0,0,0,0,0,0,0,0)';
      OUTPUT_LOAD='(1.0,-1.0)';
    'DDR3_SA_CS_N3':
      PIN_NUMBER='(0,0,0,0,0,0,0,0,0,0,AP53,0,0,0,0,0,0,0,0,0,0,0,0,0,0,0,0,0,0,0,0,0,0,0,0,0,0,0,0,0,0,0)';
      OUTPUT_LOAD='(1.0,-1.0)';
    'DDR3_SA_CS_N2':
      PIN_NUMBER='(0,0,0,0,0,0,0,0,0,0,AN54,0,0,0,0,0,0,0,0,0,0,0,0,0,0,0,0,0,0,0,0,0,0,0,0,0,0,0,0,0,0,0)';
      OUTPUT_LOAD='(1.0,-1.0)';
    'DDR3_SA_CS_N1':
      PIN_NUMBER='(0,0,0,0,0,0,0,0,0,0,AK53,0,0,0,0,0,0,0,0,0,0,0,0,0,0,0,0,0,0,0,0,0,0,0,0,0,0,0,0,0,0,0)';
      OUTPUT_LOAD='(1.0,-1.0)';
    'DDR3_SA_CS_N0':
      PIN_NUMBER='(0,0,0,0,0,0,0,0,0,0,AL54,0,0,0,0,0,0,0,0,0,0,0,0,0,0,0,0,0,0,0,0,0,0,0,0,0,0,0,0,0,0,0)';
      OUTPUT_LOAD='(1.0,-1.0)';
    'DDR3_SA_DQ31':
      PIN_NUMBER='(0,0,0,0,0,0,0,0,0,0,AN62,0,0,0,0,0,0,0,0,0,0,0,0,0,0,0,0,0,0,0,0,0,0,0,0,0,0,0,0,0,0,0)';
      BIDIRECTIONAL='TRUE';
      INPUT_LOAD='(-0.01,0.01)';
      OUTPUT_LOAD='(1.0,-1.0)';
    'DDR3_SA_DQ30':
      PIN_NUMBER='(0,0,0,0,0,0,0,0,0,0,AP63,0,0,0,0,0,0,0,0,0,0,0,0,0,0,0,0,0,0,0,0,0,0,0,0,0,0,0,0,0,0,0)';
      BIDIRECTIONAL='TRUE';
      INPUT_LOAD='(-0.01,0.01)';
      OUTPUT_LOAD='(1.0,-1.0)';
    'DDR3_SA_DQ29':
      PIN_NUMBER='(0,0,0,0,0,0,0,0,0,0,AL62,0,0,0,0,0,0,0,0,0,0,0,0,0,0,0,0,0,0,0,0,0,0,0,0,0,0,0,0,0,0,0)';
      BIDIRECTIONAL='TRUE';
      INPUT_LOAD='(-0.01,0.01)';
      OUTPUT_LOAD='(1.0,-1.0)';
    'DDR3_SA_DQ28':
      PIN_NUMBER='(0,0,0,0,0,0,0,0,0,0,AK63,0,0,0,0,0,0,0,0,0,0,0,0,0,0,0,0,0,0,0,0,0,0,0,0,0,0,0,0,0,0,0)';
      BIDIRECTIONAL='TRUE';
      INPUT_LOAD='(-0.01,0.01)';
      OUTPUT_LOAD='(1.0,-1.0)';
    'DDR3_SA_DQ27':
      PIN_NUMBER='(0,0,0,0,0,0,0,0,0,0,AP65,0,0,0,0,0,0,0,0,0,0,0,0,0,0,0,0,0,0,0,0,0,0,0,0,0,0,0,0,0,0,0)';
      BIDIRECTIONAL='TRUE';
      INPUT_LOAD='(-0.01,0.01)';
      OUTPUT_LOAD='(1.0,-1.0)';
    'DDR3_SA_DQ26':
      PIN_NUMBER='(0,0,0,0,0,0,0,0,0,0,AN66,0,0,0,0,0,0,0,0,0,0,0,0,0,0,0,0,0,0,0,0,0,0,0,0,0,0,0,0,0,0,0)';
      BIDIRECTIONAL='TRUE';
      INPUT_LOAD='(-0.01,0.01)';
      OUTPUT_LOAD='(1.0,-1.0)';
    'DDR3_SA_DQ25':
      PIN_NUMBER='(0,0,0,0,0,0,0,0,0,0,AK65,0,0,0,0,0,0,0,0,0,0,0,0,0,0,0,0,0,0,0,0,0,0,0,0,0,0,0,0,0,0,0)';
      BIDIRECTIONAL='TRUE';
      INPUT_LOAD='(-0.01,0.01)';
      OUTPUT_LOAD='(1.0,-1.0)';
    'DDR3_SA_DQ24':
      PIN_NUMBER='(0,0,0,0,0,0,0,0,0,0,AL66,0,0,0,0,0,0,0,0,0,0,0,0,0,0,0,0,0,0,0,0,0,0,0,0,0,0,0,0,0,0,0)';
      BIDIRECTIONAL='TRUE';
      INPUT_LOAD='(-0.01,0.01)';
      OUTPUT_LOAD='(1.0,-1.0)';
    'DDR3_SA_DQ23':
      PIN_NUMBER='(0,0,0,0,0,0,0,0,0,0,AN68,0,0,0,0,0,0,0,0,0,0,0,0,0,0,0,0,0,0,0,0,0,0,0,0,0,0,0,0,0,0,0)';
      BIDIRECTIONAL='TRUE';
      INPUT_LOAD='(-0.01,0.01)';
      OUTPUT_LOAD='(1.0,-1.0)';
    'DDR3_SA_DQ22':
      PIN_NUMBER='(0,0,0,0,0,0,0,0,0,0,AP69,0,0,0,0,0,0,0,0,0,0,0,0,0,0,0,0,0,0,0,0,0,0,0,0,0,0,0,0,0,0,0)';
      BIDIRECTIONAL='TRUE';
      INPUT_LOAD='(-0.01,0.01)';
      OUTPUT_LOAD='(1.0,-1.0)';
    'DDR3_SA_DQ21':
      PIN_NUMBER='(0,0,0,0,0,0,0,0,0,0,AL68,0,0,0,0,0,0,0,0,0,0,0,0,0,0,0,0,0,0,0,0,0,0,0,0,0,0,0,0,0,0,0)';
      BIDIRECTIONAL='TRUE';
      INPUT_LOAD='(-0.01,0.01)';
      OUTPUT_LOAD='(1.0,-1.0)';
    'DDR3_SA_DQ20':
      PIN_NUMBER='(0,0,0,0,0,0,0,0,0,0,AK69,0,0,0,0,0,0,0,0,0,0,0,0,0,0,0,0,0,0,0,0,0,0,0,0,0,0,0,0,0,0,0)';
      BIDIRECTIONAL='TRUE';
      INPUT_LOAD='(-0.01,0.01)';
      OUTPUT_LOAD='(1.0,-1.0)';
    'DDR3_SA_DQ19':
      PIN_NUMBER='(0,0,0,0,0,0,0,0,0,0,AP71,0,0,0,0,0,0,0,0,0,0,0,0,0,0,0,0,0,0,0,0,0,0,0,0,0,0,0,0,0,0,0)';
      BIDIRECTIONAL='TRUE';
      INPUT_LOAD='(-0.01,0.01)';
      OUTPUT_LOAD='(1.0,-1.0)';
    'DDR3_SA_DQ18':
      PIN_NUMBER='(0,0,0,0,0,0,0,0,0,0,AN72,0,0,0,0,0,0,0,0,0,0,0,0,0,0,0,0,0,0,0,0,0,0,0,0,0,0,0,0,0,0,0)';
      BIDIRECTIONAL='TRUE';
      INPUT_LOAD='(-0.01,0.01)';
      OUTPUT_LOAD='(1.0,-1.0)';
    'DDR3_SA_DQ17':
      PIN_NUMBER='(0,0,0,0,0,0,0,0,0,0,AK71,0,0,0,0,0,0,0,0,0,0,0,0,0,0,0,0,0,0,0,0,0,0,0,0,0,0,0,0,0,0,0)';
      BIDIRECTIONAL='TRUE';
      INPUT_LOAD='(-0.01,0.01)';
      OUTPUT_LOAD='(1.0,-1.0)';
    'DDR3_SA_DQ16':
      PIN_NUMBER='(0,0,0,0,0,0,0,0,0,0,AL72,0,0,0,0,0,0,0,0,0,0,0,0,0,0,0,0,0,0,0,0,0,0,0,0,0,0,0,0,0,0,0)';
      BIDIRECTIONAL='TRUE';
      INPUT_LOAD='(-0.01,0.01)';
      OUTPUT_LOAD='(1.0,-1.0)';
    'DDR3_SA_DQ15':
      PIN_NUMBER='(0,0,0,0,0,0,0,0,0,0,AN74,0,0,0,0,0,0,0,0,0,0,0,0,0,0,0,0,0,0,0,0,0,0,0,0,0,0,0,0,0,0,0)';
      BIDIRECTIONAL='TRUE';
      INPUT_LOAD='(-0.01,0.01)';
      OUTPUT_LOAD='(1.0,-1.0)';
    'DDR3_SA_DQ14':
      PIN_NUMBER='(0,0,0,0,0,0,0,0,0,0,AP75,0,0,0,0,0,0,0,0,0,0,0,0,0,0,0,0,0,0,0,0,0,0,0,0,0,0,0,0,0,0,0)';
      BIDIRECTIONAL='TRUE';
      INPUT_LOAD='(-0.01,0.01)';
      OUTPUT_LOAD='(1.0,-1.0)';
    'DDR3_SA_DQ13':
      PIN_NUMBER='(0,0,0,0,0,0,0,0,0,0,AL74,0,0,0,0,0,0,0,0,0,0,0,0,0,0,0,0,0,0,0,0,0,0,0,0,0,0,0,0,0,0,0)';
      BIDIRECTIONAL='TRUE';
      INPUT_LOAD='(-0.01,0.01)';
      OUTPUT_LOAD='(1.0,-1.0)';
    'DDR3_SA_DQ12':
      PIN_NUMBER='(0,0,0,0,0,0,0,0,0,0,AK75,0,0,0,0,0,0,0,0,0,0,0,0,0,0,0,0,0,0,0,0,0,0,0,0,0,0,0,0,0,0,0)';
      BIDIRECTIONAL='TRUE';
      INPUT_LOAD='(-0.01,0.01)';
      OUTPUT_LOAD='(1.0,-1.0)';
    'DDR3_SA_DQ11':
      PIN_NUMBER='(0,0,0,0,0,0,0,0,0,0,AP77,0,0,0,0,0,0,0,0,0,0,0,0,0,0,0,0,0,0,0,0,0,0,0,0,0,0,0,0,0,0,0)';
      BIDIRECTIONAL='TRUE';
      INPUT_LOAD='(-0.01,0.01)';
      OUTPUT_LOAD='(1.0,-1.0)';
    'DDR3_SA_DQ10':
      PIN_NUMBER='(0,0,0,0,0,0,0,0,0,0,AN78,0,0,0,0,0,0,0,0,0,0,0,0,0,0,0,0,0,0,0,0,0,0,0,0,0,0,0,0,0,0,0)';
      BIDIRECTIONAL='TRUE';
      INPUT_LOAD='(-0.01,0.01)';
      OUTPUT_LOAD='(1.0,-1.0)';
    'DDR3_SA_DQ9':
      PIN_NUMBER='(0,0,0,0,0,0,0,0,0,0,AK77,0,0,0,0,0,0,0,0,0,0,0,0,0,0,0,0,0,0,0,0,0,0,0,0,0,0,0,0,0,0,0)';
      BIDIRECTIONAL='TRUE';
      INPUT_LOAD='(-0.01,0.01)';
      OUTPUT_LOAD='(1.0,-1.0)';
    'DDR3_SA_DQ8':
      PIN_NUMBER='(0,0,0,0,0,0,0,0,0,0,AL78,0,0,0,0,0,0,0,0,0,0,0,0,0,0,0,0,0,0,0,0,0,0,0,0,0,0,0,0,0,0,0)';
      BIDIRECTIONAL='TRUE';
      INPUT_LOAD='(-0.01,0.01)';
      OUTPUT_LOAD='(1.0,-1.0)';
    'DDR3_SA_DQ7':
      PIN_NUMBER='(0,0,0,0,0,0,0,0,0,0,AF71,0,0,0,0,0,0,0,0,0,0,0,0,0,0,0,0,0,0,0,0,0,0,0,0,0,0,0,0,0,0,0)';
      BIDIRECTIONAL='TRUE';
      INPUT_LOAD='(-0.01,0.01)';
      OUTPUT_LOAD='(1.0,-1.0)';
    'DDR3_SA_DQ6':
      PIN_NUMBER='(0,0,0,0,0,0,0,0,0,0,AG72,0,0,0,0,0,0,0,0,0,0,0,0,0,0,0,0,0,0,0,0,0,0,0,0,0,0,0,0,0,0,0)';
      BIDIRECTIONAL='TRUE';
      INPUT_LOAD='(-0.01,0.01)';
      OUTPUT_LOAD='(1.0,-1.0)';
    'DDR3_SA_DQ5':
      PIN_NUMBER='(0,0,0,0,0,0,0,0,0,0,AD71,0,0,0,0,0,0,0,0,0,0,0,0,0,0,0,0,0,0,0,0,0,0,0,0,0,0,0,0,0,0,0)';
      BIDIRECTIONAL='TRUE';
      INPUT_LOAD='(-0.01,0.01)';
      OUTPUT_LOAD='(1.0,-1.0)';
    'DDR3_SA_DQ4':
      PIN_NUMBER='(0,0,0,0,0,0,0,0,0,0,AC72,0,0,0,0,0,0,0,0,0,0,0,0,0,0,0,0,0,0,0,0,0,0,0,0,0,0,0,0,0,0,0)';
      BIDIRECTIONAL='TRUE';
      INPUT_LOAD='(-0.01,0.01)';
      OUTPUT_LOAD='(1.0,-1.0)';
    'DDR3_SA_DQ3':
      PIN_NUMBER='(0,0,0,0,0,0,0,0,0,0,AG74,0,0,0,0,0,0,0,0,0,0,0,0,0,0,0,0,0,0,0,0,0,0,0,0,0,0,0,0,0,0,0)';
      BIDIRECTIONAL='TRUE';
      INPUT_LOAD='(-0.01,0.01)';
      OUTPUT_LOAD='(1.0,-1.0)';
    'DDR3_SA_DQ2':
      PIN_NUMBER='(0,0,0,0,0,0,0,0,0,0,AF75,0,0,0,0,0,0,0,0,0,0,0,0,0,0,0,0,0,0,0,0,0,0,0,0,0,0,0,0,0,0,0)';
      BIDIRECTIONAL='TRUE';
      INPUT_LOAD='(-0.01,0.01)';
      OUTPUT_LOAD='(1.0,-1.0)';
    'DDR3_SA_DQ1':
      PIN_NUMBER='(0,0,0,0,0,0,0,0,0,0,AC74,0,0,0,0,0,0,0,0,0,0,0,0,0,0,0,0,0,0,0,0,0,0,0,0,0,0,0,0,0,0,0)';
      BIDIRECTIONAL='TRUE';
      INPUT_LOAD='(-0.01,0.01)';
      OUTPUT_LOAD='(1.0,-1.0)';
    'DDR3_SA_DQ0':
      PIN_NUMBER='(0,0,0,0,0,0,0,0,0,0,AD75,0,0,0,0,0,0,0,0,0,0,0,0,0,0,0,0,0,0,0,0,0,0,0,0,0,0,0,0,0,0,0)';
      BIDIRECTIONAL='TRUE';
      INPUT_LOAD='(-0.01,0.01)';
      OUTPUT_LOAD='(1.0,-1.0)';
    'DDR3_SA_DQS_DN9':
      PIN_NUMBER='(0,0,0,0,0,0,0,0,0,0,AN58,0,0,0,0,0,0,0,0,0,0,0,0,0,0,0,0,0,0,0,0,0,0,0,0,0,0,0,0,0,0,0)';
      BIDIRECTIONAL='TRUE';
      INPUT_LOAD='(-0.01,0.01)';
      OUTPUT_LOAD='(1.0,-1.0)';
    'DDR3_SA_DQS_DN8':
      PIN_NUMBER='(0,0,0,0,0,0,0,0,0,0,AN64,0,0,0,0,0,0,0,0,0,0,0,0,0,0,0,0,0,0,0,0,0,0,0,0,0,0,0,0,0,0,0)';
      BIDIRECTIONAL='TRUE';
      INPUT_LOAD='(-0.01,0.01)';
      OUTPUT_LOAD='(1.0,-1.0)';
    'DDR3_SA_DQS_DN7':
      PIN_NUMBER='(0,0,0,0,0,0,0,0,0,0,AN70,0,0,0,0,0,0,0,0,0,0,0,0,0,0,0,0,0,0,0,0,0,0,0,0,0,0,0,0,0,0,0)';
      BIDIRECTIONAL='TRUE';
      INPUT_LOAD='(-0.01,0.01)';
      OUTPUT_LOAD='(1.0,-1.0)';
    'DDR3_SA_DQS_DN6':
      PIN_NUMBER='(0,0,0,0,0,0,0,0,0,0,AN76,0,0,0,0,0,0,0,0,0,0,0,0,0,0,0,0,0,0,0,0,0,0,0,0,0,0,0,0,0,0,0)';
      BIDIRECTIONAL='TRUE';
      INPUT_LOAD='(-0.01,0.01)';
      OUTPUT_LOAD='(1.0,-1.0)';
    'DDR3_SA_DQS_DN5':
      PIN_NUMBER='(0,0,0,0,0,0,0,0,0,0,AH73,0,0,0,0,0,0,0,0,0,0,0,0,0,0,0,0,0,0,0,0,0,0,0,0,0,0,0,0,0,0,0)';
      BIDIRECTIONAL='TRUE';
      INPUT_LOAD='(-0.01,0.01)';
      OUTPUT_LOAD='(1.0,-1.0)';
    'DDR3_SA_DQS_DN4':
      PIN_NUMBER='(0,0,0,0,0,0,0,0,0,0,AJ58,0,0,0,0,0,0,0,0,0,0,0,0,0,0,0,0,0,0,0,0,0,0,0,0,0,0,0,0,0,0,0)';
      BIDIRECTIONAL='TRUE';
      INPUT_LOAD='(-0.01,0.01)';
      OUTPUT_LOAD='(1.0,-1.0)';
    'DDR3_SA_DQS_DN3':
      PIN_NUMBER='(0,0,0,0,0,0,0,0,0,0,AJ64,0,0,0,0,0,0,0,0,0,0,0,0,0,0,0,0,0,0,0,0,0,0,0,0,0,0,0,0,0,0,0)';
      BIDIRECTIONAL='TRUE';
      INPUT_LOAD='(-0.01,0.01)';
      OUTPUT_LOAD='(1.0,-1.0)';
    'DDR3_SA_DQS_DN2':
      PIN_NUMBER='(0,0,0,0,0,0,0,0,0,0,AJ70,0,0,0,0,0,0,0,0,0,0,0,0,0,0,0,0,0,0,0,0,0,0,0,0,0,0,0,0,0,0,0)';
      BIDIRECTIONAL='TRUE';
      INPUT_LOAD='(-0.01,0.01)';
      OUTPUT_LOAD='(1.0,-1.0)';
    'DDR3_SA_DQS_DN1':
      PIN_NUMBER='(0,0,0,0,0,0,0,0,0,0,AJ76,0,0,0,0,0,0,0,0,0,0,0,0,0,0,0,0,0,0,0,0,0,0,0,0,0,0,0,0,0,0,0)';
      BIDIRECTIONAL='TRUE';
      INPUT_LOAD='(-0.01,0.01)';
      OUTPUT_LOAD='(1.0,-1.0)';
    'DDR3_SA_DQS_DN0':
      PIN_NUMBER='(0,0,0,0,0,0,0,0,0,0,AB73,0,0,0,0,0,0,0,0,0,0,0,0,0,0,0,0,0,0,0,0,0,0,0,0,0,0,0,0,0,0,0)';
      BIDIRECTIONAL='TRUE';
      INPUT_LOAD='(-0.01,0.01)';
      OUTPUT_LOAD='(1.0,-1.0)';
    'DDR3_SA_DQS_DP9':
      PIN_NUMBER='(0,0,0,0,0,0,0,0,0,0,AR58,0,0,0,0,0,0,0,0,0,0,0,0,0,0,0,0,0,0,0,0,0,0,0,0,0,0,0,0,0,0,0)';
      BIDIRECTIONAL='TRUE';
      INPUT_LOAD='(-0.01,0.01)';
      OUTPUT_LOAD='(1.0,-1.0)';
    'DDR3_SA_DQS_DP8':
      PIN_NUMBER='(0,0,0,0,0,0,0,0,0,0,AR64,0,0,0,0,0,0,0,0,0,0,0,0,0,0,0,0,0,0,0,0,0,0,0,0,0,0,0,0,0,0,0)';
      BIDIRECTIONAL='TRUE';
      INPUT_LOAD='(-0.01,0.01)';
      OUTPUT_LOAD='(1.0,-1.0)';
    'DDR3_SA_DQS_DP7':
      PIN_NUMBER='(0,0,0,0,0,0,0,0,0,0,AR70,0,0,0,0,0,0,0,0,0,0,0,0,0,0,0,0,0,0,0,0,0,0,0,0,0,0,0,0,0,0,0)';
      BIDIRECTIONAL='TRUE';
      INPUT_LOAD='(-0.01,0.01)';
      OUTPUT_LOAD='(1.0,-1.0)';
    'DDR3_SA_DQS_DP6':
      PIN_NUMBER='(0,0,0,0,0,0,0,0,0,0,AR76,0,0,0,0,0,0,0,0,0,0,0,0,0,0,0,0,0,0,0,0,0,0,0,0,0,0,0,0,0,0,0)';
      BIDIRECTIONAL='TRUE';
      INPUT_LOAD='(-0.01,0.01)';
      OUTPUT_LOAD='(1.0,-1.0)';
    'DDR3_SA_DQS_DP5':
      PIN_NUMBER='(0,0,0,0,0,0,0,0,0,0,AF73,0,0,0,0,0,0,0,0,0,0,0,0,0,0,0,0,0,0,0,0,0,0,0,0,0,0,0,0,0,0,0)';
      BIDIRECTIONAL='TRUE';
      INPUT_LOAD='(-0.01,0.01)';
      OUTPUT_LOAD='(1.0,-1.0)';
    'DDR3_SA_DQS_DP4':
      PIN_NUMBER='(0,0,0,0,0,0,0,0,0,0,AL58,0,0,0,0,0,0,0,0,0,0,0,0,0,0,0,0,0,0,0,0,0,0,0,0,0,0,0,0,0,0,0)';
      BIDIRECTIONAL='TRUE';
      INPUT_LOAD='(-0.01,0.01)';
      OUTPUT_LOAD='(1.0,-1.0)';
    'DDR3_SA_DQS_DP3':
      PIN_NUMBER='(0,0,0,0,0,0,0,0,0,0,AL64,0,0,0,0,0,0,0,0,0,0,0,0,0,0,0,0,0,0,0,0,0,0,0,0,0,0,0,0,0,0,0)';
      BIDIRECTIONAL='TRUE';
      INPUT_LOAD='(-0.01,0.01)';
      OUTPUT_LOAD='(1.0,-1.0)';
    'DDR3_SA_DQS_DP2':
      PIN_NUMBER='(0,0,0,0,0,0,0,0,0,0,AL70,0,0,0,0,0,0,0,0,0,0,0,0,0,0,0,0,0,0,0,0,0,0,0,0,0,0,0,0,0,0,0)';
      BIDIRECTIONAL='TRUE';
      INPUT_LOAD='(-0.01,0.01)';
      OUTPUT_LOAD='(1.0,-1.0)';
    'DDR3_SA_DQS_DP1':
      PIN_NUMBER='(0,0,0,0,0,0,0,0,0,0,AL76,0,0,0,0,0,0,0,0,0,0,0,0,0,0,0,0,0,0,0,0,0,0,0,0,0,0,0,0,0,0,0)';
      BIDIRECTIONAL='TRUE';
      INPUT_LOAD='(-0.01,0.01)';
      OUTPUT_LOAD='(1.0,-1.0)';
    'DDR3_SA_DQS_DP0':
      PIN_NUMBER='(0,0,0,0,0,0,0,0,0,0,AD73,0,0,0,0,0,0,0,0,0,0,0,0,0,0,0,0,0,0,0,0,0,0,0,0,0,0,0,0,0,0,0)';
      BIDIRECTIONAL='TRUE';
      INPUT_LOAD='(-0.01,0.01)';
      OUTPUT_LOAD='(1.0,-1.0)';
    'DDR3_SA_ECC7':
      PIN_NUMBER='(0,0,0,0,0,0,0,0,0,0,AN56,0,0,0,0,0,0,0,0,0,0,0,0,0,0,0,0,0,0,0,0,0,0,0,0,0,0,0,0,0,0,0)';
      BIDIRECTIONAL='TRUE';
      INPUT_LOAD='(-0.01,0.01)';
      OUTPUT_LOAD='(1.0,-1.0)';
    'DDR3_SA_ECC6':
      PIN_NUMBER='(0,0,0,0,0,0,0,0,0,0,AP57,0,0,0,0,0,0,0,0,0,0,0,0,0,0,0,0,0,0,0,0,0,0,0,0,0,0,0,0,0,0,0)';
      BIDIRECTIONAL='TRUE';
      INPUT_LOAD='(-0.01,0.01)';
      OUTPUT_LOAD='(1.0,-1.0)';
    'DDR3_SA_ECC5':
      PIN_NUMBER='(0,0,0,0,0,0,0,0,0,0,AL56,0,0,0,0,0,0,0,0,0,0,0,0,0,0,0,0,0,0,0,0,0,0,0,0,0,0,0,0,0,0,0)';
      BIDIRECTIONAL='TRUE';
      INPUT_LOAD='(-0.01,0.01)';
      OUTPUT_LOAD='(1.0,-1.0)';
    'DDR3_SA_ECC4':
      PIN_NUMBER='(0,0,0,0,0,0,0,0,0,0,AK57,0,0,0,0,0,0,0,0,0,0,0,0,0,0,0,0,0,0,0,0,0,0,0,0,0,0,0,0,0,0,0)';
      BIDIRECTIONAL='TRUE';
      INPUT_LOAD='(-0.01,0.01)';
      OUTPUT_LOAD='(1.0,-1.0)';
    'DDR3_SA_ECC3':
      PIN_NUMBER='(0,0,0,0,0,0,0,0,0,0,AP59,0,0,0,0,0,0,0,0,0,0,0,0,0,0,0,0,0,0,0,0,0,0,0,0,0,0,0,0,0,0,0)';
      BIDIRECTIONAL='TRUE';
      INPUT_LOAD='(-0.01,0.01)';
      OUTPUT_LOAD='(1.0,-1.0)';
    'DDR3_SA_ECC2':
      PIN_NUMBER='(0,0,0,0,0,0,0,0,0,0,AN60,0,0,0,0,0,0,0,0,0,0,0,0,0,0,0,0,0,0,0,0,0,0,0,0,0,0,0,0,0,0,0)';
      BIDIRECTIONAL='TRUE';
      INPUT_LOAD='(-0.01,0.01)';
      OUTPUT_LOAD='(1.0,-1.0)';
    'DDR3_SA_ECC1':
      PIN_NUMBER='(0,0,0,0,0,0,0,0,0,0,AK59,0,0,0,0,0,0,0,0,0,0,0,0,0,0,0,0,0,0,0,0,0,0,0,0,0,0,0,0,0,0,0)';
      BIDIRECTIONAL='TRUE';
      INPUT_LOAD='(-0.01,0.01)';
      OUTPUT_LOAD='(1.0,-1.0)';
    'DDR3_SA_ECC0':
      PIN_NUMBER='(0,0,0,0,0,0,0,0,0,0,AL60,0,0,0,0,0,0,0,0,0,0,0,0,0,0,0,0,0,0,0,0,0,0,0,0,0,0,0,0,0,0,0)';
      BIDIRECTIONAL='TRUE';
      INPUT_LOAD='(-0.01,0.01)';
      OUTPUT_LOAD='(1.0,-1.0)';
    'DDR3_SA_PAR':
      PIN_NUMBER='(0,0,0,0,0,0,0,0,0,0,AP44,0,0,0,0,0,0,0,0,0,0,0,0,0,0,0,0,0,0,0,0,0,0,0,0,0,0,0,0,0,0,0)';
      OUTPUT_LOAD='(1.0,-1.0)';
    'DDR3_SB_CA6':
      PIN_NUMBER='(0,0,0,0,0,0,0,0,0,0,AB42,0,0,0,0,0,0,0,0,0,0,0,0,0,0,0,0,0,0,0,0,0,0,0,0,0,0,0,0,0,0,0)';
      OUTPUT_LOAD='(1.0,-1.0)';
    'DDR3_SB_CA5':
      PIN_NUMBER='(0,0,0,0,0,0,0,0,0,0,AG43,0,0,0,0,0,0,0,0,0,0,0,0,0,0,0,0,0,0,0,0,0,0,0,0,0,0,0,0,0,0,0)';
      OUTPUT_LOAD='(1.0,-1.0)';
    'DDR3_SB_CA4':
      PIN_NUMBER='(0,0,0,0,0,0,0,0,0,0,AC43,0,0,0,0,0,0,0,0,0,0,0,0,0,0,0,0,0,0,0,0,0,0,0,0,0,0,0,0,0,0,0)';
      OUTPUT_LOAD='(1.0,-1.0)';
    'DDR3_SB_CA3':
      PIN_NUMBER='(0,0,0,0,0,0,0,0,0,0,AF44,0,0,0,0,0,0,0,0,0,0,0,0,0,0,0,0,0,0,0,0,0,0,0,0,0,0,0,0,0,0,0)';
      OUTPUT_LOAD='(1.0,-1.0)';
    'DDR3_SB_CA2':
      PIN_NUMBER='(0,0,0,0,0,0,0,0,0,0,AD44,0,0,0,0,0,0,0,0,0,0,0,0,0,0,0,0,0,0,0,0,0,0,0,0,0,0,0,0,0,0,0)';
      OUTPUT_LOAD='(1.0,-1.0)';
    'DDR3_SB_CA1':
      PIN_NUMBER='(0,0,0,0,0,0,0,0,0,0,AL43,0,0,0,0,0,0,0,0,0,0,0,0,0,0,0,0,0,0,0,0,0,0,0,0,0,0,0,0,0,0,0)';
      OUTPUT_LOAD='(1.0,-1.0)';
    'DDR3_SB_CA0':
      PIN_NUMBER='(0,0,0,0,0,0,0,0,0,0,AK44,0,0,0,0,0,0,0,0,0,0,0,0,0,0,0,0,0,0,0,0,0,0,0,0,0,0,0,0,0,0,0)';
      OUTPUT_LOAD='(1.0,-1.0)';
    'DDR3_SB_CS_N3':
      PIN_NUMBER='(0,0,0,0,0,0,0,0,0,0,AD40,0,0,0,0,0,0,0,0,0,0,0,0,0,0,0,0,0,0,0,0,0,0,0,0,0,0,0,0,0,0,0)';
      OUTPUT_LOAD='(1.0,-1.0)';
    'DDR3_SB_CS_N2':
      PIN_NUMBER='(0,0,0,0,0,0,0,0,0,0,AF40,0,0,0,0,0,0,0,0,0,0,0,0,0,0,0,0,0,0,0,0,0,0,0,0,0,0,0,0,0,0,0)';
      OUTPUT_LOAD='(1.0,-1.0)';
    'DDR3_SB_CS_N1':
      PIN_NUMBER='(0,0,0,0,0,0,0,0,0,0,AG41,0,0,0,0,0,0,0,0,0,0,0,0,0,0,0,0,0,0,0,0,0,0,0,0,0,0,0,0,0,0,0)';
      OUTPUT_LOAD='(1.0,-1.0)';
    'DDR3_SB_CS_N0':
      PIN_NUMBER='(0,0,0,0,0,0,0,0,0,0,AC41,0,0,0,0,0,0,0,0,0,0,0,0,0,0,0,0,0,0,0,0,0,0,0,0,0,0,0,0,0,0,0)';
      OUTPUT_LOAD='(1.0,-1.0)';
    'DDR3_SB_DQ31':
      PIN_NUMBER='(0,0,0,0,0,0,0,0,0,0,AN19,0,0,0,0,0,0,0,0,0,0,0,0,0,0,0,0,0,0,0,0,0,0,0,0,0,0,0,0,0,0,0)';
      BIDIRECTIONAL='TRUE';
      INPUT_LOAD='(-0.01,0.01)';
      OUTPUT_LOAD='(1.0,-1.0)';
    'DDR3_SB_DQ30':
      PIN_NUMBER='(0,0,0,0,0,0,0,0,0,0,AP20,0,0,0,0,0,0,0,0,0,0,0,0,0,0,0,0,0,0,0,0,0,0,0,0,0,0,0,0,0,0,0)';
      BIDIRECTIONAL='TRUE';
      INPUT_LOAD='(-0.01,0.01)';
      OUTPUT_LOAD='(1.0,-1.0)';
    'DDR3_SB_DQ29':
      PIN_NUMBER='(0,0,0,0,0,0,0,0,0,0,AL19,0,0,0,0,0,0,0,0,0,0,0,0,0,0,0,0,0,0,0,0,0,0,0,0,0,0,0,0,0,0,0)';
      BIDIRECTIONAL='TRUE';
      INPUT_LOAD='(-0.01,0.01)';
      OUTPUT_LOAD='(1.0,-1.0)';
    'DDR3_SB_DQ28':
      PIN_NUMBER='(0,0,0,0,0,0,0,0,0,0,AK20,0,0,0,0,0,0,0,0,0,0,0,0,0,0,0,0,0,0,0,0,0,0,0,0,0,0,0,0,0,0,0)';
      BIDIRECTIONAL='TRUE';
      INPUT_LOAD='(-0.01,0.01)';
      OUTPUT_LOAD='(1.0,-1.0)';
    'DDR3_SB_DQ27':
      PIN_NUMBER='(0,0,0,0,0,0,0,0,0,0,AP22,0,0,0,0,0,0,0,0,0,0,0,0,0,0,0,0,0,0,0,0,0,0,0,0,0,0,0,0,0,0,0)';
      BIDIRECTIONAL='TRUE';
      INPUT_LOAD='(-0.01,0.01)';
      OUTPUT_LOAD='(1.0,-1.0)';
    'DDR3_SB_DQ26':
      PIN_NUMBER='(0,0,0,0,0,0,0,0,0,0,AN23,0,0,0,0,0,0,0,0,0,0,0,0,0,0,0,0,0,0,0,0,0,0,0,0,0,0,0,0,0,0,0)';
      BIDIRECTIONAL='TRUE';
      INPUT_LOAD='(-0.01,0.01)';
      OUTPUT_LOAD='(1.0,-1.0)';
    'DDR3_SB_DQ25':
      PIN_NUMBER='(0,0,0,0,0,0,0,0,0,0,AK22,0,0,0,0,0,0,0,0,0,0,0,0,0,0,0,0,0,0,0,0,0,0,0,0,0,0,0,0,0,0,0)';
      BIDIRECTIONAL='TRUE';
      INPUT_LOAD='(-0.01,0.01)';
      OUTPUT_LOAD='(1.0,-1.0)';
    'DDR3_SB_DQ24':
      PIN_NUMBER='(0,0,0,0,0,0,0,0,0,0,AL23,0,0,0,0,0,0,0,0,0,0,0,0,0,0,0,0,0,0,0,0,0,0,0,0,0,0,0,0,0,0,0)';
      BIDIRECTIONAL='TRUE';
      INPUT_LOAD='(-0.01,0.01)';
      OUTPUT_LOAD='(1.0,-1.0)';
    'DDR3_SB_DQ23':
      PIN_NUMBER='(0,0,0,0,0,0,0,0,0,0,AF22,0,0,0,0,0,0,0,0,0,0,0,0,0,0,0,0,0,0,0,0,0,0,0,0,0,0,0,0,0,0,0)';
      BIDIRECTIONAL='TRUE';
      INPUT_LOAD='(-0.01,0.01)';
      OUTPUT_LOAD='(1.0,-1.0)';
    'DDR3_SB_DQ22':
      PIN_NUMBER='(0,0,0,0,0,0,0,0,0,0,AG23,0,0,0,0,0,0,0,0,0,0,0,0,0,0,0,0,0,0,0,0,0,0,0,0,0,0,0,0,0,0,0)';
      BIDIRECTIONAL='TRUE';
      INPUT_LOAD='(-0.01,0.01)';
      OUTPUT_LOAD='(1.0,-1.0)';
    'DDR3_SB_DQ21':
      PIN_NUMBER='(0,0,0,0,0,0,0,0,0,0,AD22,0,0,0,0,0,0,0,0,0,0,0,0,0,0,0,0,0,0,0,0,0,0,0,0,0,0,0,0,0,0,0)';
      BIDIRECTIONAL='TRUE';
      INPUT_LOAD='(-0.01,0.01)';
      OUTPUT_LOAD='(1.0,-1.0)';
    'DDR3_SB_DQ20':
      PIN_NUMBER='(0,0,0,0,0,0,0,0,0,0,AC23,0,0,0,0,0,0,0,0,0,0,0,0,0,0,0,0,0,0,0,0,0,0,0,0,0,0,0,0,0,0,0)';
      BIDIRECTIONAL='TRUE';
      INPUT_LOAD='(-0.01,0.01)';
      OUTPUT_LOAD='(1.0,-1.0)';
    'DDR3_SB_DQ19':
      PIN_NUMBER='(0,0,0,0,0,0,0,0,0,0,AG25,0,0,0,0,0,0,0,0,0,0,0,0,0,0,0,0,0,0,0,0,0,0,0,0,0,0,0,0,0,0,0)';
      BIDIRECTIONAL='TRUE';
      INPUT_LOAD='(-0.01,0.01)';
      OUTPUT_LOAD='(1.0,-1.0)';
    'DDR3_SB_DQ18':
      PIN_NUMBER='(0,0,0,0,0,0,0,0,0,0,AF26,0,0,0,0,0,0,0,0,0,0,0,0,0,0,0,0,0,0,0,0,0,0,0,0,0,0,0,0,0,0,0)';
      BIDIRECTIONAL='TRUE';
      INPUT_LOAD='(-0.01,0.01)';
      OUTPUT_LOAD='(1.0,-1.0)';
    'DDR3_SB_DQ17':
      PIN_NUMBER='(0,0,0,0,0,0,0,0,0,0,AC25,0,0,0,0,0,0,0,0,0,0,0,0,0,0,0,0,0,0,0,0,0,0,0,0,0,0,0,0,0,0,0)';
      BIDIRECTIONAL='TRUE';
      INPUT_LOAD='(-0.01,0.01)';
      OUTPUT_LOAD='(1.0,-1.0)';
    'DDR3_SB_DQ16':
      PIN_NUMBER='(0,0,0,0,0,0,0,0,0,0,AD26,0,0,0,0,0,0,0,0,0,0,0,0,0,0,0,0,0,0,0,0,0,0,0,0,0,0,0,0,0,0,0)';
      BIDIRECTIONAL='TRUE';
      INPUT_LOAD='(-0.01,0.01)';
      OUTPUT_LOAD='(1.0,-1.0)';
    'DDR3_SB_DQ15':
      PIN_NUMBER='(0,0,0,0,0,0,0,0,0,0,AN25,0,0,0,0,0,0,0,0,0,0,0,0,0,0,0,0,0,0,0,0,0,0,0,0,0,0,0,0,0,0,0)';
      BIDIRECTIONAL='TRUE';
      INPUT_LOAD='(-0.01,0.01)';
      OUTPUT_LOAD='(1.0,-1.0)';
    'DDR3_SB_DQ14':
      PIN_NUMBER='(0,0,0,0,0,0,0,0,0,0,AP26,0,0,0,0,0,0,0,0,0,0,0,0,0,0,0,0,0,0,0,0,0,0,0,0,0,0,0,0,0,0,0)';
      BIDIRECTIONAL='TRUE';
      INPUT_LOAD='(-0.01,0.01)';
      OUTPUT_LOAD='(1.0,-1.0)';
    'DDR3_SB_DQ13':
      PIN_NUMBER='(0,0,0,0,0,0,0,0,0,0,AL25,0,0,0,0,0,0,0,0,0,0,0,0,0,0,0,0,0,0,0,0,0,0,0,0,0,0,0,0,0,0,0)';
      BIDIRECTIONAL='TRUE';
      INPUT_LOAD='(-0.01,0.01)';
      OUTPUT_LOAD='(1.0,-1.0)';
    'DDR3_SB_DQ12':
      PIN_NUMBER='(0,0,0,0,0,0,0,0,0,0,AK26,0,0,0,0,0,0,0,0,0,0,0,0,0,0,0,0,0,0,0,0,0,0,0,0,0,0,0,0,0,0,0)';
      BIDIRECTIONAL='TRUE';
      INPUT_LOAD='(-0.01,0.01)';
      OUTPUT_LOAD='(1.0,-1.0)';
    'DDR3_SB_DQ11':
      PIN_NUMBER='(0,0,0,0,0,0,0,0,0,0,AP28,0,0,0,0,0,0,0,0,0,0,0,0,0,0,0,0,0,0,0,0,0,0,0,0,0,0,0,0,0,0,0)';
      BIDIRECTIONAL='TRUE';
      INPUT_LOAD='(-0.01,0.01)';
      OUTPUT_LOAD='(1.0,-1.0)';
    'DDR3_SB_DQ10':
      PIN_NUMBER='(0,0,0,0,0,0,0,0,0,0,AN29,0,0,0,0,0,0,0,0,0,0,0,0,0,0,0,0,0,0,0,0,0,0,0,0,0,0,0,0,0,0,0)';
      BIDIRECTIONAL='TRUE';
      INPUT_LOAD='(-0.01,0.01)';
      OUTPUT_LOAD='(1.0,-1.0)';
    'DDR3_SB_DQ9':
      PIN_NUMBER='(0,0,0,0,0,0,0,0,0,0,AK28,0,0,0,0,0,0,0,0,0,0,0,0,0,0,0,0,0,0,0,0,0,0,0,0,0,0,0,0,0,0,0)';
      BIDIRECTIONAL='TRUE';
      INPUT_LOAD='(-0.01,0.01)';
      OUTPUT_LOAD='(1.0,-1.0)';
    'DDR3_SB_DQ8':
      PIN_NUMBER='(0,0,0,0,0,0,0,0,0,0,AL29,0,0,0,0,0,0,0,0,0,0,0,0,0,0,0,0,0,0,0,0,0,0,0,0,0,0,0,0,0,0,0)';
      BIDIRECTIONAL='TRUE';
      INPUT_LOAD='(-0.01,0.01)';
      OUTPUT_LOAD='(1.0,-1.0)';
    'DDR3_SB_DQ7':
      PIN_NUMBER='(0,0,0,0,0,0,0,0,0,0,AN31,0,0,0,0,0,0,0,0,0,0,0,0,0,0,0,0,0,0,0,0,0,0,0,0,0,0,0,0,0,0,0)';
      BIDIRECTIONAL='TRUE';
      INPUT_LOAD='(-0.01,0.01)';
      OUTPUT_LOAD='(1.0,-1.0)';
    'DDR3_SB_DQ6':
      PIN_NUMBER='(0,0,0,0,0,0,0,0,0,0,AP32,0,0,0,0,0,0,0,0,0,0,0,0,0,0,0,0,0,0,0,0,0,0,0,0,0,0,0,0,0,0,0)';
      BIDIRECTIONAL='TRUE';
      INPUT_LOAD='(-0.01,0.01)';
      OUTPUT_LOAD='(1.0,-1.0)';
    'DDR3_SB_DQ5':
      PIN_NUMBER='(0,0,0,0,0,0,0,0,0,0,AL31,0,0,0,0,0,0,0,0,0,0,0,0,0,0,0,0,0,0,0,0,0,0,0,0,0,0,0,0,0,0,0)';
      BIDIRECTIONAL='TRUE';
      INPUT_LOAD='(-0.01,0.01)';
      OUTPUT_LOAD='(1.0,-1.0)';
    'DDR3_SB_DQ4':
      PIN_NUMBER='(0,0,0,0,0,0,0,0,0,0,AK32,0,0,0,0,0,0,0,0,0,0,0,0,0,0,0,0,0,0,0,0,0,0,0,0,0,0,0,0,0,0,0)';
      BIDIRECTIONAL='TRUE';
      INPUT_LOAD='(-0.01,0.01)';
      OUTPUT_LOAD='(1.0,-1.0)';
    'DDR3_SB_DQ3':
      PIN_NUMBER='(0,0,0,0,0,0,0,0,0,0,AP34,0,0,0,0,0,0,0,0,0,0,0,0,0,0,0,0,0,0,0,0,0,0,0,0,0,0,0,0,0,0,0)';
      BIDIRECTIONAL='TRUE';
      INPUT_LOAD='(-0.01,0.01)';
      OUTPUT_LOAD='(1.0,-1.0)';
    'DDR3_SB_DQ2':
      PIN_NUMBER='(0,0,0,0,0,0,0,0,0,0,AN35,0,0,0,0,0,0,0,0,0,0,0,0,0,0,0,0,0,0,0,0,0,0,0,0,0,0,0,0,0,0,0)';
      BIDIRECTIONAL='TRUE';
      INPUT_LOAD='(-0.01,0.01)';
      OUTPUT_LOAD='(1.0,-1.0)';
    'DDR3_SB_DQ1':
      PIN_NUMBER='(0,0,0,0,0,0,0,0,0,0,AK34,0,0,0,0,0,0,0,0,0,0,0,0,0,0,0,0,0,0,0,0,0,0,0,0,0,0,0,0,0,0,0)';
      BIDIRECTIONAL='TRUE';
      INPUT_LOAD='(-0.01,0.01)';
      OUTPUT_LOAD='(1.0,-1.0)';
    'DDR3_SB_DQ0':
      PIN_NUMBER='(0,0,0,0,0,0,0,0,0,0,AL35,0,0,0,0,0,0,0,0,0,0,0,0,0,0,0,0,0,0,0,0,0,0,0,0,0,0,0,0,0,0,0)';
      BIDIRECTIONAL='TRUE';
      INPUT_LOAD='(-0.01,0.01)';
      OUTPUT_LOAD='(1.0,-1.0)';
    'DDR3_SB_DQS_DN9':
      PIN_NUMBER='(0,0,0,0,0,0,0,0,0,0,AJ39,0,0,0,0,0,0,0,0,0,0,0,0,0,0,0,0,0,0,0,0,0,0,0,0,0,0,0,0,0,0,0)';
      BIDIRECTIONAL='TRUE';
      INPUT_LOAD='(-0.01,0.01)';
      OUTPUT_LOAD='(1.0,-1.0)';
    'DDR3_SB_DQS_DN8':
      PIN_NUMBER='(0,0,0,0,0,0,0,0,0,0,AN21,0,0,0,0,0,0,0,0,0,0,0,0,0,0,0,0,0,0,0,0,0,0,0,0,0,0,0,0,0,0,0)';
      BIDIRECTIONAL='TRUE';
      INPUT_LOAD='(-0.01,0.01)';
      OUTPUT_LOAD='(1.0,-1.0)';
    'DDR3_SB_DQS_DN7':
      PIN_NUMBER='(0,0,0,0,0,0,0,0,0,0,AF24,0,0,0,0,0,0,0,0,0,0,0,0,0,0,0,0,0,0,0,0,0,0,0,0,0,0,0,0,0,0,0)';
      BIDIRECTIONAL='TRUE';
      INPUT_LOAD='(-0.01,0.01)';
      OUTPUT_LOAD='(1.0,-1.0)';
    'DDR3_SB_DQS_DN6':
      PIN_NUMBER='(0,0,0,0,0,0,0,0,0,0,AN27,0,0,0,0,0,0,0,0,0,0,0,0,0,0,0,0,0,0,0,0,0,0,0,0,0,0,0,0,0,0,0)';
      BIDIRECTIONAL='TRUE';
      INPUT_LOAD='(-0.01,0.01)';
      OUTPUT_LOAD='(1.0,-1.0)';
    'DDR3_SB_DQS_DN5':
      PIN_NUMBER='(0,0,0,0,0,0,0,0,0,0,AN33,0,0,0,0,0,0,0,0,0,0,0,0,0,0,0,0,0,0,0,0,0,0,0,0,0,0,0,0,0,0,0)';
      BIDIRECTIONAL='TRUE';
      INPUT_LOAD='(-0.01,0.01)';
      OUTPUT_LOAD='(1.0,-1.0)';
    'DDR3_SB_DQS_DN4':
      PIN_NUMBER='(0,0,0,0,0,0,0,0,0,0,AR39,0,0,0,0,0,0,0,0,0,0,0,0,0,0,0,0,0,0,0,0,0,0,0,0,0,0,0,0,0,0,0)';
      BIDIRECTIONAL='TRUE';
      INPUT_LOAD='(-0.01,0.01)';
      OUTPUT_LOAD='(1.0,-1.0)';
    'DDR3_SB_DQS_DN3':
      PIN_NUMBER='(0,0,0,0,0,0,0,0,0,0,AJ21,0,0,0,0,0,0,0,0,0,0,0,0,0,0,0,0,0,0,0,0,0,0,0,0,0,0,0,0,0,0,0)';
      BIDIRECTIONAL='TRUE';
      INPUT_LOAD='(-0.01,0.01)';
      OUTPUT_LOAD='(1.0,-1.0)';
    'DDR3_SB_DQS_DN2':
      PIN_NUMBER='(0,0,0,0,0,0,0,0,0,0,AB24,0,0,0,0,0,0,0,0,0,0,0,0,0,0,0,0,0,0,0,0,0,0,0,0,0,0,0,0,0,0,0)';
      BIDIRECTIONAL='TRUE';
      INPUT_LOAD='(-0.01,0.01)';
      OUTPUT_LOAD='(1.0,-1.0)';
    'DDR3_SB_DQS_DN1':
      PIN_NUMBER='(0,0,0,0,0,0,0,0,0,0,AJ27,0,0,0,0,0,0,0,0,0,0,0,0,0,0,0,0,0,0,0,0,0,0,0,0,0,0,0,0,0,0,0)';
      BIDIRECTIONAL='TRUE';
      INPUT_LOAD='(-0.01,0.01)';
      OUTPUT_LOAD='(1.0,-1.0)';
    'DDR3_SB_DQS_DN0':
      PIN_NUMBER='(0,0,0,0,0,0,0,0,0,0,AJ33,0,0,0,0,0,0,0,0,0,0,0,0,0,0,0,0,0,0,0,0,0,0,0,0,0,0,0,0,0,0,0)';
      BIDIRECTIONAL='TRUE';
      INPUT_LOAD='(-0.01,0.01)';
      OUTPUT_LOAD='(1.0,-1.0)';
    'DDR3_SB_DQS_DP9':
      PIN_NUMBER='(0,0,0,0,0,0,0,0,0,0,AL39,0,0,0,0,0,0,0,0,0,0,0,0,0,0,0,0,0,0,0,0,0,0,0,0,0,0,0,0,0,0,0)';
      BIDIRECTIONAL='TRUE';
      INPUT_LOAD='(-0.01,0.01)';
      OUTPUT_LOAD='(1.0,-1.0)';
    'DDR3_SB_DQS_DP8':
      PIN_NUMBER='(0,0,0,0,0,0,0,0,0,0,AR21,0,0,0,0,0,0,0,0,0,0,0,0,0,0,0,0,0,0,0,0,0,0,0,0,0,0,0,0,0,0,0)';
      BIDIRECTIONAL='TRUE';
      INPUT_LOAD='(-0.01,0.01)';
      OUTPUT_LOAD='(1.0,-1.0)';
    'DDR3_SB_DQS_DP7':
      PIN_NUMBER='(0,0,0,0,0,0,0,0,0,0,AH24,0,0,0,0,0,0,0,0,0,0,0,0,0,0,0,0,0,0,0,0,0,0,0,0,0,0,0,0,0,0,0)';
      BIDIRECTIONAL='TRUE';
      INPUT_LOAD='(-0.01,0.01)';
      OUTPUT_LOAD='(1.0,-1.0)';
    'DDR3_SB_DQS_DP6':
      PIN_NUMBER='(0,0,0,0,0,0,0,0,0,0,AR27,0,0,0,0,0,0,0,0,0,0,0,0,0,0,0,0,0,0,0,0,0,0,0,0,0,0,0,0,0,0,0)';
      BIDIRECTIONAL='TRUE';
      INPUT_LOAD='(-0.01,0.01)';
      OUTPUT_LOAD='(1.0,-1.0)';
    'DDR3_SB_DQS_DP5':
      PIN_NUMBER='(0,0,0,0,0,0,0,0,0,0,AR33,0,0,0,0,0,0,0,0,0,0,0,0,0,0,0,0,0,0,0,0,0,0,0,0,0,0,0,0,0,0,0)';
      BIDIRECTIONAL='TRUE';
      INPUT_LOAD='(-0.01,0.01)';
      OUTPUT_LOAD='(1.0,-1.0)';
    'DDR3_SB_DQS_DP4':
      PIN_NUMBER='(0,0,0,0,0,0,0,0,0,0,AN39,0,0,0,0,0,0,0,0,0,0,0,0,0,0,0,0,0,0,0,0,0,0,0,0,0,0,0,0,0,0,0)';
      BIDIRECTIONAL='TRUE';
      INPUT_LOAD='(-0.01,0.01)';
      OUTPUT_LOAD='(1.0,-1.0)';
    'DDR3_SB_DQS_DP3':
      PIN_NUMBER='(0,0,0,0,0,0,0,0,0,0,AL21,0,0,0,0,0,0,0,0,0,0,0,0,0,0,0,0,0,0,0,0,0,0,0,0,0,0,0,0,0,0,0)';
      BIDIRECTIONAL='TRUE';
      INPUT_LOAD='(-0.01,0.01)';
      OUTPUT_LOAD='(1.0,-1.0)';
    'DDR3_SB_DQS_DP2':
      PIN_NUMBER='(0,0,0,0,0,0,0,0,0,0,AD24,0,0,0,0,0,0,0,0,0,0,0,0,0,0,0,0,0,0,0,0,0,0,0,0,0,0,0,0,0,0,0)';
      BIDIRECTIONAL='TRUE';
      INPUT_LOAD='(-0.01,0.01)';
      OUTPUT_LOAD='(1.0,-1.0)';
    'DDR3_SB_DQS_DP1':
      PIN_NUMBER='(0,0,0,0,0,0,0,0,0,0,AL27,0,0,0,0,0,0,0,0,0,0,0,0,0,0,0,0,0,0,0,0,0,0,0,0,0,0,0,0,0,0,0)';
      BIDIRECTIONAL='TRUE';
      INPUT_LOAD='(-0.01,0.01)';
      OUTPUT_LOAD='(1.0,-1.0)';
    'DDR3_SB_DQS_DP0':
      PIN_NUMBER='(0,0,0,0,0,0,0,0,0,0,AL33,0,0,0,0,0,0,0,0,0,0,0,0,0,0,0,0,0,0,0,0,0,0,0,0,0,0,0,0,0,0,0)';
      BIDIRECTIONAL='TRUE';
      INPUT_LOAD='(-0.01,0.01)';
      OUTPUT_LOAD='(1.0,-1.0)';
    'DDR3_SB_ECC7':
      PIN_NUMBER='(0,0,0,0,0,0,0,0,0,0,AP40,0,0,0,0,0,0,0,0,0,0,0,0,0,0,0,0,0,0,0,0,0,0,0,0,0,0,0,0,0,0,0)';
      BIDIRECTIONAL='TRUE';
      INPUT_LOAD='(-0.01,0.01)';
      OUTPUT_LOAD='(1.0,-1.0)';
    'DDR3_SB_ECC6':
      PIN_NUMBER='(0,0,0,0,0,0,0,0,0,0,AN41,0,0,0,0,0,0,0,0,0,0,0,0,0,0,0,0,0,0,0,0,0,0,0,0,0,0,0,0,0,0,0)';
      BIDIRECTIONAL='TRUE';
      INPUT_LOAD='(-0.01,0.01)';
      OUTPUT_LOAD='(1.0,-1.0)';
    'DDR3_SB_ECC5':
      PIN_NUMBER='(0,0,0,0,0,0,0,0,0,0,AK40,0,0,0,0,0,0,0,0,0,0,0,0,0,0,0,0,0,0,0,0,0,0,0,0,0,0,0,0,0,0,0)';
      BIDIRECTIONAL='TRUE';
      INPUT_LOAD='(-0.01,0.01)';
      OUTPUT_LOAD='(1.0,-1.0)';
    'DDR3_SB_ECC4':
      PIN_NUMBER='(0,0,0,0,0,0,0,0,0,0,AL41,0,0,0,0,0,0,0,0,0,0,0,0,0,0,0,0,0,0,0,0,0,0,0,0,0,0,0,0,0,0,0)';
      BIDIRECTIONAL='TRUE';
      INPUT_LOAD='(-0.01,0.01)';
      OUTPUT_LOAD='(1.0,-1.0)';
    'DDR3_SB_ECC3':
      PIN_NUMBER='(0,0,0,0,0,0,0,0,0,0,AN37,0,0,0,0,0,0,0,0,0,0,0,0,0,0,0,0,0,0,0,0,0,0,0,0,0,0,0,0,0,0,0)';
      BIDIRECTIONAL='TRUE';
      INPUT_LOAD='(-0.01,0.01)';
      OUTPUT_LOAD='(1.0,-1.0)';
    'DDR3_SB_ECC2':
      PIN_NUMBER='(0,0,0,0,0,0,0,0,0,0,AP38,0,0,0,0,0,0,0,0,0,0,0,0,0,0,0,0,0,0,0,0,0,0,0,0,0,0,0,0,0,0,0)';
      BIDIRECTIONAL='TRUE';
      INPUT_LOAD='(-0.01,0.01)';
      OUTPUT_LOAD='(1.0,-1.0)';
    'DDR3_SB_ECC1':
      PIN_NUMBER='(0,0,0,0,0,0,0,0,0,0,AL37,0,0,0,0,0,0,0,0,0,0,0,0,0,0,0,0,0,0,0,0,0,0,0,0,0,0,0,0,0,0,0)';
      BIDIRECTIONAL='TRUE';
      INPUT_LOAD='(-0.01,0.01)';
      OUTPUT_LOAD='(1.0,-1.0)';
    'DDR3_SB_ECC0':
      PIN_NUMBER='(0,0,0,0,0,0,0,0,0,0,AK38,0,0,0,0,0,0,0,0,0,0,0,0,0,0,0,0,0,0,0,0,0,0,0,0,0,0,0,0,0,0,0)';
      BIDIRECTIONAL='TRUE';
      INPUT_LOAD='(-0.01,0.01)';
      OUTPUT_LOAD='(1.0,-1.0)';
    'DDR3_SB_PAR':
      PIN_NUMBER='(0,0,0,0,0,0,0,0,0,0,AH42,0,0,0,0,0,0,0,0,0,0,0,0,0,0,0,0,0,0,0,0,0,0,0,0,0,0,0,0,0,0,0)';
      OUTPUT_LOAD='(1.0,-1.0)';
    '-DDR4_ALERT':
      PIN_NUMBER='(0,0,0,0,0,0,0,0,0,0,0,CY47,0,0,0,0,0,0,0,0,0,0,0,0,0,0,0,0,0,0,0,0,0,0,0,0,0,0,0,0,0,0)';
      INPUT_LOAD='(-0.01,0.01)';
    'DDR4_A_RSP1':
      PIN_NUMBER='(0,0,0,0,0,0,0,0,0,0,0,DC43,0,0,0,0,0,0,0,0,0,0,0,0,0,0,0,0,0,0,0,0,0,0,0,0,0,0,0,0,0,0)';
      INPUT_LOAD='(-0.01,0.01)';
    'DDR4_A_RSP0':
      PIN_NUMBER='(0,0,0,0,0,0,0,0,0,0,0,DD44,0,0,0,0,0,0,0,0,0,0,0,0,0,0,0,0,0,0,0,0,0,0,0,0,0,0,0,0,0,0)';
      INPUT_LOAD='(-0.01,0.01)';
    'DDR4_B_RSP1':
      PIN_NUMBER='(0,0,0,0,0,0,0,0,0,0,0,DG43,0,0,0,0,0,0,0,0,0,0,0,0,0,0,0,0,0,0,0,0,0,0,0,0,0,0,0,0,0,0)';
      INPUT_LOAD='(-0.01,0.01)';
    'DDR4_B_RSP0':
      PIN_NUMBER='(0,0,0,0,0,0,0,0,0,0,0,DF44,0,0,0,0,0,0,0,0,0,0,0,0,0,0,0,0,0,0,0,0,0,0,0,0,0,0,0,0,0,0)';
      INPUT_LOAD='(-0.01,0.01)';
    'DDR4_CLK_DN1':
      PIN_NUMBER='(0,0,0,0,0,0,0,0,0,0,0,EE45,0,0,0,0,0,0,0,0,0,0,0,0,0,0,0,0,0,0,0,0,0,0,0,0,0,0,0,0,0,0)';
      OUTPUT_LOAD='(1.0,-1.0)';
    'DDR4_CLK_DN0':
      PIN_NUMBER='(0,0,0,0,0,0,0,0,0,0,0,EJ45,0,0,0,0,0,0,0,0,0,0,0,0,0,0,0,0,0,0,0,0,0,0,0,0,0,0,0,0,0,0)';
      OUTPUT_LOAD='(1.0,-1.0)';
    'DDR4_CLK_DP1':
      PIN_NUMBER='(0,0,0,0,0,0,0,0,0,0,0,EC45,0,0,0,0,0,0,0,0,0,0,0,0,0,0,0,0,0,0,0,0,0,0,0,0,0,0,0,0,0,0)';
      OUTPUT_LOAD='(1.0,-1.0)';
    'DDR4_CLK_DP0':
      PIN_NUMBER='(0,0,0,0,0,0,0,0,0,0,0,EG45,0,0,0,0,0,0,0,0,0,0,0,0,0,0,0,0,0,0,0,0,0,0,0,0,0,0,0,0,0,0)';
      OUTPUT_LOAD='(1.0,-1.0)';
    'DDR4_SA_CA6':
      PIN_NUMBER='(0,0,0,0,0,0,0,0,0,0,0,ED44,0,0,0,0,0,0,0,0,0,0,0,0,0,0,0,0,0,0,0,0,0,0,0,0,0,0,0,0,0,0)';
      OUTPUT_LOAD='(1.0,-1.0)';
    'DDR4_SA_CA5':
      PIN_NUMBER='(0,0,0,0,0,0,0,0,0,0,0,EP47,0,0,0,0,0,0,0,0,0,0,0,0,0,0,0,0,0,0,0,0,0,0,0,0,0,0,0,0,0,0)';
      OUTPUT_LOAD='(1.0,-1.0)';
    'DDR4_SA_CA4':
      PIN_NUMBER='(0,0,0,0,0,0,0,0,0,0,0,EM47,0,0,0,0,0,0,0,0,0,0,0,0,0,0,0,0,0,0,0,0,0,0,0,0,0,0,0,0,0,0)';
      OUTPUT_LOAD='(1.0,-1.0)';
    'DDR4_SA_CA3':
      PIN_NUMBER='(0,0,0,0,0,0,0,0,0,0,0,EL48,0,0,0,0,0,0,0,0,0,0,0,0,0,0,0,0,0,0,0,0,0,0,0,0,0,0,0,0,0,0)';
      OUTPUT_LOAD='(1.0,-1.0)';
    'DDR4_SA_CA2':
      PIN_NUMBER='(0,0,0,0,0,0,0,0,0,0,0,EK49,0,0,0,0,0,0,0,0,0,0,0,0,0,0,0,0,0,0,0,0,0,0,0,0,0,0,0,0,0,0)';
      OUTPUT_LOAD='(1.0,-1.0)';
    'DDR4_SA_CA1':
      PIN_NUMBER='(0,0,0,0,0,0,0,0,0,0,0,ET49,0,0,0,0,0,0,0,0,0,0,0,0,0,0,0,0,0,0,0,0,0,0,0,0,0,0,0,0,0,0)';
      OUTPUT_LOAD='(1.0,-1.0)';
    'DDR4_SA_CA0':
      PIN_NUMBER='(0,0,0,0,0,0,0,0,0,0,0,EP49,0,0,0,0,0,0,0,0,0,0,0,0,0,0,0,0,0,0,0,0,0,0,0,0,0,0,0,0,0,0)';
      OUTPUT_LOAD='(1.0,-1.0)';
    'DDR4_SA_CS_N3':
      PIN_NUMBER='(0,0,0,0,0,0,0,0,0,0,0,EL50,0,0,0,0,0,0,0,0,0,0,0,0,0,0,0,0,0,0,0,0,0,0,0,0,0,0,0,0,0,0)';
      OUTPUT_LOAD='(1.0,-1.0)';
    'DDR4_SA_CS_N2':
      PIN_NUMBER='(0,0,0,0,0,0,0,0,0,0,0,EM51,0,0,0,0,0,0,0,0,0,0,0,0,0,0,0,0,0,0,0,0,0,0,0,0,0,0,0,0,0,0)';
      OUTPUT_LOAD='(1.0,-1.0)';
    'DDR4_SA_CS_N1':
      PIN_NUMBER='(0,0,0,0,0,0,0,0,0,0,0,ET51,0,0,0,0,0,0,0,0,0,0,0,0,0,0,0,0,0,0,0,0,0,0,0,0,0,0,0,0,0,0)';
      OUTPUT_LOAD='(1.0,-1.0)';
    'DDR4_SA_CS_N0':
      PIN_NUMBER='(0,0,0,0,0,0,0,0,0,0,0,EP51,0,0,0,0,0,0,0,0,0,0,0,0,0,0,0,0,0,0,0,0,0,0,0,0,0,0,0,0,0,0)';
      OUTPUT_LOAD='(1.0,-1.0)';
    'DDR4_SA_DQ31':
      PIN_NUMBER='(0,0,0,0,0,0,0,0,0,0,0,EP59,0,0,0,0,0,0,0,0,0,0,0,0,0,0,0,0,0,0,0,0,0,0,0,0,0,0,0,0,0,0)';
      BIDIRECTIONAL='TRUE';
      INPUT_LOAD='(-0.01,0.01)';
      OUTPUT_LOAD='(1.0,-1.0)';
    'DDR4_SA_DQ30':
      PIN_NUMBER='(0,0,0,0,0,0,0,0,0,0,0,ER60,0,0,0,0,0,0,0,0,0,0,0,0,0,0,0,0,0,0,0,0,0,0,0,0,0,0,0,0,0,0)';
      BIDIRECTIONAL='TRUE';
      INPUT_LOAD='(-0.01,0.01)';
      OUTPUT_LOAD='(1.0,-1.0)';
    'DDR4_SA_DQ29':
      PIN_NUMBER='(0,0,0,0,0,0,0,0,0,0,0,EM59,0,0,0,0,0,0,0,0,0,0,0,0,0,0,0,0,0,0,0,0,0,0,0,0,0,0,0,0,0,0)';
      BIDIRECTIONAL='TRUE';
      INPUT_LOAD='(-0.01,0.01)';
      OUTPUT_LOAD='(1.0,-1.0)';
    'DDR4_SA_DQ28':
      PIN_NUMBER='(0,0,0,0,0,0,0,0,0,0,0,EL60,0,0,0,0,0,0,0,0,0,0,0,0,0,0,0,0,0,0,0,0,0,0,0,0,0,0,0,0,0,0)';
      BIDIRECTIONAL='TRUE';
      INPUT_LOAD='(-0.01,0.01)';
      OUTPUT_LOAD='(1.0,-1.0)';
    'DDR4_SA_DQ27':
      PIN_NUMBER='(0,0,0,0,0,0,0,0,0,0,0,ER62,0,0,0,0,0,0,0,0,0,0,0,0,0,0,0,0,0,0,0,0,0,0,0,0,0,0,0,0,0,0)';
      BIDIRECTIONAL='TRUE';
      INPUT_LOAD='(-0.01,0.01)';
      OUTPUT_LOAD='(1.0,-1.0)';
    'DDR4_SA_DQ26':
      PIN_NUMBER='(0,0,0,0,0,0,0,0,0,0,0,EP63,0,0,0,0,0,0,0,0,0,0,0,0,0,0,0,0,0,0,0,0,0,0,0,0,0,0,0,0,0,0)';
      BIDIRECTIONAL='TRUE';
      INPUT_LOAD='(-0.01,0.01)';
      OUTPUT_LOAD='(1.0,-1.0)';
    'DDR4_SA_DQ25':
      PIN_NUMBER='(0,0,0,0,0,0,0,0,0,0,0,EL62,0,0,0,0,0,0,0,0,0,0,0,0,0,0,0,0,0,0,0,0,0,0,0,0,0,0,0,0,0,0)';
      BIDIRECTIONAL='TRUE';
      INPUT_LOAD='(-0.01,0.01)';
      OUTPUT_LOAD='(1.0,-1.0)';
    'DDR4_SA_DQ24':
      PIN_NUMBER='(0,0,0,0,0,0,0,0,0,0,0,EM63,0,0,0,0,0,0,0,0,0,0,0,0,0,0,0,0,0,0,0,0,0,0,0,0,0,0,0,0,0,0)';
      BIDIRECTIONAL='TRUE';
      INPUT_LOAD='(-0.01,0.01)';
      OUTPUT_LOAD='(1.0,-1.0)';
    'DDR4_SA_DQ23':
      PIN_NUMBER='(0,0,0,0,0,0,0,0,0,0,0,EP65,0,0,0,0,0,0,0,0,0,0,0,0,0,0,0,0,0,0,0,0,0,0,0,0,0,0,0,0,0,0)';
      BIDIRECTIONAL='TRUE';
      INPUT_LOAD='(-0.01,0.01)';
      OUTPUT_LOAD='(1.0,-1.0)';
    'DDR4_SA_DQ22':
      PIN_NUMBER='(0,0,0,0,0,0,0,0,0,0,0,EL66,0,0,0,0,0,0,0,0,0,0,0,0,0,0,0,0,0,0,0,0,0,0,0,0,0,0,0,0,0,0)';
      BIDIRECTIONAL='TRUE';
      INPUT_LOAD='(-0.01,0.01)';
      OUTPUT_LOAD='(1.0,-1.0)';
    'DDR4_SA_DQ21':
      PIN_NUMBER='(0,0,0,0,0,0,0,0,0,0,0,EM65,0,0,0,0,0,0,0,0,0,0,0,0,0,0,0,0,0,0,0,0,0,0,0,0,0,0,0,0,0,0)';
      BIDIRECTIONAL='TRUE';
      INPUT_LOAD='(-0.01,0.01)';
      OUTPUT_LOAD='(1.0,-1.0)';
    'DDR4_SA_DQ20':
      PIN_NUMBER='(0,0,0,0,0,0,0,0,0,0,0,ER66,0,0,0,0,0,0,0,0,0,0,0,0,0,0,0,0,0,0,0,0,0,0,0,0,0,0,0,0,0,0)';
      BIDIRECTIONAL='TRUE';
      INPUT_LOAD='(-0.01,0.01)';
      OUTPUT_LOAD='(1.0,-1.0)';
    'DDR4_SA_DQ19':
      PIN_NUMBER='(0,0,0,0,0,0,0,0,0,0,0,ER68,0,0,0,0,0,0,0,0,0,0,0,0,0,0,0,0,0,0,0,0,0,0,0,0,0,0,0,0,0,0)';
      BIDIRECTIONAL='TRUE';
      INPUT_LOAD='(-0.01,0.01)';
      OUTPUT_LOAD='(1.0,-1.0)';
    'DDR4_SA_DQ18':
      PIN_NUMBER='(0,0,0,0,0,0,0,0,0,0,0,EN70,0,0,0,0,0,0,0,0,0,0,0,0,0,0,0,0,0,0,0,0,0,0,0,0,0,0,0,0,0,0)';
      BIDIRECTIONAL='TRUE';
      INPUT_LOAD='(-0.01,0.01)';
      OUTPUT_LOAD='(1.0,-1.0)';
    'DDR4_SA_DQ17':
      PIN_NUMBER='(0,0,0,0,0,0,0,0,0,0,0,EM69,0,0,0,0,0,0,0,0,0,0,0,0,0,0,0,0,0,0,0,0,0,0,0,0,0,0,0,0,0,0)';
      BIDIRECTIONAL='TRUE';
      INPUT_LOAD='(-0.01,0.01)';
      OUTPUT_LOAD='(1.0,-1.0)';
    'DDR4_SA_DQ16':
      PIN_NUMBER='(0,0,0,0,0,0,0,0,0,0,0,EM71,0,0,0,0,0,0,0,0,0,0,0,0,0,0,0,0,0,0,0,0,0,0,0,0,0,0,0,0,0,0)';
      BIDIRECTIONAL='TRUE';
      INPUT_LOAD='(-0.01,0.01)';
      OUTPUT_LOAD='(1.0,-1.0)';
    'DDR4_SA_DQ15':
      PIN_NUMBER='(0,0,0,0,0,0,0,0,0,0,0,EG68,0,0,0,0,0,0,0,0,0,0,0,0,0,0,0,0,0,0,0,0,0,0,0,0,0,0,0,0,0,0)';
      BIDIRECTIONAL='TRUE';
      INPUT_LOAD='(-0.01,0.01)';
      OUTPUT_LOAD='(1.0,-1.0)';
    'DDR4_SA_DQ14':
      PIN_NUMBER='(0,0,0,0,0,0,0,0,0,0,0,EH69,0,0,0,0,0,0,0,0,0,0,0,0,0,0,0,0,0,0,0,0,0,0,0,0,0,0,0,0,0,0)';
      BIDIRECTIONAL='TRUE';
      INPUT_LOAD='(-0.01,0.01)';
      OUTPUT_LOAD='(1.0,-1.0)';
    'DDR4_SA_DQ13':
      PIN_NUMBER='(0,0,0,0,0,0,0,0,0,0,0,EE68,0,0,0,0,0,0,0,0,0,0,0,0,0,0,0,0,0,0,0,0,0,0,0,0,0,0,0,0,0,0)';
      BIDIRECTIONAL='TRUE';
      INPUT_LOAD='(-0.01,0.01)';
      OUTPUT_LOAD='(1.0,-1.0)';
    'DDR4_SA_DQ12':
      PIN_NUMBER='(0,0,0,0,0,0,0,0,0,0,0,ED69,0,0,0,0,0,0,0,0,0,0,0,0,0,0,0,0,0,0,0,0,0,0,0,0,0,0,0,0,0,0)';
      BIDIRECTIONAL='TRUE';
      INPUT_LOAD='(-0.01,0.01)';
      OUTPUT_LOAD='(1.0,-1.0)';
    'DDR4_SA_DQ11':
      PIN_NUMBER='(0,0,0,0,0,0,0,0,0,0,0,EH71,0,0,0,0,0,0,0,0,0,0,0,0,0,0,0,0,0,0,0,0,0,0,0,0,0,0,0,0,0,0)';
      BIDIRECTIONAL='TRUE';
      INPUT_LOAD='(-0.01,0.01)';
      OUTPUT_LOAD='(1.0,-1.0)';
    'DDR4_SA_DQ10':
      PIN_NUMBER='(0,0,0,0,0,0,0,0,0,0,0,EG72,0,0,0,0,0,0,0,0,0,0,0,0,0,0,0,0,0,0,0,0,0,0,0,0,0,0,0,0,0,0)';
      BIDIRECTIONAL='TRUE';
      INPUT_LOAD='(-0.01,0.01)';
      OUTPUT_LOAD='(1.0,-1.0)';
    'DDR4_SA_DQ9':
      PIN_NUMBER='(0,0,0,0,0,0,0,0,0,0,0,ED71,0,0,0,0,0,0,0,0,0,0,0,0,0,0,0,0,0,0,0,0,0,0,0,0,0,0,0,0,0,0)';
      BIDIRECTIONAL='TRUE';
      INPUT_LOAD='(-0.01,0.01)';
      OUTPUT_LOAD='(1.0,-1.0)';
    'DDR4_SA_DQ8':
      PIN_NUMBER='(0,0,0,0,0,0,0,0,0,0,0,EE72,0,0,0,0,0,0,0,0,0,0,0,0,0,0,0,0,0,0,0,0,0,0,0,0,0,0,0,0,0,0)';
      BIDIRECTIONAL='TRUE';
      INPUT_LOAD='(-0.01,0.01)';
      OUTPUT_LOAD='(1.0,-1.0)';
    'DDR4_SA_DQ7':
      PIN_NUMBER='(0,0,0,0,0,0,0,0,0,0,0,ER72,0,0,0,0,0,0,0,0,0,0,0,0,0,0,0,0,0,0,0,0,0,0,0,0,0,0,0,0,0,0)';
      BIDIRECTIONAL='TRUE';
      INPUT_LOAD='(-0.01,0.01)';
      OUTPUT_LOAD='(1.0,-1.0)';
    'DDR4_SA_DQ6':
      PIN_NUMBER='(0,0,0,0,0,0,0,0,0,0,0,EP73,0,0,0,0,0,0,0,0,0,0,0,0,0,0,0,0,0,0,0,0,0,0,0,0,0,0,0,0,0,0)';
      BIDIRECTIONAL='TRUE';
      INPUT_LOAD='(-0.01,0.01)';
      OUTPUT_LOAD='(1.0,-1.0)';
    'DDR4_SA_DQ5':
      PIN_NUMBER='(0,0,0,0,0,0,0,0,0,0,0,EK73,0,0,0,0,0,0,0,0,0,0,0,0,0,0,0,0,0,0,0,0,0,0,0,0,0,0,0,0,0,0)';
      BIDIRECTIONAL='TRUE';
      INPUT_LOAD='(-0.01,0.01)';
      OUTPUT_LOAD='(1.0,-1.0)';
    'DDR4_SA_DQ4':
      PIN_NUMBER='(0,0,0,0,0,0,0,0,0,0,0,EL74,0,0,0,0,0,0,0,0,0,0,0,0,0,0,0,0,0,0,0,0,0,0,0,0,0,0,0,0,0,0)';
      BIDIRECTIONAL='TRUE';
      INPUT_LOAD='(-0.01,0.01)';
      OUTPUT_LOAD='(1.0,-1.0)';
    'DDR4_SA_DQ3':
      PIN_NUMBER='(0,0,0,0,0,0,0,0,0,0,0,ER76,0,0,0,0,0,0,0,0,0,0,0,0,0,0,0,0,0,0,0,0,0,0,0,0,0,0,0,0,0,0)';
      BIDIRECTIONAL='TRUE';
      INPUT_LOAD='(-0.01,0.01)';
      OUTPUT_LOAD='(1.0,-1.0)';
    'DDR4_SA_DQ2':
      PIN_NUMBER='(0,0,0,0,0,0,0,0,0,0,0,EP79,0,0,0,0,0,0,0,0,0,0,0,0,0,0,0,0,0,0,0,0,0,0,0,0,0,0,0,0,0,0)';
      BIDIRECTIONAL='TRUE';
      INPUT_LOAD='(-0.01,0.01)';
      OUTPUT_LOAD='(1.0,-1.0)';
    'DDR4_SA_DQ1':
      PIN_NUMBER='(0,0,0,0,0,0,0,0,0,0,0,EM77,0,0,0,0,0,0,0,0,0,0,0,0,0,0,0,0,0,0,0,0,0,0,0,0,0,0,0,0,0,0)';
      BIDIRECTIONAL='TRUE';
      INPUT_LOAD='(-0.01,0.01)';
      OUTPUT_LOAD='(1.0,-1.0)';
    'DDR4_SA_DQ0':
      PIN_NUMBER='(0,0,0,0,0,0,0,0,0,0,0,EL78,0,0,0,0,0,0,0,0,0,0,0,0,0,0,0,0,0,0,0,0,0,0,0,0,0,0,0,0,0,0)';
      BIDIRECTIONAL='TRUE';
      INPUT_LOAD='(-0.01,0.01)';
      OUTPUT_LOAD='(1.0,-1.0)';
    'DDR4_SA_DQS_DN9':
      PIN_NUMBER='(0,0,0,0,0,0,0,0,0,0,0,ET55,0,0,0,0,0,0,0,0,0,0,0,0,0,0,0,0,0,0,0,0,0,0,0,0,0,0,0,0,0,0)';
      BIDIRECTIONAL='TRUE';
      INPUT_LOAD='(-0.01,0.01)';
      OUTPUT_LOAD='(1.0,-1.0)';
    'DDR4_SA_DQS_DN8':
      PIN_NUMBER='(0,0,0,0,0,0,0,0,0,0,0,ET61,0,0,0,0,0,0,0,0,0,0,0,0,0,0,0,0,0,0,0,0,0,0,0,0,0,0,0,0,0,0)';
      BIDIRECTIONAL='TRUE';
      INPUT_LOAD='(-0.01,0.01)';
      OUTPUT_LOAD='(1.0,-1.0)';
    'DDR4_SA_DQS_DN7':
      PIN_NUMBER='(0,0,0,0,0,0,0,0,0,0,0,EN68,0,0,0,0,0,0,0,0,0,0,0,0,0,0,0,0,0,0,0,0,0,0,0,0,0,0,0,0,0,0)';
      BIDIRECTIONAL='TRUE';
      INPUT_LOAD='(-0.01,0.01)';
      OUTPUT_LOAD='(1.0,-1.0)';
    'DDR4_SA_DQS_DN6':
      PIN_NUMBER='(0,0,0,0,0,0,0,0,0,0,0,EJ70,0,0,0,0,0,0,0,0,0,0,0,0,0,0,0,0,0,0,0,0,0,0,0,0,0,0,0,0,0,0)';
      BIDIRECTIONAL='TRUE';
      INPUT_LOAD='(-0.01,0.01)';
      OUTPUT_LOAD='(1.0,-1.0)';
    'DDR4_SA_DQS_DN5':
      PIN_NUMBER='(0,0,0,0,0,0,0,0,0,0,0,EM75,0,0,0,0,0,0,0,0,0,0,0,0,0,0,0,0,0,0,0,0,0,0,0,0,0,0,0,0,0,0)';
      BIDIRECTIONAL='TRUE';
      INPUT_LOAD='(-0.01,0.01)';
      OUTPUT_LOAD='(1.0,-1.0)';
    'DDR4_SA_DQS_DN4':
      PIN_NUMBER='(0,0,0,0,0,0,0,0,0,0,0,EM55,0,0,0,0,0,0,0,0,0,0,0,0,0,0,0,0,0,0,0,0,0,0,0,0,0,0,0,0,0,0)';
      BIDIRECTIONAL='TRUE';
      INPUT_LOAD='(-0.01,0.01)';
      OUTPUT_LOAD='(1.0,-1.0)';
    'DDR4_SA_DQS_DN3':
      PIN_NUMBER='(0,0,0,0,0,0,0,0,0,0,0,EK61,0,0,0,0,0,0,0,0,0,0,0,0,0,0,0,0,0,0,0,0,0,0,0,0,0,0,0,0,0,0)';
      BIDIRECTIONAL='TRUE';
      INPUT_LOAD='(-0.01,0.01)';
      OUTPUT_LOAD='(1.0,-1.0)';
    'DDR4_SA_DQS_DN2':
      PIN_NUMBER='(0,0,0,0,0,0,0,0,0,0,0,EK67,0,0,0,0,0,0,0,0,0,0,0,0,0,0,0,0,0,0,0,0,0,0,0,0,0,0,0,0,0,0)';
      BIDIRECTIONAL='TRUE';
      INPUT_LOAD='(-0.01,0.01)';
      OUTPUT_LOAD='(1.0,-1.0)';
    'DDR4_SA_DQS_DN1':
      PIN_NUMBER='(0,0,0,0,0,0,0,0,0,0,0,EC70,0,0,0,0,0,0,0,0,0,0,0,0,0,0,0,0,0,0,0,0,0,0,0,0,0,0,0,0,0,0)';
      BIDIRECTIONAL='TRUE';
      INPUT_LOAD='(-0.01,0.01)';
      OUTPUT_LOAD='(1.0,-1.0)';
    'DDR4_SA_DQS_DN0':
      PIN_NUMBER='(0,0,0,0,0,0,0,0,0,0,0,EP75,0,0,0,0,0,0,0,0,0,0,0,0,0,0,0,0,0,0,0,0,0,0,0,0,0,0,0,0,0,0)';
      BIDIRECTIONAL='TRUE';
      INPUT_LOAD='(-0.01,0.01)';
      OUTPUT_LOAD='(1.0,-1.0)';
    'DDR4_SA_DQS_DP9':
      PIN_NUMBER='(0,0,0,0,0,0,0,0,0,0,0,EP55,0,0,0,0,0,0,0,0,0,0,0,0,0,0,0,0,0,0,0,0,0,0,0,0,0,0,0,0,0,0)';
      BIDIRECTIONAL='TRUE';
      INPUT_LOAD='(-0.01,0.01)';
      OUTPUT_LOAD='(1.0,-1.0)';
    'DDR4_SA_DQS_DP8':
      PIN_NUMBER='(0,0,0,0,0,0,0,0,0,0,0,EP61,0,0,0,0,0,0,0,0,0,0,0,0,0,0,0,0,0,0,0,0,0,0,0,0,0,0,0,0,0,0)';
      BIDIRECTIONAL='TRUE';
      INPUT_LOAD='(-0.01,0.01)';
      OUTPUT_LOAD='(1.0,-1.0)';
    'DDR4_SA_DQS_DP7':
      PIN_NUMBER='(0,0,0,0,0,0,0,0,0,0,0,EM67,0,0,0,0,0,0,0,0,0,0,0,0,0,0,0,0,0,0,0,0,0,0,0,0,0,0,0,0,0,0)';
      BIDIRECTIONAL='TRUE';
      INPUT_LOAD='(-0.01,0.01)';
      OUTPUT_LOAD='(1.0,-1.0)';
    'DDR4_SA_DQS_DP6':
      PIN_NUMBER='(0,0,0,0,0,0,0,0,0,0,0,EG70,0,0,0,0,0,0,0,0,0,0,0,0,0,0,0,0,0,0,0,0,0,0,0,0,0,0,0,0,0,0)';
      BIDIRECTIONAL='TRUE';
      INPUT_LOAD='(-0.01,0.01)';
      OUTPUT_LOAD='(1.0,-1.0)';
    'DDR4_SA_DQS_DP5':
      PIN_NUMBER='(0,0,0,0,0,0,0,0,0,0,0,EN74,0,0,0,0,0,0,0,0,0,0,0,0,0,0,0,0,0,0,0,0,0,0,0,0,0,0,0,0,0,0)';
      BIDIRECTIONAL='TRUE';
      INPUT_LOAD='(-0.01,0.01)';
      OUTPUT_LOAD='(1.0,-1.0)';
    'DDR4_SA_DQS_DP4':
      PIN_NUMBER='(0,0,0,0,0,0,0,0,0,0,0,EK55,0,0,0,0,0,0,0,0,0,0,0,0,0,0,0,0,0,0,0,0,0,0,0,0,0,0,0,0,0,0)';
      BIDIRECTIONAL='TRUE';
      INPUT_LOAD='(-0.01,0.01)';
      OUTPUT_LOAD='(1.0,-1.0)';
    'DDR4_SA_DQS_DP3':
      PIN_NUMBER='(0,0,0,0,0,0,0,0,0,0,0,EM61,0,0,0,0,0,0,0,0,0,0,0,0,0,0,0,0,0,0,0,0,0,0,0,0,0,0,0,0,0,0)';
      BIDIRECTIONAL='TRUE';
      INPUT_LOAD='(-0.01,0.01)';
      OUTPUT_LOAD='(1.0,-1.0)';
    'DDR4_SA_DQS_DP2':
      PIN_NUMBER='(0,0,0,0,0,0,0,0,0,0,0,EL68,0,0,0,0,0,0,0,0,0,0,0,0,0,0,0,0,0,0,0,0,0,0,0,0,0,0,0,0,0,0)';
      BIDIRECTIONAL='TRUE';
      INPUT_LOAD='(-0.01,0.01)';
      OUTPUT_LOAD='(1.0,-1.0)';
    'DDR4_SA_DQS_DP1':
      PIN_NUMBER='(0,0,0,0,0,0,0,0,0,0,0,EE70,0,0,0,0,0,0,0,0,0,0,0,0,0,0,0,0,0,0,0,0,0,0,0,0,0,0,0,0,0,0)';
      BIDIRECTIONAL='TRUE';
      INPUT_LOAD='(-0.01,0.01)';
      OUTPUT_LOAD='(1.0,-1.0)';
    'DDR4_SA_DQS_DP0':
      PIN_NUMBER='(0,0,0,0,0,0,0,0,0,0,0,EN76,0,0,0,0,0,0,0,0,0,0,0,0,0,0,0,0,0,0,0,0,0,0,0,0,0,0,0,0,0,0)';
      BIDIRECTIONAL='TRUE';
      INPUT_LOAD='(-0.01,0.01)';
      OUTPUT_LOAD='(1.0,-1.0)';
    'DDR4_SA_ECC7':
      PIN_NUMBER='(0,0,0,0,0,0,0,0,0,0,0,EP53,0,0,0,0,0,0,0,0,0,0,0,0,0,0,0,0,0,0,0,0,0,0,0,0,0,0,0,0,0,0)';
      BIDIRECTIONAL='TRUE';
      INPUT_LOAD='(-0.01,0.01)';
      OUTPUT_LOAD='(1.0,-1.0)';
    'DDR4_SA_ECC6':
      PIN_NUMBER='(0,0,0,0,0,0,0,0,0,0,0,ER54,0,0,0,0,0,0,0,0,0,0,0,0,0,0,0,0,0,0,0,0,0,0,0,0,0,0,0,0,0,0)';
      BIDIRECTIONAL='TRUE';
      INPUT_LOAD='(-0.01,0.01)';
      OUTPUT_LOAD='(1.0,-1.0)';
    'DDR4_SA_ECC5':
      PIN_NUMBER='(0,0,0,0,0,0,0,0,0,0,0,EM53,0,0,0,0,0,0,0,0,0,0,0,0,0,0,0,0,0,0,0,0,0,0,0,0,0,0,0,0,0,0)';
      BIDIRECTIONAL='TRUE';
      INPUT_LOAD='(-0.01,0.01)';
      OUTPUT_LOAD='(1.0,-1.0)';
    'DDR4_SA_ECC4':
      PIN_NUMBER='(0,0,0,0,0,0,0,0,0,0,0,EL54,0,0,0,0,0,0,0,0,0,0,0,0,0,0,0,0,0,0,0,0,0,0,0,0,0,0,0,0,0,0)';
      BIDIRECTIONAL='TRUE';
      INPUT_LOAD='(-0.01,0.01)';
      OUTPUT_LOAD='(1.0,-1.0)';
    'DDR4_SA_ECC3':
      PIN_NUMBER='(0,0,0,0,0,0,0,0,0,0,0,ER56,0,0,0,0,0,0,0,0,0,0,0,0,0,0,0,0,0,0,0,0,0,0,0,0,0,0,0,0,0,0)';
      BIDIRECTIONAL='TRUE';
      INPUT_LOAD='(-0.01,0.01)';
      OUTPUT_LOAD='(1.0,-1.0)';
    'DDR4_SA_ECC2':
      PIN_NUMBER='(0,0,0,0,0,0,0,0,0,0,0,EP57,0,0,0,0,0,0,0,0,0,0,0,0,0,0,0,0,0,0,0,0,0,0,0,0,0,0,0,0,0,0)';
      BIDIRECTIONAL='TRUE';
      INPUT_LOAD='(-0.01,0.01)';
      OUTPUT_LOAD='(1.0,-1.0)';
    'DDR4_SA_ECC1':
      PIN_NUMBER='(0,0,0,0,0,0,0,0,0,0,0,EL56,0,0,0,0,0,0,0,0,0,0,0,0,0,0,0,0,0,0,0,0,0,0,0,0,0,0,0,0,0,0)';
      BIDIRECTIONAL='TRUE';
      INPUT_LOAD='(-0.01,0.01)';
      OUTPUT_LOAD='(1.0,-1.0)';
    'DDR4_SA_ECC0':
      PIN_NUMBER='(0,0,0,0,0,0,0,0,0,0,0,EM57,0,0,0,0,0,0,0,0,0,0,0,0,0,0,0,0,0,0,0,0,0,0,0,0,0,0,0,0,0,0)';
      BIDIRECTIONAL='TRUE';
      INPUT_LOAD='(-0.01,0.01)';
      OUTPUT_LOAD='(1.0,-1.0)';
    'DDR4_SA_PAR':
      PIN_NUMBER='(0,0,0,0,0,0,0,0,0,0,0,EE43,0,0,0,0,0,0,0,0,0,0,0,0,0,0,0,0,0,0,0,0,0,0,0,0,0,0,0,0,0,0)';
      OUTPUT_LOAD='(1.0,-1.0)';
    'DDR4_SB_CA6':
      PIN_NUMBER='(0,0,0,0,0,0,0,0,0,0,0,EK42,0,0,0,0,0,0,0,0,0,0,0,0,0,0,0,0,0,0,0,0,0,0,0,0,0,0,0,0,0,0)';
      OUTPUT_LOAD='(1.0,-1.0)';
    'DDR4_SB_CA5':
      PIN_NUMBER='(0,0,0,0,0,0,0,0,0,0,0,ET42,0,0,0,0,0,0,0,0,0,0,0,0,0,0,0,0,0,0,0,0,0,0,0,0,0,0,0,0,0,0)';
      OUTPUT_LOAD='(1.0,-1.0)';
    'DDR4_SB_CA4':
      PIN_NUMBER='(0,0,0,0,0,0,0,0,0,0,0,EL43,0,0,0,0,0,0,0,0,0,0,0,0,0,0,0,0,0,0,0,0,0,0,0,0,0,0,0,0,0,0)';
      OUTPUT_LOAD='(1.0,-1.0)';
    'DDR4_SB_CA3':
      PIN_NUMBER='(0,0,0,0,0,0,0,0,0,0,0,EP44,0,0,0,0,0,0,0,0,0,0,0,0,0,0,0,0,0,0,0,0,0,0,0,0,0,0,0,0,0,0)';
      OUTPUT_LOAD='(1.0,-1.0)';
    'DDR4_SB_CA2':
      PIN_NUMBER='(0,0,0,0,0,0,0,0,0,0,0,EM44,0,0,0,0,0,0,0,0,0,0,0,0,0,0,0,0,0,0,0,0,0,0,0,0,0,0,0,0,0,0)';
      OUTPUT_LOAD='(1.0,-1.0)';
    'DDR4_SB_CA1':
      PIN_NUMBER='(0,0,0,0,0,0,0,0,0,0,0,EH44,0,0,0,0,0,0,0,0,0,0,0,0,0,0,0,0,0,0,0,0,0,0,0,0,0,0,0,0,0,0)';
      OUTPUT_LOAD='(1.0,-1.0)';
    'DDR4_SB_CA0':
      PIN_NUMBER='(0,0,0,0,0,0,0,0,0,0,0,EG43,0,0,0,0,0,0,0,0,0,0,0,0,0,0,0,0,0,0,0,0,0,0,0,0,0,0,0,0,0,0)';
      OUTPUT_LOAD='(1.0,-1.0)';
    'DDR4_SB_CS_N3':
      PIN_NUMBER='(0,0,0,0,0,0,0,0,0,0,0,EL41,0,0,0,0,0,0,0,0,0,0,0,0,0,0,0,0,0,0,0,0,0,0,0,0,0,0,0,0,0,0)';
      OUTPUT_LOAD='(1.0,-1.0)';
    'DDR4_SB_CS_N2':
      PIN_NUMBER='(0,0,0,0,0,0,0,0,0,0,0,EM40,0,0,0,0,0,0,0,0,0,0,0,0,0,0,0,0,0,0,0,0,0,0,0,0,0,0,0,0,0,0)';
      OUTPUT_LOAD='(1.0,-1.0)';
    'DDR4_SB_CS_N1':
      PIN_NUMBER='(0,0,0,0,0,0,0,0,0,0,0,ET40,0,0,0,0,0,0,0,0,0,0,0,0,0,0,0,0,0,0,0,0,0,0,0,0,0,0,0,0,0,0)';
      OUTPUT_LOAD='(1.0,-1.0)';
    'DDR4_SB_CS_N0':
      PIN_NUMBER='(0,0,0,0,0,0,0,0,0,0,0,EP40,0,0,0,0,0,0,0,0,0,0,0,0,0,0,0,0,0,0,0,0,0,0,0,0,0,0,0,0,0,0)';
      OUTPUT_LOAD='(1.0,-1.0)';
    'DDR4_SB_DQ31':
      PIN_NUMBER='(0,0,0,0,0,0,0,0,0,0,0,EP16,0,0,0,0,0,0,0,0,0,0,0,0,0,0,0,0,0,0,0,0,0,0,0,0,0,0,0,0,0,0)';
      BIDIRECTIONAL='TRUE';
      INPUT_LOAD='(-0.01,0.01)';
      OUTPUT_LOAD='(1.0,-1.0)';
    'DDR4_SB_DQ30':
      PIN_NUMBER='(0,0,0,0,0,0,0,0,0,0,0,ER17,0,0,0,0,0,0,0,0,0,0,0,0,0,0,0,0,0,0,0,0,0,0,0,0,0,0,0,0,0,0)';
      BIDIRECTIONAL='TRUE';
      INPUT_LOAD='(-0.01,0.01)';
      OUTPUT_LOAD='(1.0,-1.0)';
    'DDR4_SB_DQ29':
      PIN_NUMBER='(0,0,0,0,0,0,0,0,0,0,0,EM16,0,0,0,0,0,0,0,0,0,0,0,0,0,0,0,0,0,0,0,0,0,0,0,0,0,0,0,0,0,0)';
      BIDIRECTIONAL='TRUE';
      INPUT_LOAD='(-0.01,0.01)';
      OUTPUT_LOAD='(1.0,-1.0)';
    'DDR4_SB_DQ28':
      PIN_NUMBER='(0,0,0,0,0,0,0,0,0,0,0,EL17,0,0,0,0,0,0,0,0,0,0,0,0,0,0,0,0,0,0,0,0,0,0,0,0,0,0,0,0,0,0)';
      BIDIRECTIONAL='TRUE';
      INPUT_LOAD='(-0.01,0.01)';
      OUTPUT_LOAD='(1.0,-1.0)';
    'DDR4_SB_DQ27':
      PIN_NUMBER='(0,0,0,0,0,0,0,0,0,0,0,ER19,0,0,0,0,0,0,0,0,0,0,0,0,0,0,0,0,0,0,0,0,0,0,0,0,0,0,0,0,0,0)';
      BIDIRECTIONAL='TRUE';
      INPUT_LOAD='(-0.01,0.01)';
      OUTPUT_LOAD='(1.0,-1.0)';
    'DDR4_SB_DQ26':
      PIN_NUMBER='(0,0,0,0,0,0,0,0,0,0,0,EP20,0,0,0,0,0,0,0,0,0,0,0,0,0,0,0,0,0,0,0,0,0,0,0,0,0,0,0,0,0,0)';
      BIDIRECTIONAL='TRUE';
      INPUT_LOAD='(-0.01,0.01)';
      OUTPUT_LOAD='(1.0,-1.0)';
    'DDR4_SB_DQ25':
      PIN_NUMBER='(0,0,0,0,0,0,0,0,0,0,0,EL19,0,0,0,0,0,0,0,0,0,0,0,0,0,0,0,0,0,0,0,0,0,0,0,0,0,0,0,0,0,0)';
      BIDIRECTIONAL='TRUE';
      INPUT_LOAD='(-0.01,0.01)';
      OUTPUT_LOAD='(1.0,-1.0)';
    'DDR4_SB_DQ24':
      PIN_NUMBER='(0,0,0,0,0,0,0,0,0,0,0,EM20,0,0,0,0,0,0,0,0,0,0,0,0,0,0,0,0,0,0,0,0,0,0,0,0,0,0,0,0,0,0)';
      BIDIRECTIONAL='TRUE';
      INPUT_LOAD='(-0.01,0.01)';
      OUTPUT_LOAD='(1.0,-1.0)';
    'DDR4_SB_DQ23':
      PIN_NUMBER='(0,0,0,0,0,0,0,0,0,0,0,EP22,0,0,0,0,0,0,0,0,0,0,0,0,0,0,0,0,0,0,0,0,0,0,0,0,0,0,0,0,0,0)';
      BIDIRECTIONAL='TRUE';
      INPUT_LOAD='(-0.01,0.01)';
      OUTPUT_LOAD='(1.0,-1.0)';
    'DDR4_SB_DQ22':
      PIN_NUMBER='(0,0,0,0,0,0,0,0,0,0,0,ER23,0,0,0,0,0,0,0,0,0,0,0,0,0,0,0,0,0,0,0,0,0,0,0,0,0,0,0,0,0,0)';
      BIDIRECTIONAL='TRUE';
      INPUT_LOAD='(-0.01,0.01)';
      OUTPUT_LOAD='(1.0,-1.0)';
    'DDR4_SB_DQ21':
      PIN_NUMBER='(0,0,0,0,0,0,0,0,0,0,0,EM22,0,0,0,0,0,0,0,0,0,0,0,0,0,0,0,0,0,0,0,0,0,0,0,0,0,0,0,0,0,0)';
      BIDIRECTIONAL='TRUE';
      INPUT_LOAD='(-0.01,0.01)';
      OUTPUT_LOAD='(1.0,-1.0)';
    'DDR4_SB_DQ20':
      PIN_NUMBER='(0,0,0,0,0,0,0,0,0,0,0,EL23,0,0,0,0,0,0,0,0,0,0,0,0,0,0,0,0,0,0,0,0,0,0,0,0,0,0,0,0,0,0)';
      BIDIRECTIONAL='TRUE';
      INPUT_LOAD='(-0.01,0.01)';
      OUTPUT_LOAD='(1.0,-1.0)';
    'DDR4_SB_DQ19':
      PIN_NUMBER='(0,0,0,0,0,0,0,0,0,0,0,ER25,0,0,0,0,0,0,0,0,0,0,0,0,0,0,0,0,0,0,0,0,0,0,0,0,0,0,0,0,0,0)';
      BIDIRECTIONAL='TRUE';
      INPUT_LOAD='(-0.01,0.01)';
      OUTPUT_LOAD='(1.0,-1.0)';
    'DDR4_SB_DQ18':
      PIN_NUMBER='(0,0,0,0,0,0,0,0,0,0,0,EP26,0,0,0,0,0,0,0,0,0,0,0,0,0,0,0,0,0,0,0,0,0,0,0,0,0,0,0,0,0,0)';
      BIDIRECTIONAL='TRUE';
      INPUT_LOAD='(-0.01,0.01)';
      OUTPUT_LOAD='(1.0,-1.0)';
    'DDR4_SB_DQ17':
      PIN_NUMBER='(0,0,0,0,0,0,0,0,0,0,0,EL25,0,0,0,0,0,0,0,0,0,0,0,0,0,0,0,0,0,0,0,0,0,0,0,0,0,0,0,0,0,0)';
      BIDIRECTIONAL='TRUE';
      INPUT_LOAD='(-0.01,0.01)';
      OUTPUT_LOAD='(1.0,-1.0)';
    'DDR4_SB_DQ16':
      PIN_NUMBER='(0,0,0,0,0,0,0,0,0,0,0,EM26,0,0,0,0,0,0,0,0,0,0,0,0,0,0,0,0,0,0,0,0,0,0,0,0,0,0,0,0,0,0)';
      BIDIRECTIONAL='TRUE';
      INPUT_LOAD='(-0.01,0.01)';
      OUTPUT_LOAD='(1.0,-1.0)';
    'DDR4_SB_DQ15':
      PIN_NUMBER='(0,0,0,0,0,0,0,0,0,0,0,EP28,0,0,0,0,0,0,0,0,0,0,0,0,0,0,0,0,0,0,0,0,0,0,0,0,0,0,0,0,0,0)';
      BIDIRECTIONAL='TRUE';
      INPUT_LOAD='(-0.01,0.01)';
      OUTPUT_LOAD='(1.0,-1.0)';
    'DDR4_SB_DQ14':
      PIN_NUMBER='(0,0,0,0,0,0,0,0,0,0,0,ER29,0,0,0,0,0,0,0,0,0,0,0,0,0,0,0,0,0,0,0,0,0,0,0,0,0,0,0,0,0,0)';
      BIDIRECTIONAL='TRUE';
      INPUT_LOAD='(-0.01,0.01)';
      OUTPUT_LOAD='(1.0,-1.0)';
    'DDR4_SB_DQ13':
      PIN_NUMBER='(0,0,0,0,0,0,0,0,0,0,0,EM28,0,0,0,0,0,0,0,0,0,0,0,0,0,0,0,0,0,0,0,0,0,0,0,0,0,0,0,0,0,0)';
      BIDIRECTIONAL='TRUE';
      INPUT_LOAD='(-0.01,0.01)';
      OUTPUT_LOAD='(1.0,-1.0)';
    'DDR4_SB_DQ12':
      PIN_NUMBER='(0,0,0,0,0,0,0,0,0,0,0,EL29,0,0,0,0,0,0,0,0,0,0,0,0,0,0,0,0,0,0,0,0,0,0,0,0,0,0,0,0,0,0)';
      BIDIRECTIONAL='TRUE';
      INPUT_LOAD='(-0.01,0.01)';
      OUTPUT_LOAD='(1.0,-1.0)';
    'DDR4_SB_DQ11':
      PIN_NUMBER='(0,0,0,0,0,0,0,0,0,0,0,ER31,0,0,0,0,0,0,0,0,0,0,0,0,0,0,0,0,0,0,0,0,0,0,0,0,0,0,0,0,0,0)';
      BIDIRECTIONAL='TRUE';
      INPUT_LOAD='(-0.01,0.01)';
      OUTPUT_LOAD='(1.0,-1.0)';
    'DDR4_SB_DQ10':
      PIN_NUMBER='(0,0,0,0,0,0,0,0,0,0,0,EP32,0,0,0,0,0,0,0,0,0,0,0,0,0,0,0,0,0,0,0,0,0,0,0,0,0,0,0,0,0,0)';
      BIDIRECTIONAL='TRUE';
      INPUT_LOAD='(-0.01,0.01)';
      OUTPUT_LOAD='(1.0,-1.0)';
    'DDR4_SB_DQ9':
      PIN_NUMBER='(0,0,0,0,0,0,0,0,0,0,0,EL31,0,0,0,0,0,0,0,0,0,0,0,0,0,0,0,0,0,0,0,0,0,0,0,0,0,0,0,0,0,0)';
      BIDIRECTIONAL='TRUE';
      INPUT_LOAD='(-0.01,0.01)';
      OUTPUT_LOAD='(1.0,-1.0)';
    'DDR4_SB_DQ8':
      PIN_NUMBER='(0,0,0,0,0,0,0,0,0,0,0,EM32,0,0,0,0,0,0,0,0,0,0,0,0,0,0,0,0,0,0,0,0,0,0,0,0,0,0,0,0,0,0)';
      BIDIRECTIONAL='TRUE';
      INPUT_LOAD='(-0.01,0.01)';
      OUTPUT_LOAD='(1.0,-1.0)';
    'DDR4_SB_DQ7':
      PIN_NUMBER='(0,0,0,0,0,0,0,0,0,0,0,EG25,0,0,0,0,0,0,0,0,0,0,0,0,0,0,0,0,0,0,0,0,0,0,0,0,0,0,0,0,0,0)';
      BIDIRECTIONAL='TRUE';
      INPUT_LOAD='(-0.01,0.01)';
      OUTPUT_LOAD='(1.0,-1.0)';
    'DDR4_SB_DQ6':
      PIN_NUMBER='(0,0,0,0,0,0,0,0,0,0,0,EH26,0,0,0,0,0,0,0,0,0,0,0,0,0,0,0,0,0,0,0,0,0,0,0,0,0,0,0,0,0,0)';
      BIDIRECTIONAL='TRUE';
      INPUT_LOAD='(-0.01,0.01)';
      OUTPUT_LOAD='(1.0,-1.0)';
    'DDR4_SB_DQ5':
      PIN_NUMBER='(0,0,0,0,0,0,0,0,0,0,0,EE25,0,0,0,0,0,0,0,0,0,0,0,0,0,0,0,0,0,0,0,0,0,0,0,0,0,0,0,0,0,0)';
      BIDIRECTIONAL='TRUE';
      INPUT_LOAD='(-0.01,0.01)';
      OUTPUT_LOAD='(1.0,-1.0)';
    'DDR4_SB_DQ4':
      PIN_NUMBER='(0,0,0,0,0,0,0,0,0,0,0,ED26,0,0,0,0,0,0,0,0,0,0,0,0,0,0,0,0,0,0,0,0,0,0,0,0,0,0,0,0,0,0)';
      BIDIRECTIONAL='TRUE';
      INPUT_LOAD='(-0.01,0.01)';
      OUTPUT_LOAD='(1.0,-1.0)';
    'DDR4_SB_DQ3':
      PIN_NUMBER='(0,0,0,0,0,0,0,0,0,0,0,EH28,0,0,0,0,0,0,0,0,0,0,0,0,0,0,0,0,0,0,0,0,0,0,0,0,0,0,0,0,0,0)';
      BIDIRECTIONAL='TRUE';
      INPUT_LOAD='(-0.01,0.01)';
      OUTPUT_LOAD='(1.0,-1.0)';
    'DDR4_SB_DQ2':
      PIN_NUMBER='(0,0,0,0,0,0,0,0,0,0,0,EG29,0,0,0,0,0,0,0,0,0,0,0,0,0,0,0,0,0,0,0,0,0,0,0,0,0,0,0,0,0,0)';
      BIDIRECTIONAL='TRUE';
      INPUT_LOAD='(-0.01,0.01)';
      OUTPUT_LOAD='(1.0,-1.0)';
    'DDR4_SB_DQ1':
      PIN_NUMBER='(0,0,0,0,0,0,0,0,0,0,0,ED28,0,0,0,0,0,0,0,0,0,0,0,0,0,0,0,0,0,0,0,0,0,0,0,0,0,0,0,0,0,0)';
      BIDIRECTIONAL='TRUE';
      INPUT_LOAD='(-0.01,0.01)';
      OUTPUT_LOAD='(1.0,-1.0)';
    'DDR4_SB_DQ0':
      PIN_NUMBER='(0,0,0,0,0,0,0,0,0,0,0,EE29,0,0,0,0,0,0,0,0,0,0,0,0,0,0,0,0,0,0,0,0,0,0,0,0,0,0,0,0,0,0)';
      BIDIRECTIONAL='TRUE';
      INPUT_LOAD='(-0.01,0.01)';
      OUTPUT_LOAD='(1.0,-1.0)';
    'DDR4_SB_DQS_DN9':
      PIN_NUMBER='(0,0,0,0,0,0,0,0,0,0,0,EK36,0,0,0,0,0,0,0,0,0,0,0,0,0,0,0,0,0,0,0,0,0,0,0,0,0,0,0,0,0,0)';
      BIDIRECTIONAL='TRUE';
      INPUT_LOAD='(-0.01,0.01)';
      OUTPUT_LOAD='(1.0,-1.0)';
    'DDR4_SB_DQS_DN8':
      PIN_NUMBER='(0,0,0,0,0,0,0,0,0,0,0,ET18,0,0,0,0,0,0,0,0,0,0,0,0,0,0,0,0,0,0,0,0,0,0,0,0,0,0,0,0,0,0)';
      BIDIRECTIONAL='TRUE';
      INPUT_LOAD='(-0.01,0.01)';
      OUTPUT_LOAD='(1.0,-1.0)';
    'DDR4_SB_DQS_DN7':
      PIN_NUMBER='(0,0,0,0,0,0,0,0,0,0,0,ET24,0,0,0,0,0,0,0,0,0,0,0,0,0,0,0,0,0,0,0,0,0,0,0,0,0,0,0,0,0,0)';
      BIDIRECTIONAL='TRUE';
      INPUT_LOAD='(-0.01,0.01)';
      OUTPUT_LOAD='(1.0,-1.0)';
    'DDR4_SB_DQS_DN6':
      PIN_NUMBER='(0,0,0,0,0,0,0,0,0,0,0,ET30,0,0,0,0,0,0,0,0,0,0,0,0,0,0,0,0,0,0,0,0,0,0,0,0,0,0,0,0,0,0)';
      BIDIRECTIONAL='TRUE';
      INPUT_LOAD='(-0.01,0.01)';
      OUTPUT_LOAD='(1.0,-1.0)';
    'DDR4_SB_DQS_DN5':
      PIN_NUMBER='(0,0,0,0,0,0,0,0,0,0,0,EJ27,0,0,0,0,0,0,0,0,0,0,0,0,0,0,0,0,0,0,0,0,0,0,0,0,0,0,0,0,0,0)';
      BIDIRECTIONAL='TRUE';
      INPUT_LOAD='(-0.01,0.01)';
      OUTPUT_LOAD='(1.0,-1.0)';
    'DDR4_SB_DQS_DN4':
      PIN_NUMBER='(0,0,0,0,0,0,0,0,0,0,0,ET36,0,0,0,0,0,0,0,0,0,0,0,0,0,0,0,0,0,0,0,0,0,0,0,0,0,0,0,0,0,0)';
      BIDIRECTIONAL='TRUE';
      INPUT_LOAD='(-0.01,0.01)';
      OUTPUT_LOAD='(1.0,-1.0)';
    'DDR4_SB_DQS_DN3':
      PIN_NUMBER='(0,0,0,0,0,0,0,0,0,0,0,EK18,0,0,0,0,0,0,0,0,0,0,0,0,0,0,0,0,0,0,0,0,0,0,0,0,0,0,0,0,0,0)';
      BIDIRECTIONAL='TRUE';
      INPUT_LOAD='(-0.01,0.01)';
      OUTPUT_LOAD='(1.0,-1.0)';
    'DDR4_SB_DQS_DN2':
      PIN_NUMBER='(0,0,0,0,0,0,0,0,0,0,0,EK24,0,0,0,0,0,0,0,0,0,0,0,0,0,0,0,0,0,0,0,0,0,0,0,0,0,0,0,0,0,0)';
      BIDIRECTIONAL='TRUE';
      INPUT_LOAD='(-0.01,0.01)';
      OUTPUT_LOAD='(1.0,-1.0)';
    'DDR4_SB_DQS_DN1':
      PIN_NUMBER='(0,0,0,0,0,0,0,0,0,0,0,EK30,0,0,0,0,0,0,0,0,0,0,0,0,0,0,0,0,0,0,0,0,0,0,0,0,0,0,0,0,0,0)';
      BIDIRECTIONAL='TRUE';
      INPUT_LOAD='(-0.01,0.01)';
      OUTPUT_LOAD='(1.0,-1.0)';
    'DDR4_SB_DQS_DN0':
      PIN_NUMBER='(0,0,0,0,0,0,0,0,0,0,0,EE27,0,0,0,0,0,0,0,0,0,0,0,0,0,0,0,0,0,0,0,0,0,0,0,0,0,0,0,0,0,0)';
      BIDIRECTIONAL='TRUE';
      INPUT_LOAD='(-0.01,0.01)';
      OUTPUT_LOAD='(1.0,-1.0)';
    'DDR4_SB_DQS_DP9':
      PIN_NUMBER='(0,0,0,0,0,0,0,0,0,0,0,EM36,0,0,0,0,0,0,0,0,0,0,0,0,0,0,0,0,0,0,0,0,0,0,0,0,0,0,0,0,0,0)';
      BIDIRECTIONAL='TRUE';
      INPUT_LOAD='(-0.01,0.01)';
      OUTPUT_LOAD='(1.0,-1.0)';
    'DDR4_SB_DQS_DP8':
      PIN_NUMBER='(0,0,0,0,0,0,0,0,0,0,0,EP18,0,0,0,0,0,0,0,0,0,0,0,0,0,0,0,0,0,0,0,0,0,0,0,0,0,0,0,0,0,0)';
      BIDIRECTIONAL='TRUE';
      INPUT_LOAD='(-0.01,0.01)';
      OUTPUT_LOAD='(1.0,-1.0)';
    'DDR4_SB_DQS_DP7':
      PIN_NUMBER='(0,0,0,0,0,0,0,0,0,0,0,EP24,0,0,0,0,0,0,0,0,0,0,0,0,0,0,0,0,0,0,0,0,0,0,0,0,0,0,0,0,0,0)';
      BIDIRECTIONAL='TRUE';
      INPUT_LOAD='(-0.01,0.01)';
      OUTPUT_LOAD='(1.0,-1.0)';
    'DDR4_SB_DQS_DP6':
      PIN_NUMBER='(0,0,0,0,0,0,0,0,0,0,0,EP30,0,0,0,0,0,0,0,0,0,0,0,0,0,0,0,0,0,0,0,0,0,0,0,0,0,0,0,0,0,0)';
      BIDIRECTIONAL='TRUE';
      INPUT_LOAD='(-0.01,0.01)';
      OUTPUT_LOAD='(1.0,-1.0)';
    'DDR4_SB_DQS_DP5':
      PIN_NUMBER='(0,0,0,0,0,0,0,0,0,0,0,EG27,0,0,0,0,0,0,0,0,0,0,0,0,0,0,0,0,0,0,0,0,0,0,0,0,0,0,0,0,0,0)';
      BIDIRECTIONAL='TRUE';
      INPUT_LOAD='(-0.01,0.01)';
      OUTPUT_LOAD='(1.0,-1.0)';
    'DDR4_SB_DQS_DP4':
      PIN_NUMBER='(0,0,0,0,0,0,0,0,0,0,0,EP36,0,0,0,0,0,0,0,0,0,0,0,0,0,0,0,0,0,0,0,0,0,0,0,0,0,0,0,0,0,0)';
      BIDIRECTIONAL='TRUE';
      INPUT_LOAD='(-0.01,0.01)';
      OUTPUT_LOAD='(1.0,-1.0)';
    'DDR4_SB_DQS_DP3':
      PIN_NUMBER='(0,0,0,0,0,0,0,0,0,0,0,EM18,0,0,0,0,0,0,0,0,0,0,0,0,0,0,0,0,0,0,0,0,0,0,0,0,0,0,0,0,0,0)';
      BIDIRECTIONAL='TRUE';
      INPUT_LOAD='(-0.01,0.01)';
      OUTPUT_LOAD='(1.0,-1.0)';
    'DDR4_SB_DQS_DP2':
      PIN_NUMBER='(0,0,0,0,0,0,0,0,0,0,0,EM24,0,0,0,0,0,0,0,0,0,0,0,0,0,0,0,0,0,0,0,0,0,0,0,0,0,0,0,0,0,0)';
      BIDIRECTIONAL='TRUE';
      INPUT_LOAD='(-0.01,0.01)';
      OUTPUT_LOAD='(1.0,-1.0)';
    'DDR4_SB_DQS_DP1':
      PIN_NUMBER='(0,0,0,0,0,0,0,0,0,0,0,EM30,0,0,0,0,0,0,0,0,0,0,0,0,0,0,0,0,0,0,0,0,0,0,0,0,0,0,0,0,0,0)';
      BIDIRECTIONAL='TRUE';
      INPUT_LOAD='(-0.01,0.01)';
      OUTPUT_LOAD='(1.0,-1.0)';
    'DDR4_SB_DQS_DP0':
      PIN_NUMBER='(0,0,0,0,0,0,0,0,0,0,0,EC27,0,0,0,0,0,0,0,0,0,0,0,0,0,0,0,0,0,0,0,0,0,0,0,0,0,0,0,0,0,0)';
      BIDIRECTIONAL='TRUE';
      INPUT_LOAD='(-0.01,0.01)';
      OUTPUT_LOAD='(1.0,-1.0)';
    'DDR4_SB_ECC7':
      PIN_NUMBER='(0,0,0,0,0,0,0,0,0,0,0,ER37,0,0,0,0,0,0,0,0,0,0,0,0,0,0,0,0,0,0,0,0,0,0,0,0,0,0,0,0,0,0)';
      BIDIRECTIONAL='TRUE';
      INPUT_LOAD='(-0.01,0.01)';
      OUTPUT_LOAD='(1.0,-1.0)';
    'DDR4_SB_ECC6':
      PIN_NUMBER='(0,0,0,0,0,0,0,0,0,0,0,EP38,0,0,0,0,0,0,0,0,0,0,0,0,0,0,0,0,0,0,0,0,0,0,0,0,0,0,0,0,0,0)';
      BIDIRECTIONAL='TRUE';
      INPUT_LOAD='(-0.01,0.01)';
      OUTPUT_LOAD='(1.0,-1.0)';
    'DDR4_SB_ECC5':
      PIN_NUMBER='(0,0,0,0,0,0,0,0,0,0,0,EL37,0,0,0,0,0,0,0,0,0,0,0,0,0,0,0,0,0,0,0,0,0,0,0,0,0,0,0,0,0,0)';
      BIDIRECTIONAL='TRUE';
      INPUT_LOAD='(-0.01,0.01)';
      OUTPUT_LOAD='(1.0,-1.0)';
    'DDR4_SB_ECC4':
      PIN_NUMBER='(0,0,0,0,0,0,0,0,0,0,0,EM38,0,0,0,0,0,0,0,0,0,0,0,0,0,0,0,0,0,0,0,0,0,0,0,0,0,0,0,0,0,0)';
      BIDIRECTIONAL='TRUE';
      INPUT_LOAD='(-0.01,0.01)';
      OUTPUT_LOAD='(1.0,-1.0)';
    'DDR4_SB_ECC3':
      PIN_NUMBER='(0,0,0,0,0,0,0,0,0,0,0,EP34,0,0,0,0,0,0,0,0,0,0,0,0,0,0,0,0,0,0,0,0,0,0,0,0,0,0,0,0,0,0)';
      BIDIRECTIONAL='TRUE';
      INPUT_LOAD='(-0.01,0.01)';
      OUTPUT_LOAD='(1.0,-1.0)';
    'DDR4_SB_ECC2':
      PIN_NUMBER='(0,0,0,0,0,0,0,0,0,0,0,ER35,0,0,0,0,0,0,0,0,0,0,0,0,0,0,0,0,0,0,0,0,0,0,0,0,0,0,0,0,0,0)';
      BIDIRECTIONAL='TRUE';
      INPUT_LOAD='(-0.01,0.01)';
      OUTPUT_LOAD='(1.0,-1.0)';
    'DDR4_SB_ECC1':
      PIN_NUMBER='(0,0,0,0,0,0,0,0,0,0,0,EM34,0,0,0,0,0,0,0,0,0,0,0,0,0,0,0,0,0,0,0,0,0,0,0,0,0,0,0,0,0,0)';
      BIDIRECTIONAL='TRUE';
      INPUT_LOAD='(-0.01,0.01)';
      OUTPUT_LOAD='(1.0,-1.0)';
    'DDR4_SB_ECC0':
      PIN_NUMBER='(0,0,0,0,0,0,0,0,0,0,0,EL35,0,0,0,0,0,0,0,0,0,0,0,0,0,0,0,0,0,0,0,0,0,0,0,0,0,0,0,0,0,0)';
      BIDIRECTIONAL='TRUE';
      INPUT_LOAD='(-0.01,0.01)';
      OUTPUT_LOAD='(1.0,-1.0)';
    'DDR4_SB_PAR':
      PIN_NUMBER='(0,0,0,0,0,0,0,0,0,0,0,EP42,0,0,0,0,0,0,0,0,0,0,0,0,0,0,0,0,0,0,0,0,0,0,0,0,0,0,0,0,0,0)';
      OUTPUT_LOAD='(1.0,-1.0)';
    '-DDR5_ALERT':
      PIN_NUMBER='(0,0,0,0,0,0,0,0,0,0,0,0,CW48,0,0,0,0,0,0,0,0,0,0,0,0,0,0,0,0,0,0,0,0,0,0,0,0,0,0,0,0,0)';
      INPUT_LOAD='(-0.01,0.01)';
    'DDR5_A_RSP1':
      PIN_NUMBER='(0,0,0,0,0,0,0,0,0,0,0,0,DP47,0,0,0,0,0,0,0,0,0,0,0,0,0,0,0,0,0,0,0,0,0,0,0,0,0,0,0,0,0)';
      INPUT_LOAD='(-0.01,0.01)';
    'DDR5_A_RSP0':
      PIN_NUMBER='(0,0,0,0,0,0,0,0,0,0,0,0,DN48,0,0,0,0,0,0,0,0,0,0,0,0,0,0,0,0,0,0,0,0,0,0,0,0,0,0,0,0,0)';
      INPUT_LOAD='(-0.01,0.01)';
    'DDR5_B_RSP1':
      PIN_NUMBER='(0,0,0,0,0,0,0,0,0,0,0,0,DK47,0,0,0,0,0,0,0,0,0,0,0,0,0,0,0,0,0,0,0,0,0,0,0,0,0,0,0,0,0)';
      INPUT_LOAD='(-0.01,0.01)';
    'DDR5_B_RSP0':
      PIN_NUMBER='(0,0,0,0,0,0,0,0,0,0,0,0,DL48,0,0,0,0,0,0,0,0,0,0,0,0,0,0,0,0,0,0,0,0,0,0,0,0,0,0,0,0,0)';
      INPUT_LOAD='(-0.01,0.01)';
    'DDR5_CLK_DN1':
      PIN_NUMBER='(0,0,0,0,0,0,0,0,0,0,0,0,DV49,0,0,0,0,0,0,0,0,0,0,0,0,0,0,0,0,0,0,0,0,0,0,0,0,0,0,0,0,0)';
      OUTPUT_LOAD='(1.0,-1.0)';
    'DDR5_CLK_DN0':
      PIN_NUMBER='(0,0,0,0,0,0,0,0,0,0,0,0,DY49,0,0,0,0,0,0,0,0,0,0,0,0,0,0,0,0,0,0,0,0,0,0,0,0,0,0,0,0,0)';
      OUTPUT_LOAD='(1.0,-1.0)';
    'DDR5_CLK_DP1':
      PIN_NUMBER='(0,0,0,0,0,0,0,0,0,0,0,0,DT49,0,0,0,0,0,0,0,0,0,0,0,0,0,0,0,0,0,0,0,0,0,0,0,0,0,0,0,0,0)';
      OUTPUT_LOAD='(1.0,-1.0)';
    'DDR5_CLK_DP0':
      PIN_NUMBER='(0,0,0,0,0,0,0,0,0,0,0,0,EB49,0,0,0,0,0,0,0,0,0,0,0,0,0,0,0,0,0,0,0,0,0,0,0,0,0,0,0,0,0)';
      OUTPUT_LOAD='(1.0,-1.0)';
    'DDR5_SA_CA6':
      PIN_NUMBER='(0,0,0,0,0,0,0,0,0,0,0,0,DY51,0,0,0,0,0,0,0,0,0,0,0,0,0,0,0,0,0,0,0,0,0,0,0,0,0,0,0,0,0)';
      OUTPUT_LOAD='(1.0,-1.0)';
    'DDR5_SA_CA5':
      PIN_NUMBER='(0,0,0,0,0,0,0,0,0,0,0,0,EG50,0,0,0,0,0,0,0,0,0,0,0,0,0,0,0,0,0,0,0,0,0,0,0,0,0,0,0,0,0)';
      OUTPUT_LOAD='(1.0,-1.0)';
    'DDR5_SA_CA4':
      PIN_NUMBER='(0,0,0,0,0,0,0,0,0,0,0,0,EE50,0,0,0,0,0,0,0,0,0,0,0,0,0,0,0,0,0,0,0,0,0,0,0,0,0,0,0,0,0)';
      OUTPUT_LOAD='(1.0,-1.0)';
    'DDR5_SA_CA3':
      PIN_NUMBER='(0,0,0,0,0,0,0,0,0,0,0,0,EH51,0,0,0,0,0,0,0,0,0,0,0,0,0,0,0,0,0,0,0,0,0,0,0,0,0,0,0,0,0)';
      OUTPUT_LOAD='(1.0,-1.0)';
    'DDR5_SA_CA2':
      PIN_NUMBER='(0,0,0,0,0,0,0,0,0,0,0,0,ED51,0,0,0,0,0,0,0,0,0,0,0,0,0,0,0,0,0,0,0,0,0,0,0,0,0,0,0,0,0)';
      OUTPUT_LOAD='(1.0,-1.0)';
    'DDR5_SA_CA1':
      PIN_NUMBER='(0,0,0,0,0,0,0,0,0,0,0,0,EJ52,0,0,0,0,0,0,0,0,0,0,0,0,0,0,0,0,0,0,0,0,0,0,0,0,0,0,0,0,0)';
      OUTPUT_LOAD='(1.0,-1.0)';
    'DDR5_SA_CA0':
      PIN_NUMBER='(0,0,0,0,0,0,0,0,0,0,0,0,EC52,0,0,0,0,0,0,0,0,0,0,0,0,0,0,0,0,0,0,0,0,0,0,0,0,0,0,0,0,0)';
      OUTPUT_LOAD='(1.0,-1.0)';
    'DDR5_SA_CS_N3':
      PIN_NUMBER='(0,0,0,0,0,0,0,0,0,0,0,0,ED53,0,0,0,0,0,0,0,0,0,0,0,0,0,0,0,0,0,0,0,0,0,0,0,0,0,0,0,0,0)';
      OUTPUT_LOAD='(1.0,-1.0)';
    'DDR5_SA_CS_N2':
      PIN_NUMBER='(0,0,0,0,0,0,0,0,0,0,0,0,EE54,0,0,0,0,0,0,0,0,0,0,0,0,0,0,0,0,0,0,0,0,0,0,0,0,0,0,0,0,0)';
      OUTPUT_LOAD='(1.0,-1.0)';
    'DDR5_SA_CS_N1':
      PIN_NUMBER='(0,0,0,0,0,0,0,0,0,0,0,0,EH53,0,0,0,0,0,0,0,0,0,0,0,0,0,0,0,0,0,0,0,0,0,0,0,0,0,0,0,0,0)';
      OUTPUT_LOAD='(1.0,-1.0)';
    'DDR5_SA_CS_N0':
      PIN_NUMBER='(0,0,0,0,0,0,0,0,0,0,0,0,EG54,0,0,0,0,0,0,0,0,0,0,0,0,0,0,0,0,0,0,0,0,0,0,0,0,0,0,0,0,0)';
      OUTPUT_LOAD='(1.0,-1.0)';
    'DDR5_SA_DQ31':
      PIN_NUMBER='(0,0,0,0,0,0,0,0,0,0,0,0,DY53,0,0,0,0,0,0,0,0,0,0,0,0,0,0,0,0,0,0,0,0,0,0,0,0,0,0,0,0,0)';
      BIDIRECTIONAL='TRUE';
      INPUT_LOAD='(-0.01,0.01)';
      OUTPUT_LOAD='(1.0,-1.0)';
    'DDR5_SA_DQ30':
      PIN_NUMBER='(0,0,0,0,0,0,0,0,0,0,0,0,EA54,0,0,0,0,0,0,0,0,0,0,0,0,0,0,0,0,0,0,0,0,0,0,0,0,0,0,0,0,0)';
      BIDIRECTIONAL='TRUE';
      INPUT_LOAD='(-0.01,0.01)';
      OUTPUT_LOAD='(1.0,-1.0)';
    'DDR5_SA_DQ29':
      PIN_NUMBER='(0,0,0,0,0,0,0,0,0,0,0,0,DV53,0,0,0,0,0,0,0,0,0,0,0,0,0,0,0,0,0,0,0,0,0,0,0,0,0,0,0,0,0)';
      BIDIRECTIONAL='TRUE';
      INPUT_LOAD='(-0.01,0.01)';
      OUTPUT_LOAD='(1.0,-1.0)';
    'DDR5_SA_DQ28':
      PIN_NUMBER='(0,0,0,0,0,0,0,0,0,0,0,0,DU54,0,0,0,0,0,0,0,0,0,0,0,0,0,0,0,0,0,0,0,0,0,0,0,0,0,0,0,0,0)';
      BIDIRECTIONAL='TRUE';
      INPUT_LOAD='(-0.01,0.01)';
      OUTPUT_LOAD='(1.0,-1.0)';
    'DDR5_SA_DQ27':
      PIN_NUMBER='(0,0,0,0,0,0,0,0,0,0,0,0,EA56,0,0,0,0,0,0,0,0,0,0,0,0,0,0,0,0,0,0,0,0,0,0,0,0,0,0,0,0,0)';
      BIDIRECTIONAL='TRUE';
      INPUT_LOAD='(-0.01,0.01)';
      OUTPUT_LOAD='(1.0,-1.0)';
    'DDR5_SA_DQ26':
      PIN_NUMBER='(0,0,0,0,0,0,0,0,0,0,0,0,DY57,0,0,0,0,0,0,0,0,0,0,0,0,0,0,0,0,0,0,0,0,0,0,0,0,0,0,0,0,0)';
      BIDIRECTIONAL='TRUE';
      INPUT_LOAD='(-0.01,0.01)';
      OUTPUT_LOAD='(1.0,-1.0)';
    'DDR5_SA_DQ25':
      PIN_NUMBER='(0,0,0,0,0,0,0,0,0,0,0,0,DU56,0,0,0,0,0,0,0,0,0,0,0,0,0,0,0,0,0,0,0,0,0,0,0,0,0,0,0,0,0)';
      BIDIRECTIONAL='TRUE';
      INPUT_LOAD='(-0.01,0.01)';
      OUTPUT_LOAD='(1.0,-1.0)';
    'DDR5_SA_DQ24':
      PIN_NUMBER='(0,0,0,0,0,0,0,0,0,0,0,0,DV57,0,0,0,0,0,0,0,0,0,0,0,0,0,0,0,0,0,0,0,0,0,0,0,0,0,0,0,0,0)';
      BIDIRECTIONAL='TRUE';
      INPUT_LOAD='(-0.01,0.01)';
      OUTPUT_LOAD='(1.0,-1.0)';
    'DDR5_SA_DQ23':
      PIN_NUMBER='(0,0,0,0,0,0,0,0,0,0,0,0,EG62,0,0,0,0,0,0,0,0,0,0,0,0,0,0,0,0,0,0,0,0,0,0,0,0,0,0,0,0,0)';
      BIDIRECTIONAL='TRUE';
      INPUT_LOAD='(-0.01,0.01)';
      OUTPUT_LOAD='(1.0,-1.0)';
    'DDR5_SA_DQ22':
      PIN_NUMBER='(0,0,0,0,0,0,0,0,0,0,0,0,EH63,0,0,0,0,0,0,0,0,0,0,0,0,0,0,0,0,0,0,0,0,0,0,0,0,0,0,0,0,0)';
      BIDIRECTIONAL='TRUE';
      INPUT_LOAD='(-0.01,0.01)';
      OUTPUT_LOAD='(1.0,-1.0)';
    'DDR5_SA_DQ21':
      PIN_NUMBER='(0,0,0,0,0,0,0,0,0,0,0,0,EE62,0,0,0,0,0,0,0,0,0,0,0,0,0,0,0,0,0,0,0,0,0,0,0,0,0,0,0,0,0)';
      BIDIRECTIONAL='TRUE';
      INPUT_LOAD='(-0.01,0.01)';
      OUTPUT_LOAD='(1.0,-1.0)';
    'DDR5_SA_DQ20':
      PIN_NUMBER='(0,0,0,0,0,0,0,0,0,0,0,0,ED63,0,0,0,0,0,0,0,0,0,0,0,0,0,0,0,0,0,0,0,0,0,0,0,0,0,0,0,0,0)';
      BIDIRECTIONAL='TRUE';
      INPUT_LOAD='(-0.01,0.01)';
      OUTPUT_LOAD='(1.0,-1.0)';
    'DDR5_SA_DQ19':
      PIN_NUMBER='(0,0,0,0,0,0,0,0,0,0,0,0,EH65,0,0,0,0,0,0,0,0,0,0,0,0,0,0,0,0,0,0,0,0,0,0,0,0,0,0,0,0,0)';
      BIDIRECTIONAL='TRUE';
      INPUT_LOAD='(-0.01,0.01)';
      OUTPUT_LOAD='(1.0,-1.0)';
    'DDR5_SA_DQ18':
      PIN_NUMBER='(0,0,0,0,0,0,0,0,0,0,0,0,EG66,0,0,0,0,0,0,0,0,0,0,0,0,0,0,0,0,0,0,0,0,0,0,0,0,0,0,0,0,0)';
      BIDIRECTIONAL='TRUE';
      INPUT_LOAD='(-0.01,0.01)';
      OUTPUT_LOAD='(1.0,-1.0)';
    'DDR5_SA_DQ17':
      PIN_NUMBER='(0,0,0,0,0,0,0,0,0,0,0,0,ED65,0,0,0,0,0,0,0,0,0,0,0,0,0,0,0,0,0,0,0,0,0,0,0,0,0,0,0,0,0)';
      BIDIRECTIONAL='TRUE';
      INPUT_LOAD='(-0.01,0.01)';
      OUTPUT_LOAD='(1.0,-1.0)';
    'DDR5_SA_DQ16':
      PIN_NUMBER='(0,0,0,0,0,0,0,0,0,0,0,0,EE66,0,0,0,0,0,0,0,0,0,0,0,0,0,0,0,0,0,0,0,0,0,0,0,0,0,0,0,0,0)';
      BIDIRECTIONAL='TRUE';
      INPUT_LOAD='(-0.01,0.01)';
      OUTPUT_LOAD='(1.0,-1.0)';
    'DDR5_SA_DQ15':
      PIN_NUMBER='(0,0,0,0,0,0,0,0,0,0,0,0,DY65,0,0,0,0,0,0,0,0,0,0,0,0,0,0,0,0,0,0,0,0,0,0,0,0,0,0,0,0,0)';
      BIDIRECTIONAL='TRUE';
      INPUT_LOAD='(-0.01,0.01)';
      OUTPUT_LOAD='(1.0,-1.0)';
    'DDR5_SA_DQ14':
      PIN_NUMBER='(0,0,0,0,0,0,0,0,0,0,0,0,EA66,0,0,0,0,0,0,0,0,0,0,0,0,0,0,0,0,0,0,0,0,0,0,0,0,0,0,0,0,0)';
      BIDIRECTIONAL='TRUE';
      INPUT_LOAD='(-0.01,0.01)';
      OUTPUT_LOAD='(1.0,-1.0)';
    'DDR5_SA_DQ13':
      PIN_NUMBER='(0,0,0,0,0,0,0,0,0,0,0,0,DV65,0,0,0,0,0,0,0,0,0,0,0,0,0,0,0,0,0,0,0,0,0,0,0,0,0,0,0,0,0)';
      BIDIRECTIONAL='TRUE';
      INPUT_LOAD='(-0.01,0.01)';
      OUTPUT_LOAD='(1.0,-1.0)';
    'DDR5_SA_DQ12':
      PIN_NUMBER='(0,0,0,0,0,0,0,0,0,0,0,0,DU66,0,0,0,0,0,0,0,0,0,0,0,0,0,0,0,0,0,0,0,0,0,0,0,0,0,0,0,0,0)';
      BIDIRECTIONAL='TRUE';
      INPUT_LOAD='(-0.01,0.01)';
      OUTPUT_LOAD='(1.0,-1.0)';
    'DDR5_SA_DQ11':
      PIN_NUMBER='(0,0,0,0,0,0,0,0,0,0,0,0,EA68,0,0,0,0,0,0,0,0,0,0,0,0,0,0,0,0,0,0,0,0,0,0,0,0,0,0,0,0,0)';
      BIDIRECTIONAL='TRUE';
      INPUT_LOAD='(-0.01,0.01)';
      OUTPUT_LOAD='(1.0,-1.0)';
    'DDR5_SA_DQ10':
      PIN_NUMBER='(0,0,0,0,0,0,0,0,0,0,0,0,DY69,0,0,0,0,0,0,0,0,0,0,0,0,0,0,0,0,0,0,0,0,0,0,0,0,0,0,0,0,0)';
      BIDIRECTIONAL='TRUE';
      INPUT_LOAD='(-0.01,0.01)';
      OUTPUT_LOAD='(1.0,-1.0)';
    'DDR5_SA_DQ9':
      PIN_NUMBER='(0,0,0,0,0,0,0,0,0,0,0,0,DU68,0,0,0,0,0,0,0,0,0,0,0,0,0,0,0,0,0,0,0,0,0,0,0,0,0,0,0,0,0)';
      BIDIRECTIONAL='TRUE';
      INPUT_LOAD='(-0.01,0.01)';
      OUTPUT_LOAD='(1.0,-1.0)';
    'DDR5_SA_DQ8':
      PIN_NUMBER='(0,0,0,0,0,0,0,0,0,0,0,0,DV69,0,0,0,0,0,0,0,0,0,0,0,0,0,0,0,0,0,0,0,0,0,0,0,0,0,0,0,0,0)';
      BIDIRECTIONAL='TRUE';
      INPUT_LOAD='(-0.01,0.01)';
      OUTPUT_LOAD='(1.0,-1.0)';
    'DDR5_SA_DQ7':
      PIN_NUMBER='(0,0,0,0,0,0,0,0,0,0,0,0,EG74,0,0,0,0,0,0,0,0,0,0,0,0,0,0,0,0,0,0,0,0,0,0,0,0,0,0,0,0,0)';
      BIDIRECTIONAL='TRUE';
      INPUT_LOAD='(-0.01,0.01)';
      OUTPUT_LOAD='(1.0,-1.0)';
    'DDR5_SA_DQ6':
      PIN_NUMBER='(0,0,0,0,0,0,0,0,0,0,0,0,EH75,0,0,0,0,0,0,0,0,0,0,0,0,0,0,0,0,0,0,0,0,0,0,0,0,0,0,0,0,0)';
      BIDIRECTIONAL='TRUE';
      INPUT_LOAD='(-0.01,0.01)';
      OUTPUT_LOAD='(1.0,-1.0)';
    'DDR5_SA_DQ5':
      PIN_NUMBER='(0,0,0,0,0,0,0,0,0,0,0,0,EE74,0,0,0,0,0,0,0,0,0,0,0,0,0,0,0,0,0,0,0,0,0,0,0,0,0,0,0,0,0)';
      BIDIRECTIONAL='TRUE';
      INPUT_LOAD='(-0.01,0.01)';
      OUTPUT_LOAD='(1.0,-1.0)';
    'DDR5_SA_DQ4':
      PIN_NUMBER='(0,0,0,0,0,0,0,0,0,0,0,0,ED75,0,0,0,0,0,0,0,0,0,0,0,0,0,0,0,0,0,0,0,0,0,0,0,0,0,0,0,0,0)';
      BIDIRECTIONAL='TRUE';
      INPUT_LOAD='(-0.01,0.01)';
      OUTPUT_LOAD='(1.0,-1.0)';
    'DDR5_SA_DQ3':
      PIN_NUMBER='(0,0,0,0,0,0,0,0,0,0,0,0,EG78,0,0,0,0,0,0,0,0,0,0,0,0,0,0,0,0,0,0,0,0,0,0,0,0,0,0,0,0,0)';
      BIDIRECTIONAL='TRUE';
      INPUT_LOAD='(-0.01,0.01)';
      OUTPUT_LOAD='(1.0,-1.0)';
    'DDR5_SA_DQ2':
      PIN_NUMBER='(0,0,0,0,0,0,0,0,0,0,0,0,ED77,0,0,0,0,0,0,0,0,0,0,0,0,0,0,0,0,0,0,0,0,0,0,0,0,0,0,0,0,0)';
      BIDIRECTIONAL='TRUE';
      INPUT_LOAD='(-0.01,0.01)';
      OUTPUT_LOAD='(1.0,-1.0)';
    'DDR5_SA_DQ1':
      PIN_NUMBER='(0,0,0,0,0,0,0,0,0,0,0,0,EH77,0,0,0,0,0,0,0,0,0,0,0,0,0,0,0,0,0,0,0,0,0,0,0,0,0,0,0,0,0)';
      BIDIRECTIONAL='TRUE';
      INPUT_LOAD='(-0.01,0.01)';
      OUTPUT_LOAD='(1.0,-1.0)';
    'DDR5_SA_DQ0':
      PIN_NUMBER='(0,0,0,0,0,0,0,0,0,0,0,0,EB77,0,0,0,0,0,0,0,0,0,0,0,0,0,0,0,0,0,0,0,0,0,0,0,0,0,0,0,0,0)';
      BIDIRECTIONAL='TRUE';
      INPUT_LOAD='(-0.01,0.01)';
      OUTPUT_LOAD='(1.0,-1.0)';
    'DDR5_SA_DQS_DN9':
      PIN_NUMBER='(0,0,0,0,0,0,0,0,0,0,0,0,EJ58,0,0,0,0,0,0,0,0,0,0,0,0,0,0,0,0,0,0,0,0,0,0,0,0,0,0,0,0,0)';
      BIDIRECTIONAL='TRUE';
      INPUT_LOAD='(-0.01,0.01)';
      OUTPUT_LOAD='(1.0,-1.0)';
    'DDR5_SA_DQS_DN8':
      PIN_NUMBER='(0,0,0,0,0,0,0,0,0,0,0,0,EB55,0,0,0,0,0,0,0,0,0,0,0,0,0,0,0,0,0,0,0,0,0,0,0,0,0,0,0,0,0)';
      BIDIRECTIONAL='TRUE';
      INPUT_LOAD='(-0.01,0.01)';
      OUTPUT_LOAD='(1.0,-1.0)';
    'DDR5_SA_DQS_DN7':
      PIN_NUMBER='(0,0,0,0,0,0,0,0,0,0,0,0,EJ64,0,0,0,0,0,0,0,0,0,0,0,0,0,0,0,0,0,0,0,0,0,0,0,0,0,0,0,0,0)';
      BIDIRECTIONAL='TRUE';
      INPUT_LOAD='(-0.01,0.01)';
      OUTPUT_LOAD='(1.0,-1.0)';
    'DDR5_SA_DQS_DN6':
      PIN_NUMBER='(0,0,0,0,0,0,0,0,0,0,0,0,EB67,0,0,0,0,0,0,0,0,0,0,0,0,0,0,0,0,0,0,0,0,0,0,0,0,0,0,0,0,0)';
      BIDIRECTIONAL='TRUE';
      INPUT_LOAD='(-0.01,0.01)';
      OUTPUT_LOAD='(1.0,-1.0)';
    'DDR5_SA_DQS_DN5':
      PIN_NUMBER='(0,0,0,0,0,0,0,0,0,0,0,0,EJ76,0,0,0,0,0,0,0,0,0,0,0,0,0,0,0,0,0,0,0,0,0,0,0,0,0,0,0,0,0)';
      BIDIRECTIONAL='TRUE';
      INPUT_LOAD='(-0.01,0.01)';
      OUTPUT_LOAD='(1.0,-1.0)';
    'DDR5_SA_DQS_DN4':
      PIN_NUMBER='(0,0,0,0,0,0,0,0,0,0,0,0,EE58,0,0,0,0,0,0,0,0,0,0,0,0,0,0,0,0,0,0,0,0,0,0,0,0,0,0,0,0,0)';
      BIDIRECTIONAL='TRUE';
      INPUT_LOAD='(-0.01,0.01)';
      OUTPUT_LOAD='(1.0,-1.0)';
    'DDR5_SA_DQS_DN3':
      PIN_NUMBER='(0,0,0,0,0,0,0,0,0,0,0,0,DV55,0,0,0,0,0,0,0,0,0,0,0,0,0,0,0,0,0,0,0,0,0,0,0,0,0,0,0,0,0)';
      BIDIRECTIONAL='TRUE';
      INPUT_LOAD='(-0.01,0.01)';
      OUTPUT_LOAD='(1.0,-1.0)';
    'DDR5_SA_DQS_DN2':
      PIN_NUMBER='(0,0,0,0,0,0,0,0,0,0,0,0,EC64,0,0,0,0,0,0,0,0,0,0,0,0,0,0,0,0,0,0,0,0,0,0,0,0,0,0,0,0,0)';
      BIDIRECTIONAL='TRUE';
      INPUT_LOAD='(-0.01,0.01)';
      OUTPUT_LOAD='(1.0,-1.0)';
    'DDR5_SA_DQS_DN1':
      PIN_NUMBER='(0,0,0,0,0,0,0,0,0,0,0,0,DT67,0,0,0,0,0,0,0,0,0,0,0,0,0,0,0,0,0,0,0,0,0,0,0,0,0,0,0,0,0)';
      BIDIRECTIONAL='TRUE';
      INPUT_LOAD='(-0.01,0.01)';
      OUTPUT_LOAD='(1.0,-1.0)';
    'DDR5_SA_DQS_DN0':
      PIN_NUMBER='(0,0,0,0,0,0,0,0,0,0,0,0,EE76,0,0,0,0,0,0,0,0,0,0,0,0,0,0,0,0,0,0,0,0,0,0,0,0,0,0,0,0,0)';
      BIDIRECTIONAL='TRUE';
      INPUT_LOAD='(-0.01,0.01)';
      OUTPUT_LOAD='(1.0,-1.0)';
    'DDR5_SA_DQS_DP9':
      PIN_NUMBER='(0,0,0,0,0,0,0,0,0,0,0,0,EG58,0,0,0,0,0,0,0,0,0,0,0,0,0,0,0,0,0,0,0,0,0,0,0,0,0,0,0,0,0)';
      BIDIRECTIONAL='TRUE';
      INPUT_LOAD='(-0.01,0.01)';
      OUTPUT_LOAD='(1.0,-1.0)';
    'DDR5_SA_DQS_DP8':
      PIN_NUMBER='(0,0,0,0,0,0,0,0,0,0,0,0,DY55,0,0,0,0,0,0,0,0,0,0,0,0,0,0,0,0,0,0,0,0,0,0,0,0,0,0,0,0,0)';
      BIDIRECTIONAL='TRUE';
      INPUT_LOAD='(-0.01,0.01)';
      OUTPUT_LOAD='(1.0,-1.0)';
    'DDR5_SA_DQS_DP7':
      PIN_NUMBER='(0,0,0,0,0,0,0,0,0,0,0,0,EG64,0,0,0,0,0,0,0,0,0,0,0,0,0,0,0,0,0,0,0,0,0,0,0,0,0,0,0,0,0)';
      BIDIRECTIONAL='TRUE';
      INPUT_LOAD='(-0.01,0.01)';
      OUTPUT_LOAD='(1.0,-1.0)';
    'DDR5_SA_DQS_DP6':
      PIN_NUMBER='(0,0,0,0,0,0,0,0,0,0,0,0,DY67,0,0,0,0,0,0,0,0,0,0,0,0,0,0,0,0,0,0,0,0,0,0,0,0,0,0,0,0,0)';
      BIDIRECTIONAL='TRUE';
      INPUT_LOAD='(-0.01,0.01)';
      OUTPUT_LOAD='(1.0,-1.0)';
    'DDR5_SA_DQS_DP5':
      PIN_NUMBER='(0,0,0,0,0,0,0,0,0,0,0,0,EG76,0,0,0,0,0,0,0,0,0,0,0,0,0,0,0,0,0,0,0,0,0,0,0,0,0,0,0,0,0)';
      BIDIRECTIONAL='TRUE';
      INPUT_LOAD='(-0.01,0.01)';
      OUTPUT_LOAD='(1.0,-1.0)';
    'DDR5_SA_DQS_DP4':
      PIN_NUMBER='(0,0,0,0,0,0,0,0,0,0,0,0,EC58,0,0,0,0,0,0,0,0,0,0,0,0,0,0,0,0,0,0,0,0,0,0,0,0,0,0,0,0,0)';
      BIDIRECTIONAL='TRUE';
      INPUT_LOAD='(-0.01,0.01)';
      OUTPUT_LOAD='(1.0,-1.0)';
    'DDR5_SA_DQS_DP3':
      PIN_NUMBER='(0,0,0,0,0,0,0,0,0,0,0,0,DT55,0,0,0,0,0,0,0,0,0,0,0,0,0,0,0,0,0,0,0,0,0,0,0,0,0,0,0,0,0)';
      BIDIRECTIONAL='TRUE';
      INPUT_LOAD='(-0.01,0.01)';
      OUTPUT_LOAD='(1.0,-1.0)';
    'DDR5_SA_DQS_DP2':
      PIN_NUMBER='(0,0,0,0,0,0,0,0,0,0,0,0,EE64,0,0,0,0,0,0,0,0,0,0,0,0,0,0,0,0,0,0,0,0,0,0,0,0,0,0,0,0,0)';
      BIDIRECTIONAL='TRUE';
      INPUT_LOAD='(-0.01,0.01)';
      OUTPUT_LOAD='(1.0,-1.0)';
    'DDR5_SA_DQS_DP1':
      PIN_NUMBER='(0,0,0,0,0,0,0,0,0,0,0,0,DV67,0,0,0,0,0,0,0,0,0,0,0,0,0,0,0,0,0,0,0,0,0,0,0,0,0,0,0,0,0)';
      BIDIRECTIONAL='TRUE';
      INPUT_LOAD='(-0.01,0.01)';
      OUTPUT_LOAD='(1.0,-1.0)';
    'DDR5_SA_DQS_DP0':
      PIN_NUMBER='(0,0,0,0,0,0,0,0,0,0,0,0,EC76,0,0,0,0,0,0,0,0,0,0,0,0,0,0,0,0,0,0,0,0,0,0,0,0,0,0,0,0,0)';
      BIDIRECTIONAL='TRUE';
      INPUT_LOAD='(-0.01,0.01)';
      OUTPUT_LOAD='(1.0,-1.0)';
    'DDR5_SA_ECC7':
      PIN_NUMBER='(0,0,0,0,0,0,0,0,0,0,0,0,EG56,0,0,0,0,0,0,0,0,0,0,0,0,0,0,0,0,0,0,0,0,0,0,0,0,0,0,0,0,0)';
      BIDIRECTIONAL='TRUE';
      INPUT_LOAD='(-0.01,0.01)';
      OUTPUT_LOAD='(1.0,-1.0)';
    'DDR5_SA_ECC6':
      PIN_NUMBER='(0,0,0,0,0,0,0,0,0,0,0,0,EH57,0,0,0,0,0,0,0,0,0,0,0,0,0,0,0,0,0,0,0,0,0,0,0,0,0,0,0,0,0)';
      BIDIRECTIONAL='TRUE';
      INPUT_LOAD='(-0.01,0.01)';
      OUTPUT_LOAD='(1.0,-1.0)';
    'DDR5_SA_ECC5':
      PIN_NUMBER='(0,0,0,0,0,0,0,0,0,0,0,0,EE56,0,0,0,0,0,0,0,0,0,0,0,0,0,0,0,0,0,0,0,0,0,0,0,0,0,0,0,0,0)';
      BIDIRECTIONAL='TRUE';
      INPUT_LOAD='(-0.01,0.01)';
      OUTPUT_LOAD='(1.0,-1.0)';
    'DDR5_SA_ECC4':
      PIN_NUMBER='(0,0,0,0,0,0,0,0,0,0,0,0,ED57,0,0,0,0,0,0,0,0,0,0,0,0,0,0,0,0,0,0,0,0,0,0,0,0,0,0,0,0,0)';
      BIDIRECTIONAL='TRUE';
      INPUT_LOAD='(-0.01,0.01)';
      OUTPUT_LOAD='(1.0,-1.0)';
    'DDR5_SA_ECC3':
      PIN_NUMBER='(0,0,0,0,0,0,0,0,0,0,0,0,EH59,0,0,0,0,0,0,0,0,0,0,0,0,0,0,0,0,0,0,0,0,0,0,0,0,0,0,0,0,0)';
      BIDIRECTIONAL='TRUE';
      INPUT_LOAD='(-0.01,0.01)';
      OUTPUT_LOAD='(1.0,-1.0)';
    'DDR5_SA_ECC2':
      PIN_NUMBER='(0,0,0,0,0,0,0,0,0,0,0,0,EG60,0,0,0,0,0,0,0,0,0,0,0,0,0,0,0,0,0,0,0,0,0,0,0,0,0,0,0,0,0)';
      BIDIRECTIONAL='TRUE';
      INPUT_LOAD='(-0.01,0.01)';
      OUTPUT_LOAD='(1.0,-1.0)';
    'DDR5_SA_ECC1':
      PIN_NUMBER='(0,0,0,0,0,0,0,0,0,0,0,0,ED59,0,0,0,0,0,0,0,0,0,0,0,0,0,0,0,0,0,0,0,0,0,0,0,0,0,0,0,0,0)';
      BIDIRECTIONAL='TRUE';
      INPUT_LOAD='(-0.01,0.01)';
      OUTPUT_LOAD='(1.0,-1.0)';
    'DDR5_SA_ECC0':
      PIN_NUMBER='(0,0,0,0,0,0,0,0,0,0,0,0,EE60,0,0,0,0,0,0,0,0,0,0,0,0,0,0,0,0,0,0,0,0,0,0,0,0,0,0,0,0,0)';
      BIDIRECTIONAL='TRUE';
      INPUT_LOAD='(-0.01,0.01)';
      OUTPUT_LOAD='(1.0,-1.0)';
    'DDR5_SA_PAR':
      PIN_NUMBER='(0,0,0,0,0,0,0,0,0,0,0,0,EA50,0,0,0,0,0,0,0,0,0,0,0,0,0,0,0,0,0,0,0,0,0,0,0,0,0,0,0,0,0)';
      OUTPUT_LOAD='(1.0,-1.0)';
    'DDR5_SB_CA6':
      PIN_NUMBER='(0,0,0,0,0,0,0,0,0,0,0,0,EC39,0,0,0,0,0,0,0,0,0,0,0,0,0,0,0,0,0,0,0,0,0,0,0,0,0,0,0,0,0)';
      OUTPUT_LOAD='(1.0,-1.0)';
    'DDR5_SB_CA5':
      PIN_NUMBER='(0,0,0,0,0,0,0,0,0,0,0,0,EH40,0,0,0,0,0,0,0,0,0,0,0,0,0,0,0,0,0,0,0,0,0,0,0,0,0,0,0,0,0)';
      OUTPUT_LOAD='(1.0,-1.0)';
    'DDR5_SB_CA4':
      PIN_NUMBER='(0,0,0,0,0,0,0,0,0,0,0,0,ED40,0,0,0,0,0,0,0,0,0,0,0,0,0,0,0,0,0,0,0,0,0,0,0,0,0,0,0,0,0)';
      OUTPUT_LOAD='(1.0,-1.0)';
    'DDR5_SB_CA3':
      PIN_NUMBER='(0,0,0,0,0,0,0,0,0,0,0,0,EG41,0,0,0,0,0,0,0,0,0,0,0,0,0,0,0,0,0,0,0,0,0,0,0,0,0,0,0,0,0)';
      OUTPUT_LOAD='(1.0,-1.0)';
    'DDR5_SB_CA2':
      PIN_NUMBER='(0,0,0,0,0,0,0,0,0,0,0,0,EE41,0,0,0,0,0,0,0,0,0,0,0,0,0,0,0,0,0,0,0,0,0,0,0,0,0,0,0,0,0)';
      OUTPUT_LOAD='(1.0,-1.0)';
    'DDR5_SB_CA1':
      PIN_NUMBER='(0,0,0,0,0,0,0,0,0,0,0,0,DU50,0,0,0,0,0,0,0,0,0,0,0,0,0,0,0,0,0,0,0,0,0,0,0,0,0,0,0,0,0)';
      OUTPUT_LOAD='(1.0,-1.0)';
    'DDR5_SB_CA0':
      PIN_NUMBER='(0,0,0,0,0,0,0,0,0,0,0,0,DV51,0,0,0,0,0,0,0,0,0,0,0,0,0,0,0,0,0,0,0,0,0,0,0,0,0,0,0,0,0)';
      OUTPUT_LOAD='(1.0,-1.0)';
    'DDR5_SB_CS_N3':
      PIN_NUMBER='(0,0,0,0,0,0,0,0,0,0,0,0,EE37,0,0,0,0,0,0,0,0,0,0,0,0,0,0,0,0,0,0,0,0,0,0,0,0,0,0,0,0,0)';
      OUTPUT_LOAD='(1.0,-1.0)';
    'DDR5_SB_CS_N2':
      PIN_NUMBER='(0,0,0,0,0,0,0,0,0,0,0,0,ED38,0,0,0,0,0,0,0,0,0,0,0,0,0,0,0,0,0,0,0,0,0,0,0,0,0,0,0,0,0)';
      OUTPUT_LOAD='(1.0,-1.0)';
    'DDR5_SB_CS_N1':
      PIN_NUMBER='(0,0,0,0,0,0,0,0,0,0,0,0,EG37,0,0,0,0,0,0,0,0,0,0,0,0,0,0,0,0,0,0,0,0,0,0,0,0,0,0,0,0,0)';
      OUTPUT_LOAD='(1.0,-1.0)';
    'DDR5_SB_CS_N0':
      PIN_NUMBER='(0,0,0,0,0,0,0,0,0,0,0,0,EH38,0,0,0,0,0,0,0,0,0,0,0,0,0,0,0,0,0,0,0,0,0,0,0,0,0,0,0,0,0)';
      OUTPUT_LOAD='(1.0,-1.0)';
    'DDR5_SB_DQ31':
      PIN_NUMBER='(0,0,0,0,0,0,0,0,0,0,0,0,DR17,0,0,0,0,0,0,0,0,0,0,0,0,0,0,0,0,0,0,0,0,0,0,0,0,0,0,0,0,0)';
      BIDIRECTIONAL='TRUE';
      INPUT_LOAD='(-0.01,0.01)';
      OUTPUT_LOAD='(1.0,-1.0)';
    'DDR5_SB_DQ30':
      PIN_NUMBER='(0,0,0,0,0,0,0,0,0,0,0,0,EC17,0,0,0,0,0,0,0,0,0,0,0,0,0,0,0,0,0,0,0,0,0,0,0,0,0,0,0,0,0)';
      BIDIRECTIONAL='TRUE';
      INPUT_LOAD='(-0.01,0.01)';
      OUTPUT_LOAD='(1.0,-1.0)';
    'DDR5_SB_DQ29':
      PIN_NUMBER='(0,0,0,0,0,0,0,0,0,0,0,0,DU17,0,0,0,0,0,0,0,0,0,0,0,0,0,0,0,0,0,0,0,0,0,0,0,0,0,0,0,0,0)';
      BIDIRECTIONAL='TRUE';
      INPUT_LOAD='(-0.01,0.01)';
      OUTPUT_LOAD='(1.0,-1.0)';
    'DDR5_SB_DQ28':
      PIN_NUMBER='(0,0,0,0,0,0,0,0,0,0,0,0,EA17,0,0,0,0,0,0,0,0,0,0,0,0,0,0,0,0,0,0,0,0,0,0,0,0,0,0,0,0,0)';
      BIDIRECTIONAL='TRUE';
      INPUT_LOAD='(-0.01,0.01)';
      OUTPUT_LOAD='(1.0,-1.0)';
    'DDR5_SB_DQ27':
      PIN_NUMBER='(0,0,0,0,0,0,0,0,0,0,0,0,EA19,0,0,0,0,0,0,0,0,0,0,0,0,0,0,0,0,0,0,0,0,0,0,0,0,0,0,0,0,0)';
      BIDIRECTIONAL='TRUE';
      INPUT_LOAD='(-0.01,0.01)';
      OUTPUT_LOAD='(1.0,-1.0)';
    'DDR5_SB_DQ26':
      PIN_NUMBER='(0,0,0,0,0,0,0,0,0,0,0,0,DY20,0,0,0,0,0,0,0,0,0,0,0,0,0,0,0,0,0,0,0,0,0,0,0,0,0,0,0,0,0)';
      BIDIRECTIONAL='TRUE';
      INPUT_LOAD='(-0.01,0.01)';
      OUTPUT_LOAD='(1.0,-1.0)';
    'DDR5_SB_DQ25':
      PIN_NUMBER='(0,0,0,0,0,0,0,0,0,0,0,0,DU19,0,0,0,0,0,0,0,0,0,0,0,0,0,0,0,0,0,0,0,0,0,0,0,0,0,0,0,0,0)';
      BIDIRECTIONAL='TRUE';
      INPUT_LOAD='(-0.01,0.01)';
      OUTPUT_LOAD='(1.0,-1.0)';
    'DDR5_SB_DQ24':
      PIN_NUMBER='(0,0,0,0,0,0,0,0,0,0,0,0,DV20,0,0,0,0,0,0,0,0,0,0,0,0,0,0,0,0,0,0,0,0,0,0,0,0,0,0,0,0,0)';
      BIDIRECTIONAL='TRUE';
      INPUT_LOAD='(-0.01,0.01)';
      OUTPUT_LOAD='(1.0,-1.0)';
    'DDR5_SB_DQ23':
      PIN_NUMBER='(0,0,0,0,0,0,0,0,0,0,0,0,EP10,0,0,0,0,0,0,0,0,0,0,0,0,0,0,0,0,0,0,0,0,0,0,0,0,0,0,0,0,0)';
      BIDIRECTIONAL='TRUE';
      INPUT_LOAD='(-0.01,0.01)';
      OUTPUT_LOAD='(1.0,-1.0)';
    'DDR5_SB_DQ22':
      PIN_NUMBER='(0,0,0,0,0,0,0,0,0,0,0,0,ER11,0,0,0,0,0,0,0,0,0,0,0,0,0,0,0,0,0,0,0,0,0,0,0,0,0,0,0,0,0)';
      BIDIRECTIONAL='TRUE';
      INPUT_LOAD='(-0.01,0.01)';
      OUTPUT_LOAD='(1.0,-1.0)';
    'DDR5_SB_DQ21':
      PIN_NUMBER='(0,0,0,0,0,0,0,0,0,0,0,0,EM10,0,0,0,0,0,0,0,0,0,0,0,0,0,0,0,0,0,0,0,0,0,0,0,0,0,0,0,0,0)';
      BIDIRECTIONAL='TRUE';
      INPUT_LOAD='(-0.01,0.01)';
      OUTPUT_LOAD='(1.0,-1.0)';
    'DDR5_SB_DQ20':
      PIN_NUMBER='(0,0,0,0,0,0,0,0,0,0,0,0,EL11,0,0,0,0,0,0,0,0,0,0,0,0,0,0,0,0,0,0,0,0,0,0,0,0,0,0,0,0,0)';
      BIDIRECTIONAL='TRUE';
      INPUT_LOAD='(-0.01,0.01)';
      OUTPUT_LOAD='(1.0,-1.0)';
    'DDR5_SB_DQ19':
      PIN_NUMBER='(0,0,0,0,0,0,0,0,0,0,0,0,ER13,0,0,0,0,0,0,0,0,0,0,0,0,0,0,0,0,0,0,0,0,0,0,0,0,0,0,0,0,0)';
      BIDIRECTIONAL='TRUE';
      INPUT_LOAD='(-0.01,0.01)';
      OUTPUT_LOAD='(1.0,-1.0)';
    'DDR5_SB_DQ18':
      PIN_NUMBER='(0,0,0,0,0,0,0,0,0,0,0,0,EP14,0,0,0,0,0,0,0,0,0,0,0,0,0,0,0,0,0,0,0,0,0,0,0,0,0,0,0,0,0)';
      BIDIRECTIONAL='TRUE';
      INPUT_LOAD='(-0.01,0.01)';
      OUTPUT_LOAD='(1.0,-1.0)';
    'DDR5_SB_DQ17':
      PIN_NUMBER='(0,0,0,0,0,0,0,0,0,0,0,0,EL13,0,0,0,0,0,0,0,0,0,0,0,0,0,0,0,0,0,0,0,0,0,0,0,0,0,0,0,0,0)';
      BIDIRECTIONAL='TRUE';
      INPUT_LOAD='(-0.01,0.01)';
      OUTPUT_LOAD='(1.0,-1.0)';
    'DDR5_SB_DQ16':
      PIN_NUMBER='(0,0,0,0,0,0,0,0,0,0,0,0,EM14,0,0,0,0,0,0,0,0,0,0,0,0,0,0,0,0,0,0,0,0,0,0,0,0,0,0,0,0,0)';
      BIDIRECTIONAL='TRUE';
      INPUT_LOAD='(-0.01,0.01)';
      OUTPUT_LOAD='(1.0,-1.0)';
    'DDR5_SB_DQ15':
      PIN_NUMBER='(0,0,0,0,0,0,0,0,0,0,0,0,EG19,0,0,0,0,0,0,0,0,0,0,0,0,0,0,0,0,0,0,0,0,0,0,0,0,0,0,0,0,0)';
      BIDIRECTIONAL='TRUE';
      INPUT_LOAD='(-0.01,0.01)';
      OUTPUT_LOAD='(1.0,-1.0)';
    'DDR5_SB_DQ14':
      PIN_NUMBER='(0,0,0,0,0,0,0,0,0,0,0,0,EH20,0,0,0,0,0,0,0,0,0,0,0,0,0,0,0,0,0,0,0,0,0,0,0,0,0,0,0,0,0)';
      BIDIRECTIONAL='TRUE';
      INPUT_LOAD='(-0.01,0.01)';
      OUTPUT_LOAD='(1.0,-1.0)';
    'DDR5_SB_DQ13':
      PIN_NUMBER='(0,0,0,0,0,0,0,0,0,0,0,0,EE19,0,0,0,0,0,0,0,0,0,0,0,0,0,0,0,0,0,0,0,0,0,0,0,0,0,0,0,0,0)';
      BIDIRECTIONAL='TRUE';
      INPUT_LOAD='(-0.01,0.01)';
      OUTPUT_LOAD='(1.0,-1.0)';
    'DDR5_SB_DQ12':
      PIN_NUMBER='(0,0,0,0,0,0,0,0,0,0,0,0,ED20,0,0,0,0,0,0,0,0,0,0,0,0,0,0,0,0,0,0,0,0,0,0,0,0,0,0,0,0,0)';
      BIDIRECTIONAL='TRUE';
      INPUT_LOAD='(-0.01,0.01)';
      OUTPUT_LOAD='(1.0,-1.0)';
    'DDR5_SB_DQ11':
      PIN_NUMBER='(0,0,0,0,0,0,0,0,0,0,0,0,EH22,0,0,0,0,0,0,0,0,0,0,0,0,0,0,0,0,0,0,0,0,0,0,0,0,0,0,0,0,0)';
      BIDIRECTIONAL='TRUE';
      INPUT_LOAD='(-0.01,0.01)';
      OUTPUT_LOAD='(1.0,-1.0)';
    'DDR5_SB_DQ10':
      PIN_NUMBER='(0,0,0,0,0,0,0,0,0,0,0,0,EG23,0,0,0,0,0,0,0,0,0,0,0,0,0,0,0,0,0,0,0,0,0,0,0,0,0,0,0,0,0)';
      BIDIRECTIONAL='TRUE';
      INPUT_LOAD='(-0.01,0.01)';
      OUTPUT_LOAD='(1.0,-1.0)';
    'DDR5_SB_DQ9':
      PIN_NUMBER='(0,0,0,0,0,0,0,0,0,0,0,0,ED22,0,0,0,0,0,0,0,0,0,0,0,0,0,0,0,0,0,0,0,0,0,0,0,0,0,0,0,0,0)';
      BIDIRECTIONAL='TRUE';
      INPUT_LOAD='(-0.01,0.01)';
      OUTPUT_LOAD='(1.0,-1.0)';
    'DDR5_SB_DQ8':
      PIN_NUMBER='(0,0,0,0,0,0,0,0,0,0,0,0,EE23,0,0,0,0,0,0,0,0,0,0,0,0,0,0,0,0,0,0,0,0,0,0,0,0,0,0,0,0,0)';
      BIDIRECTIONAL='TRUE';
      INPUT_LOAD='(-0.01,0.01)';
      OUTPUT_LOAD='(1.0,-1.0)';
    'DDR5_SB_DQ7':
      PIN_NUMBER='(0,0,0,0,0,0,0,0,0,0,0,0,DY28,0,0,0,0,0,0,0,0,0,0,0,0,0,0,0,0,0,0,0,0,0,0,0,0,0,0,0,0,0)';
      BIDIRECTIONAL='TRUE';
      INPUT_LOAD='(-0.01,0.01)';
      OUTPUT_LOAD='(1.0,-1.0)';
    'DDR5_SB_DQ6':
      PIN_NUMBER='(0,0,0,0,0,0,0,0,0,0,0,0,EA29,0,0,0,0,0,0,0,0,0,0,0,0,0,0,0,0,0,0,0,0,0,0,0,0,0,0,0,0,0)';
      BIDIRECTIONAL='TRUE';
      INPUT_LOAD='(-0.01,0.01)';
      OUTPUT_LOAD='(1.0,-1.0)';
    'DDR5_SB_DQ5':
      PIN_NUMBER='(0,0,0,0,0,0,0,0,0,0,0,0,DV28,0,0,0,0,0,0,0,0,0,0,0,0,0,0,0,0,0,0,0,0,0,0,0,0,0,0,0,0,0)';
      BIDIRECTIONAL='TRUE';
      INPUT_LOAD='(-0.01,0.01)';
      OUTPUT_LOAD='(1.0,-1.0)';
    'DDR5_SB_DQ4':
      PIN_NUMBER='(0,0,0,0,0,0,0,0,0,0,0,0,DU29,0,0,0,0,0,0,0,0,0,0,0,0,0,0,0,0,0,0,0,0,0,0,0,0,0,0,0,0,0)';
      BIDIRECTIONAL='TRUE';
      INPUT_LOAD='(-0.01,0.01)';
      OUTPUT_LOAD='(1.0,-1.0)';
    'DDR5_SB_DQ3':
      PIN_NUMBER='(0,0,0,0,0,0,0,0,0,0,0,0,EA31,0,0,0,0,0,0,0,0,0,0,0,0,0,0,0,0,0,0,0,0,0,0,0,0,0,0,0,0,0)';
      BIDIRECTIONAL='TRUE';
      INPUT_LOAD='(-0.01,0.01)';
      OUTPUT_LOAD='(1.0,-1.0)';
    'DDR5_SB_DQ2':
      PIN_NUMBER='(0,0,0,0,0,0,0,0,0,0,0,0,DY32,0,0,0,0,0,0,0,0,0,0,0,0,0,0,0,0,0,0,0,0,0,0,0,0,0,0,0,0,0)';
      BIDIRECTIONAL='TRUE';
      INPUT_LOAD='(-0.01,0.01)';
      OUTPUT_LOAD='(1.0,-1.0)';
    'DDR5_SB_DQ1':
      PIN_NUMBER='(0,0,0,0,0,0,0,0,0,0,0,0,DU31,0,0,0,0,0,0,0,0,0,0,0,0,0,0,0,0,0,0,0,0,0,0,0,0,0,0,0,0,0)';
      BIDIRECTIONAL='TRUE';
      INPUT_LOAD='(-0.01,0.01)';
      OUTPUT_LOAD='(1.0,-1.0)';
    'DDR5_SB_DQ0':
      PIN_NUMBER='(0,0,0,0,0,0,0,0,0,0,0,0,DV32,0,0,0,0,0,0,0,0,0,0,0,0,0,0,0,0,0,0,0,0,0,0,0,0,0,0,0,0,0)';
      BIDIRECTIONAL='TRUE';
      INPUT_LOAD='(-0.01,0.01)';
      OUTPUT_LOAD='(1.0,-1.0)';
    'DDR5_SB_DQS_DN9':
      PIN_NUMBER='(0,0,0,0,0,0,0,0,0,0,0,0,EE33,0,0,0,0,0,0,0,0,0,0,0,0,0,0,0,0,0,0,0,0,0,0,0,0,0,0,0,0,0)';
      BIDIRECTIONAL='TRUE';
      INPUT_LOAD='(-0.01,0.01)';
      OUTPUT_LOAD='(1.0,-1.0)';
    'DDR5_SB_DQS_DN8':
      PIN_NUMBER='(0,0,0,0,0,0,0,0,0,0,0,0,DY18,0,0,0,0,0,0,0,0,0,0,0,0,0,0,0,0,0,0,0,0,0,0,0,0,0,0,0,0,0)';
      BIDIRECTIONAL='TRUE';
      INPUT_LOAD='(-0.01,0.01)';
      OUTPUT_LOAD='(1.0,-1.0)';
    'DDR5_SB_DQS_DN7':
      PIN_NUMBER='(0,0,0,0,0,0,0,0,0,0,0,0,ET12,0,0,0,0,0,0,0,0,0,0,0,0,0,0,0,0,0,0,0,0,0,0,0,0,0,0,0,0,0)';
      BIDIRECTIONAL='TRUE';
      INPUT_LOAD='(-0.01,0.01)';
      OUTPUT_LOAD='(1.0,-1.0)';
    'DDR5_SB_DQS_DN6':
      PIN_NUMBER='(0,0,0,0,0,0,0,0,0,0,0,0,EJ21,0,0,0,0,0,0,0,0,0,0,0,0,0,0,0,0,0,0,0,0,0,0,0,0,0,0,0,0,0)';
      BIDIRECTIONAL='TRUE';
      INPUT_LOAD='(-0.01,0.01)';
      OUTPUT_LOAD='(1.0,-1.0)';
    'DDR5_SB_DQS_DN5':
      PIN_NUMBER='(0,0,0,0,0,0,0,0,0,0,0,0,EB30,0,0,0,0,0,0,0,0,0,0,0,0,0,0,0,0,0,0,0,0,0,0,0,0,0,0,0,0,0)';
      BIDIRECTIONAL='TRUE';
      INPUT_LOAD='(-0.01,0.01)';
      OUTPUT_LOAD='(1.0,-1.0)';
    'DDR5_SB_DQS_DN4':
      PIN_NUMBER='(0,0,0,0,0,0,0,0,0,0,0,0,EJ33,0,0,0,0,0,0,0,0,0,0,0,0,0,0,0,0,0,0,0,0,0,0,0,0,0,0,0,0,0)';
      BIDIRECTIONAL='TRUE';
      INPUT_LOAD='(-0.01,0.01)';
      OUTPUT_LOAD='(1.0,-1.0)';
    'DDR5_SB_DQS_DN3':
      PIN_NUMBER='(0,0,0,0,0,0,0,0,0,0,0,0,DT18,0,0,0,0,0,0,0,0,0,0,0,0,0,0,0,0,0,0,0,0,0,0,0,0,0,0,0,0,0)';
      BIDIRECTIONAL='TRUE';
      INPUT_LOAD='(-0.01,0.01)';
      OUTPUT_LOAD='(1.0,-1.0)';
    'DDR5_SB_DQS_DN2':
      PIN_NUMBER='(0,0,0,0,0,0,0,0,0,0,0,0,EM12,0,0,0,0,0,0,0,0,0,0,0,0,0,0,0,0,0,0,0,0,0,0,0,0,0,0,0,0,0)';
      BIDIRECTIONAL='TRUE';
      INPUT_LOAD='(-0.01,0.01)';
      OUTPUT_LOAD='(1.0,-1.0)';
    'DDR5_SB_DQS_DN1':
      PIN_NUMBER='(0,0,0,0,0,0,0,0,0,0,0,0,EE21,0,0,0,0,0,0,0,0,0,0,0,0,0,0,0,0,0,0,0,0,0,0,0,0,0,0,0,0,0)';
      BIDIRECTIONAL='TRUE';
      INPUT_LOAD='(-0.01,0.01)';
      OUTPUT_LOAD='(1.0,-1.0)';
    'DDR5_SB_DQS_DN0':
      PIN_NUMBER='(0,0,0,0,0,0,0,0,0,0,0,0,DV30,0,0,0,0,0,0,0,0,0,0,0,0,0,0,0,0,0,0,0,0,0,0,0,0,0,0,0,0,0)';
      BIDIRECTIONAL='TRUE';
      INPUT_LOAD='(-0.01,0.01)';
      OUTPUT_LOAD='(1.0,-1.0)';
    'DDR5_SB_DQS_DP9':
      PIN_NUMBER='(0,0,0,0,0,0,0,0,0,0,0,0,EC33,0,0,0,0,0,0,0,0,0,0,0,0,0,0,0,0,0,0,0,0,0,0,0,0,0,0,0,0,0)';
      BIDIRECTIONAL='TRUE';
      INPUT_LOAD='(-0.01,0.01)';
      OUTPUT_LOAD='(1.0,-1.0)';
    'DDR5_SB_DQS_DP8':
      PIN_NUMBER='(0,0,0,0,0,0,0,0,0,0,0,0,EB18,0,0,0,0,0,0,0,0,0,0,0,0,0,0,0,0,0,0,0,0,0,0,0,0,0,0,0,0,0)';
      BIDIRECTIONAL='TRUE';
      INPUT_LOAD='(-0.01,0.01)';
      OUTPUT_LOAD='(1.0,-1.0)';
    'DDR5_SB_DQS_DP7':
      PIN_NUMBER='(0,0,0,0,0,0,0,0,0,0,0,0,EP12,0,0,0,0,0,0,0,0,0,0,0,0,0,0,0,0,0,0,0,0,0,0,0,0,0,0,0,0,0)';
      BIDIRECTIONAL='TRUE';
      INPUT_LOAD='(-0.01,0.01)';
      OUTPUT_LOAD='(1.0,-1.0)';
    'DDR5_SB_DQS_DP6':
      PIN_NUMBER='(0,0,0,0,0,0,0,0,0,0,0,0,EG21,0,0,0,0,0,0,0,0,0,0,0,0,0,0,0,0,0,0,0,0,0,0,0,0,0,0,0,0,0)';
      BIDIRECTIONAL='TRUE';
      INPUT_LOAD='(-0.01,0.01)';
      OUTPUT_LOAD='(1.0,-1.0)';
    'DDR5_SB_DQS_DP5':
      PIN_NUMBER='(0,0,0,0,0,0,0,0,0,0,0,0,DY30,0,0,0,0,0,0,0,0,0,0,0,0,0,0,0,0,0,0,0,0,0,0,0,0,0,0,0,0,0)';
      BIDIRECTIONAL='TRUE';
      INPUT_LOAD='(-0.01,0.01)';
      OUTPUT_LOAD='(1.0,-1.0)';
    'DDR5_SB_DQS_DP4':
      PIN_NUMBER='(0,0,0,0,0,0,0,0,0,0,0,0,EG33,0,0,0,0,0,0,0,0,0,0,0,0,0,0,0,0,0,0,0,0,0,0,0,0,0,0,0,0,0)';
      BIDIRECTIONAL='TRUE';
      INPUT_LOAD='(-0.01,0.01)';
      OUTPUT_LOAD='(1.0,-1.0)';
    'DDR5_SB_DQS_DP3':
      PIN_NUMBER='(0,0,0,0,0,0,0,0,0,0,0,0,DV18,0,0,0,0,0,0,0,0,0,0,0,0,0,0,0,0,0,0,0,0,0,0,0,0,0,0,0,0,0)';
      BIDIRECTIONAL='TRUE';
      INPUT_LOAD='(-0.01,0.01)';
      OUTPUT_LOAD='(1.0,-1.0)';
    'DDR5_SB_DQS_DP2':
      PIN_NUMBER='(0,0,0,0,0,0,0,0,0,0,0,0,EK12,0,0,0,0,0,0,0,0,0,0,0,0,0,0,0,0,0,0,0,0,0,0,0,0,0,0,0,0,0)';
      BIDIRECTIONAL='TRUE';
      INPUT_LOAD='(-0.01,0.01)';
      OUTPUT_LOAD='(1.0,-1.0)';
    'DDR5_SB_DQS_DP1':
      PIN_NUMBER='(0,0,0,0,0,0,0,0,0,0,0,0,EC21,0,0,0,0,0,0,0,0,0,0,0,0,0,0,0,0,0,0,0,0,0,0,0,0,0,0,0,0,0)';
      BIDIRECTIONAL='TRUE';
      INPUT_LOAD='(-0.01,0.01)';
      OUTPUT_LOAD='(1.0,-1.0)';
    'DDR5_SB_DQS_DP0':
      PIN_NUMBER='(0,0,0,0,0,0,0,0,0,0,0,0,DT30,0,0,0,0,0,0,0,0,0,0,0,0,0,0,0,0,0,0,0,0,0,0,0,0,0,0,0,0,0)';
      BIDIRECTIONAL='TRUE';
      INPUT_LOAD='(-0.01,0.01)';
      OUTPUT_LOAD='(1.0,-1.0)';
    'DDR5_SB_ECC7':
      PIN_NUMBER='(0,0,0,0,0,0,0,0,0,0,0,0,EH34,0,0,0,0,0,0,0,0,0,0,0,0,0,0,0,0,0,0,0,0,0,0,0,0,0,0,0,0,0)';
      BIDIRECTIONAL='TRUE';
      INPUT_LOAD='(-0.01,0.01)';
      OUTPUT_LOAD='(1.0,-1.0)';
    'DDR5_SB_ECC6':
      PIN_NUMBER='(0,0,0,0,0,0,0,0,0,0,0,0,EG35,0,0,0,0,0,0,0,0,0,0,0,0,0,0,0,0,0,0,0,0,0,0,0,0,0,0,0,0,0)';
      BIDIRECTIONAL='TRUE';
      INPUT_LOAD='(-0.01,0.01)';
      OUTPUT_LOAD='(1.0,-1.0)';
    'DDR5_SB_ECC5':
      PIN_NUMBER='(0,0,0,0,0,0,0,0,0,0,0,0,ED34,0,0,0,0,0,0,0,0,0,0,0,0,0,0,0,0,0,0,0,0,0,0,0,0,0,0,0,0,0)';
      BIDIRECTIONAL='TRUE';
      INPUT_LOAD='(-0.01,0.01)';
      OUTPUT_LOAD='(1.0,-1.0)';
    'DDR5_SB_ECC4':
      PIN_NUMBER='(0,0,0,0,0,0,0,0,0,0,0,0,EE35,0,0,0,0,0,0,0,0,0,0,0,0,0,0,0,0,0,0,0,0,0,0,0,0,0,0,0,0,0)';
      BIDIRECTIONAL='TRUE';
      INPUT_LOAD='(-0.01,0.01)';
      OUTPUT_LOAD='(1.0,-1.0)';
    'DDR5_SB_ECC3':
      PIN_NUMBER='(0,0,0,0,0,0,0,0,0,0,0,0,EG31,0,0,0,0,0,0,0,0,0,0,0,0,0,0,0,0,0,0,0,0,0,0,0,0,0,0,0,0,0)';
      BIDIRECTIONAL='TRUE';
      INPUT_LOAD='(-0.01,0.01)';
      OUTPUT_LOAD='(1.0,-1.0)';
    'DDR5_SB_ECC2':
      PIN_NUMBER='(0,0,0,0,0,0,0,0,0,0,0,0,EH32,0,0,0,0,0,0,0,0,0,0,0,0,0,0,0,0,0,0,0,0,0,0,0,0,0,0,0,0,0)';
      BIDIRECTIONAL='TRUE';
      INPUT_LOAD='(-0.01,0.01)';
      OUTPUT_LOAD='(1.0,-1.0)';
    'DDR5_SB_ECC1':
      PIN_NUMBER='(0,0,0,0,0,0,0,0,0,0,0,0,EE31,0,0,0,0,0,0,0,0,0,0,0,0,0,0,0,0,0,0,0,0,0,0,0,0,0,0,0,0,0)';
      BIDIRECTIONAL='TRUE';
      INPUT_LOAD='(-0.01,0.01)';
      OUTPUT_LOAD='(1.0,-1.0)';
    'DDR5_SB_ECC0':
      PIN_NUMBER='(0,0,0,0,0,0,0,0,0,0,0,0,ED32,0,0,0,0,0,0,0,0,0,0,0,0,0,0,0,0,0,0,0,0,0,0,0,0,0,0,0,0,0)';
      BIDIRECTIONAL='TRUE';
      INPUT_LOAD='(-0.01,0.01)';
      OUTPUT_LOAD='(1.0,-1.0)';
    'DDR5_SB_PAR':
      PIN_NUMBER='(0,0,0,0,0,0,0,0,0,0,0,0,EJ39,0,0,0,0,0,0,0,0,0,0,0,0,0,0,0,0,0,0,0,0,0,0,0,0,0,0,0,0,0)';
      OUTPUT_LOAD='(1.0,-1.0)';
    '-DDR6_ALERT':
      PIN_NUMBER='(0,0,0,0,0,0,0,0,0,0,0,0,0,CW50,0,0,0,0,0,0,0,0,0,0,0,0,0,0,0,0,0,0,0,0,0,0,0,0,0,0,0,0)';
      INPUT_LOAD='(-0.01,0.01)';
    'DDR6_A_RSP1':
      PIN_NUMBER='(0,0,0,0,0,0,0,0,0,0,0,0,0,DY47,0,0,0,0,0,0,0,0,0,0,0,0,0,0,0,0,0,0,0,0,0,0,0,0,0,0,0,0)';
      INPUT_LOAD='(-0.01,0.01)';
    'DDR6_A_RSP0':
      PIN_NUMBER='(0,0,0,0,0,0,0,0,0,0,0,0,0,EA48,0,0,0,0,0,0,0,0,0,0,0,0,0,0,0,0,0,0,0,0,0,0,0,0,0,0,0,0)';
      INPUT_LOAD='(-0.01,0.01)';
    'DDR6_B_RSP1':
      PIN_NUMBER='(0,0,0,0,0,0,0,0,0,0,0,0,0,DV47,0,0,0,0,0,0,0,0,0,0,0,0,0,0,0,0,0,0,0,0,0,0,0,0,0,0,0,0)';
      INPUT_LOAD='(-0.01,0.01)';
    'DDR6_B_RSP0':
      PIN_NUMBER='(0,0,0,0,0,0,0,0,0,0,0,0,0,DU48,0,0,0,0,0,0,0,0,0,0,0,0,0,0,0,0,0,0,0,0,0,0,0,0,0,0,0,0)';
      INPUT_LOAD='(-0.01,0.01)';
    'DDR6_CLK_DN1':
      PIN_NUMBER='(0,0,0,0,0,0,0,0,0,0,0,0,0,DL45,0,0,0,0,0,0,0,0,0,0,0,0,0,0,0,0,0,0,0,0,0,0,0,0,0,0,0,0)';
      OUTPUT_LOAD='(1.0,-1.0)';
    'DDR6_CLK_DN0':
      PIN_NUMBER='(0,0,0,0,0,0,0,0,0,0,0,0,0,DR45,0,0,0,0,0,0,0,0,0,0,0,0,0,0,0,0,0,0,0,0,0,0,0,0,0,0,0,0)';
      OUTPUT_LOAD='(1.0,-1.0)';
    'DDR6_CLK_DP1':
      PIN_NUMBER='(0,0,0,0,0,0,0,0,0,0,0,0,0,DJ45,0,0,0,0,0,0,0,0,0,0,0,0,0,0,0,0,0,0,0,0,0,0,0,0,0,0,0,0)';
      OUTPUT_LOAD='(1.0,-1.0)';
    'DDR6_CLK_DP0':
      PIN_NUMBER='(0,0,0,0,0,0,0,0,0,0,0,0,0,DN45,0,0,0,0,0,0,0,0,0,0,0,0,0,0,0,0,0,0,0,0,0,0,0,0,0,0,0,0)';
      OUTPUT_LOAD='(1.0,-1.0)';
    'DDR6_SA_CA6':
      PIN_NUMBER='(0,0,0,0,0,0,0,0,0,0,0,0,0,DK44,0,0,0,0,0,0,0,0,0,0,0,0,0,0,0,0,0,0,0,0,0,0,0,0,0,0,0,0)';
      OUTPUT_LOAD='(1.0,-1.0)';
    'DDR6_SA_CA5':
      PIN_NUMBER='(0,0,0,0,0,0,0,0,0,0,0,0,0,DN50,0,0,0,0,0,0,0,0,0,0,0,0,0,0,0,0,0,0,0,0,0,0,0,0,0,0,0,0)';
      OUTPUT_LOAD='(1.0,-1.0)';
    'DDR6_SA_CA4':
      PIN_NUMBER='(0,0,0,0,0,0,0,0,0,0,0,0,0,DL50,0,0,0,0,0,0,0,0,0,0,0,0,0,0,0,0,0,0,0,0,0,0,0,0,0,0,0,0)';
      OUTPUT_LOAD='(1.0,-1.0)';
    'DDR6_SA_CA3':
      PIN_NUMBER='(0,0,0,0,0,0,0,0,0,0,0,0,0,DP51,0,0,0,0,0,0,0,0,0,0,0,0,0,0,0,0,0,0,0,0,0,0,0,0,0,0,0,0)';
      OUTPUT_LOAD='(1.0,-1.0)';
    'DDR6_SA_CA2':
      PIN_NUMBER='(0,0,0,0,0,0,0,0,0,0,0,0,0,DK51,0,0,0,0,0,0,0,0,0,0,0,0,0,0,0,0,0,0,0,0,0,0,0,0,0,0,0,0)';
      OUTPUT_LOAD='(1.0,-1.0)';
    'DDR6_SA_CA1':
      PIN_NUMBER='(0,0,0,0,0,0,0,0,0,0,0,0,0,DR52,0,0,0,0,0,0,0,0,0,0,0,0,0,0,0,0,0,0,0,0,0,0,0,0,0,0,0,0)';
      OUTPUT_LOAD='(1.0,-1.0)';
    'DDR6_SA_CA0':
      PIN_NUMBER='(0,0,0,0,0,0,0,0,0,0,0,0,0,DJ52,0,0,0,0,0,0,0,0,0,0,0,0,0,0,0,0,0,0,0,0,0,0,0,0,0,0,0,0)';
      OUTPUT_LOAD='(1.0,-1.0)';
    'DDR6_SA_CS_N3':
      PIN_NUMBER='(0,0,0,0,0,0,0,0,0,0,0,0,0,DK53,0,0,0,0,0,0,0,0,0,0,0,0,0,0,0,0,0,0,0,0,0,0,0,0,0,0,0,0)';
      OUTPUT_LOAD='(1.0,-1.0)';
    'DDR6_SA_CS_N2':
      PIN_NUMBER='(0,0,0,0,0,0,0,0,0,0,0,0,0,DL54,0,0,0,0,0,0,0,0,0,0,0,0,0,0,0,0,0,0,0,0,0,0,0,0,0,0,0,0)';
      OUTPUT_LOAD='(1.0,-1.0)';
    'DDR6_SA_CS_N1':
      PIN_NUMBER='(0,0,0,0,0,0,0,0,0,0,0,0,0,DP53,0,0,0,0,0,0,0,0,0,0,0,0,0,0,0,0,0,0,0,0,0,0,0,0,0,0,0,0)';
      OUTPUT_LOAD='(1.0,-1.0)';
    'DDR6_SA_CS_N0':
      PIN_NUMBER='(0,0,0,0,0,0,0,0,0,0,0,0,0,DN54,0,0,0,0,0,0,0,0,0,0,0,0,0,0,0,0,0,0,0,0,0,0,0,0,0,0,0,0)';
      OUTPUT_LOAD='(1.0,-1.0)';
    'DDR6_SA_DQ31':
      PIN_NUMBER='(0,0,0,0,0,0,0,0,0,0,0,0,0,DN62,0,0,0,0,0,0,0,0,0,0,0,0,0,0,0,0,0,0,0,0,0,0,0,0,0,0,0,0)';
      BIDIRECTIONAL='TRUE';
      INPUT_LOAD='(-0.01,0.01)';
      OUTPUT_LOAD='(1.0,-1.0)';
    'DDR6_SA_DQ30':
      PIN_NUMBER='(0,0,0,0,0,0,0,0,0,0,0,0,0,DP63,0,0,0,0,0,0,0,0,0,0,0,0,0,0,0,0,0,0,0,0,0,0,0,0,0,0,0,0)';
      BIDIRECTIONAL='TRUE';
      INPUT_LOAD='(-0.01,0.01)';
      OUTPUT_LOAD='(1.0,-1.0)';
    'DDR6_SA_DQ29':
      PIN_NUMBER='(0,0,0,0,0,0,0,0,0,0,0,0,0,DL62,0,0,0,0,0,0,0,0,0,0,0,0,0,0,0,0,0,0,0,0,0,0,0,0,0,0,0,0)';
      BIDIRECTIONAL='TRUE';
      INPUT_LOAD='(-0.01,0.01)';
      OUTPUT_LOAD='(1.0,-1.0)';
    'DDR6_SA_DQ28':
      PIN_NUMBER='(0,0,0,0,0,0,0,0,0,0,0,0,0,DK63,0,0,0,0,0,0,0,0,0,0,0,0,0,0,0,0,0,0,0,0,0,0,0,0,0,0,0,0)';
      BIDIRECTIONAL='TRUE';
      INPUT_LOAD='(-0.01,0.01)';
      OUTPUT_LOAD='(1.0,-1.0)';
    'DDR6_SA_DQ27':
      PIN_NUMBER='(0,0,0,0,0,0,0,0,0,0,0,0,0,DP65,0,0,0,0,0,0,0,0,0,0,0,0,0,0,0,0,0,0,0,0,0,0,0,0,0,0,0,0)';
      BIDIRECTIONAL='TRUE';
      INPUT_LOAD='(-0.01,0.01)';
      OUTPUT_LOAD='(1.0,-1.0)';
    'DDR6_SA_DQ26':
      PIN_NUMBER='(0,0,0,0,0,0,0,0,0,0,0,0,0,DN66,0,0,0,0,0,0,0,0,0,0,0,0,0,0,0,0,0,0,0,0,0,0,0,0,0,0,0,0)';
      BIDIRECTIONAL='TRUE';
      INPUT_LOAD='(-0.01,0.01)';
      OUTPUT_LOAD='(1.0,-1.0)';
    'DDR6_SA_DQ25':
      PIN_NUMBER='(0,0,0,0,0,0,0,0,0,0,0,0,0,DK65,0,0,0,0,0,0,0,0,0,0,0,0,0,0,0,0,0,0,0,0,0,0,0,0,0,0,0,0)';
      BIDIRECTIONAL='TRUE';
      INPUT_LOAD='(-0.01,0.01)';
      OUTPUT_LOAD='(1.0,-1.0)';
    'DDR6_SA_DQ24':
      PIN_NUMBER='(0,0,0,0,0,0,0,0,0,0,0,0,0,DL66,0,0,0,0,0,0,0,0,0,0,0,0,0,0,0,0,0,0,0,0,0,0,0,0,0,0,0,0)';
      BIDIRECTIONAL='TRUE';
      INPUT_LOAD='(-0.01,0.01)';
      OUTPUT_LOAD='(1.0,-1.0)';
    'DDR6_SA_DQ23':
      PIN_NUMBER='(0,0,0,0,0,0,0,0,0,0,0,0,0,DY59,0,0,0,0,0,0,0,0,0,0,0,0,0,0,0,0,0,0,0,0,0,0,0,0,0,0,0,0)';
      BIDIRECTIONAL='TRUE';
      INPUT_LOAD='(-0.01,0.01)';
      OUTPUT_LOAD='(1.0,-1.0)';
    'DDR6_SA_DQ22':
      PIN_NUMBER='(0,0,0,0,0,0,0,0,0,0,0,0,0,EA60,0,0,0,0,0,0,0,0,0,0,0,0,0,0,0,0,0,0,0,0,0,0,0,0,0,0,0,0)';
      BIDIRECTIONAL='TRUE';
      INPUT_LOAD='(-0.01,0.01)';
      OUTPUT_LOAD='(1.0,-1.0)';
    'DDR6_SA_DQ21':
      PIN_NUMBER='(0,0,0,0,0,0,0,0,0,0,0,0,0,DV59,0,0,0,0,0,0,0,0,0,0,0,0,0,0,0,0,0,0,0,0,0,0,0,0,0,0,0,0)';
      BIDIRECTIONAL='TRUE';
      INPUT_LOAD='(-0.01,0.01)';
      OUTPUT_LOAD='(1.0,-1.0)';
    'DDR6_SA_DQ20':
      PIN_NUMBER='(0,0,0,0,0,0,0,0,0,0,0,0,0,DU60,0,0,0,0,0,0,0,0,0,0,0,0,0,0,0,0,0,0,0,0,0,0,0,0,0,0,0,0)';
      BIDIRECTIONAL='TRUE';
      INPUT_LOAD='(-0.01,0.01)';
      OUTPUT_LOAD='(1.0,-1.0)';
    'DDR6_SA_DQ19':
      PIN_NUMBER='(0,0,0,0,0,0,0,0,0,0,0,0,0,EA62,0,0,0,0,0,0,0,0,0,0,0,0,0,0,0,0,0,0,0,0,0,0,0,0,0,0,0,0)';
      BIDIRECTIONAL='TRUE';
      INPUT_LOAD='(-0.01,0.01)';
      OUTPUT_LOAD='(1.0,-1.0)';
    'DDR6_SA_DQ18':
      PIN_NUMBER='(0,0,0,0,0,0,0,0,0,0,0,0,0,DY63,0,0,0,0,0,0,0,0,0,0,0,0,0,0,0,0,0,0,0,0,0,0,0,0,0,0,0,0)';
      BIDIRECTIONAL='TRUE';
      INPUT_LOAD='(-0.01,0.01)';
      OUTPUT_LOAD='(1.0,-1.0)';
    'DDR6_SA_DQ17':
      PIN_NUMBER='(0,0,0,0,0,0,0,0,0,0,0,0,0,DU62,0,0,0,0,0,0,0,0,0,0,0,0,0,0,0,0,0,0,0,0,0,0,0,0,0,0,0,0)';
      BIDIRECTIONAL='TRUE';
      INPUT_LOAD='(-0.01,0.01)';
      OUTPUT_LOAD='(1.0,-1.0)';
    'DDR6_SA_DQ16':
      PIN_NUMBER='(0,0,0,0,0,0,0,0,0,0,0,0,0,DV63,0,0,0,0,0,0,0,0,0,0,0,0,0,0,0,0,0,0,0,0,0,0,0,0,0,0,0,0)';
      BIDIRECTIONAL='TRUE';
      INPUT_LOAD='(-0.01,0.01)';
      OUTPUT_LOAD='(1.0,-1.0)';
    'DDR6_SA_DQ15':
      PIN_NUMBER='(0,0,0,0,0,0,0,0,0,0,0,0,0,DN68,0,0,0,0,0,0,0,0,0,0,0,0,0,0,0,0,0,0,0,0,0,0,0,0,0,0,0,0)';
      BIDIRECTIONAL='TRUE';
      INPUT_LOAD='(-0.01,0.01)';
      OUTPUT_LOAD='(1.0,-1.0)';
    'DDR6_SA_DQ14':
      PIN_NUMBER='(0,0,0,0,0,0,0,0,0,0,0,0,0,DP69,0,0,0,0,0,0,0,0,0,0,0,0,0,0,0,0,0,0,0,0,0,0,0,0,0,0,0,0)';
      BIDIRECTIONAL='TRUE';
      INPUT_LOAD='(-0.01,0.01)';
      OUTPUT_LOAD='(1.0,-1.0)';
    'DDR6_SA_DQ13':
      PIN_NUMBER='(0,0,0,0,0,0,0,0,0,0,0,0,0,DL68,0,0,0,0,0,0,0,0,0,0,0,0,0,0,0,0,0,0,0,0,0,0,0,0,0,0,0,0)';
      BIDIRECTIONAL='TRUE';
      INPUT_LOAD='(-0.01,0.01)';
      OUTPUT_LOAD='(1.0,-1.0)';
    'DDR6_SA_DQ12':
      PIN_NUMBER='(0,0,0,0,0,0,0,0,0,0,0,0,0,DK69,0,0,0,0,0,0,0,0,0,0,0,0,0,0,0,0,0,0,0,0,0,0,0,0,0,0,0,0)';
      BIDIRECTIONAL='TRUE';
      INPUT_LOAD='(-0.01,0.01)';
      OUTPUT_LOAD='(1.0,-1.0)';
    'DDR6_SA_DQ11':
      PIN_NUMBER='(0,0,0,0,0,0,0,0,0,0,0,0,0,DP71,0,0,0,0,0,0,0,0,0,0,0,0,0,0,0,0,0,0,0,0,0,0,0,0,0,0,0,0)';
      BIDIRECTIONAL='TRUE';
      INPUT_LOAD='(-0.01,0.01)';
      OUTPUT_LOAD='(1.0,-1.0)';
    'DDR6_SA_DQ10':
      PIN_NUMBER='(0,0,0,0,0,0,0,0,0,0,0,0,0,DN72,0,0,0,0,0,0,0,0,0,0,0,0,0,0,0,0,0,0,0,0,0,0,0,0,0,0,0,0)';
      BIDIRECTIONAL='TRUE';
      INPUT_LOAD='(-0.01,0.01)';
      OUTPUT_LOAD='(1.0,-1.0)';
    'DDR6_SA_DQ9':
      PIN_NUMBER='(0,0,0,0,0,0,0,0,0,0,0,0,0,DK71,0,0,0,0,0,0,0,0,0,0,0,0,0,0,0,0,0,0,0,0,0,0,0,0,0,0,0,0)';
      BIDIRECTIONAL='TRUE';
      INPUT_LOAD='(-0.01,0.01)';
      OUTPUT_LOAD='(1.0,-1.0)';
    'DDR6_SA_DQ8':
      PIN_NUMBER='(0,0,0,0,0,0,0,0,0,0,0,0,0,DL72,0,0,0,0,0,0,0,0,0,0,0,0,0,0,0,0,0,0,0,0,0,0,0,0,0,0,0,0)';
      BIDIRECTIONAL='TRUE';
      INPUT_LOAD='(-0.01,0.01)';
      OUTPUT_LOAD='(1.0,-1.0)';
    'DDR6_SA_DQ7':
      PIN_NUMBER='(0,0,0,0,0,0,0,0,0,0,0,0,0,DY71,0,0,0,0,0,0,0,0,0,0,0,0,0,0,0,0,0,0,0,0,0,0,0,0,0,0,0,0)';
      BIDIRECTIONAL='TRUE';
      INPUT_LOAD='(-0.01,0.01)';
      OUTPUT_LOAD='(1.0,-1.0)';
    'DDR6_SA_DQ6':
      PIN_NUMBER='(0,0,0,0,0,0,0,0,0,0,0,0,0,EA72,0,0,0,0,0,0,0,0,0,0,0,0,0,0,0,0,0,0,0,0,0,0,0,0,0,0,0,0)';
      BIDIRECTIONAL='TRUE';
      INPUT_LOAD='(-0.01,0.01)';
      OUTPUT_LOAD='(1.0,-1.0)';
    'DDR6_SA_DQ5':
      PIN_NUMBER='(0,0,0,0,0,0,0,0,0,0,0,0,0,DV71,0,0,0,0,0,0,0,0,0,0,0,0,0,0,0,0,0,0,0,0,0,0,0,0,0,0,0,0)';
      BIDIRECTIONAL='TRUE';
      INPUT_LOAD='(-0.01,0.01)';
      OUTPUT_LOAD='(1.0,-1.0)';
    'DDR6_SA_DQ4':
      PIN_NUMBER='(0,0,0,0,0,0,0,0,0,0,0,0,0,DU72,0,0,0,0,0,0,0,0,0,0,0,0,0,0,0,0,0,0,0,0,0,0,0,0,0,0,0,0)';
      BIDIRECTIONAL='TRUE';
      INPUT_LOAD='(-0.01,0.01)';
      OUTPUT_LOAD='(1.0,-1.0)';
    'DDR6_SA_DQ3':
      PIN_NUMBER='(0,0,0,0,0,0,0,0,0,0,0,0,0,EA74,0,0,0,0,0,0,0,0,0,0,0,0,0,0,0,0,0,0,0,0,0,0,0,0,0,0,0,0)';
      BIDIRECTIONAL='TRUE';
      INPUT_LOAD='(-0.01,0.01)';
      OUTPUT_LOAD='(1.0,-1.0)';
    'DDR6_SA_DQ2':
      PIN_NUMBER='(0,0,0,0,0,0,0,0,0,0,0,0,0,DY75,0,0,0,0,0,0,0,0,0,0,0,0,0,0,0,0,0,0,0,0,0,0,0,0,0,0,0,0)';
      BIDIRECTIONAL='TRUE';
      INPUT_LOAD='(-0.01,0.01)';
      OUTPUT_LOAD='(1.0,-1.0)';
    'DDR6_SA_DQ1':
      PIN_NUMBER='(0,0,0,0,0,0,0,0,0,0,0,0,0,DU74,0,0,0,0,0,0,0,0,0,0,0,0,0,0,0,0,0,0,0,0,0,0,0,0,0,0,0,0)';
      BIDIRECTIONAL='TRUE';
      INPUT_LOAD='(-0.01,0.01)';
      OUTPUT_LOAD='(1.0,-1.0)';
    'DDR6_SA_DQ0':
      PIN_NUMBER='(0,0,0,0,0,0,0,0,0,0,0,0,0,DV75,0,0,0,0,0,0,0,0,0,0,0,0,0,0,0,0,0,0,0,0,0,0,0,0,0,0,0,0)';
      BIDIRECTIONAL='TRUE';
      INPUT_LOAD='(-0.01,0.01)';
      OUTPUT_LOAD='(1.0,-1.0)';
    'DDR6_SA_DQS_DN9':
      PIN_NUMBER='(0,0,0,0,0,0,0,0,0,0,0,0,0,DR58,0,0,0,0,0,0,0,0,0,0,0,0,0,0,0,0,0,0,0,0,0,0,0,0,0,0,0,0)';
      BIDIRECTIONAL='TRUE';
      INPUT_LOAD='(-0.01,0.01)';
      OUTPUT_LOAD='(1.0,-1.0)';
    'DDR6_SA_DQS_DN8':
      PIN_NUMBER='(0,0,0,0,0,0,0,0,0,0,0,0,0,DR64,0,0,0,0,0,0,0,0,0,0,0,0,0,0,0,0,0,0,0,0,0,0,0,0,0,0,0,0)';
      BIDIRECTIONAL='TRUE';
      INPUT_LOAD='(-0.01,0.01)';
      OUTPUT_LOAD='(1.0,-1.0)';
    'DDR6_SA_DQS_DN7':
      PIN_NUMBER='(0,0,0,0,0,0,0,0,0,0,0,0,0,EB61,0,0,0,0,0,0,0,0,0,0,0,0,0,0,0,0,0,0,0,0,0,0,0,0,0,0,0,0)';
      BIDIRECTIONAL='TRUE';
      INPUT_LOAD='(-0.01,0.01)';
      OUTPUT_LOAD='(1.0,-1.0)';
    'DDR6_SA_DQS_DN6':
      PIN_NUMBER='(0,0,0,0,0,0,0,0,0,0,0,0,0,DR70,0,0,0,0,0,0,0,0,0,0,0,0,0,0,0,0,0,0,0,0,0,0,0,0,0,0,0,0)';
      BIDIRECTIONAL='TRUE';
      INPUT_LOAD='(-0.01,0.01)';
      OUTPUT_LOAD='(1.0,-1.0)';
    'DDR6_SA_DQS_DN5':
      PIN_NUMBER='(0,0,0,0,0,0,0,0,0,0,0,0,0,EB73,0,0,0,0,0,0,0,0,0,0,0,0,0,0,0,0,0,0,0,0,0,0,0,0,0,0,0,0)';
      BIDIRECTIONAL='TRUE';
      INPUT_LOAD='(-0.01,0.01)';
      OUTPUT_LOAD='(1.0,-1.0)';
    'DDR6_SA_DQS_DN4':
      PIN_NUMBER='(0,0,0,0,0,0,0,0,0,0,0,0,0,DL58,0,0,0,0,0,0,0,0,0,0,0,0,0,0,0,0,0,0,0,0,0,0,0,0,0,0,0,0)';
      BIDIRECTIONAL='TRUE';
      INPUT_LOAD='(-0.01,0.01)';
      OUTPUT_LOAD='(1.0,-1.0)';
    'DDR6_SA_DQS_DN3':
      PIN_NUMBER='(0,0,0,0,0,0,0,0,0,0,0,0,0,DL64,0,0,0,0,0,0,0,0,0,0,0,0,0,0,0,0,0,0,0,0,0,0,0,0,0,0,0,0)';
      BIDIRECTIONAL='TRUE';
      INPUT_LOAD='(-0.01,0.01)';
      OUTPUT_LOAD='(1.0,-1.0)';
    'DDR6_SA_DQS_DN2':
      PIN_NUMBER='(0,0,0,0,0,0,0,0,0,0,0,0,0,DT61,0,0,0,0,0,0,0,0,0,0,0,0,0,0,0,0,0,0,0,0,0,0,0,0,0,0,0,0)';
      BIDIRECTIONAL='TRUE';
      INPUT_LOAD='(-0.01,0.01)';
      OUTPUT_LOAD='(1.0,-1.0)';
    'DDR6_SA_DQS_DN1':
      PIN_NUMBER='(0,0,0,0,0,0,0,0,0,0,0,0,0,DJ70,0,0,0,0,0,0,0,0,0,0,0,0,0,0,0,0,0,0,0,0,0,0,0,0,0,0,0,0)';
      BIDIRECTIONAL='TRUE';
      INPUT_LOAD='(-0.01,0.01)';
      OUTPUT_LOAD='(1.0,-1.0)';
    'DDR6_SA_DQS_DN0':
      PIN_NUMBER='(0,0,0,0,0,0,0,0,0,0,0,0,0,DV73,0,0,0,0,0,0,0,0,0,0,0,0,0,0,0,0,0,0,0,0,0,0,0,0,0,0,0,0)';
      BIDIRECTIONAL='TRUE';
      INPUT_LOAD='(-0.01,0.01)';
      OUTPUT_LOAD='(1.0,-1.0)';
    'DDR6_SA_DQS_DP9':
      PIN_NUMBER='(0,0,0,0,0,0,0,0,0,0,0,0,0,DN58,0,0,0,0,0,0,0,0,0,0,0,0,0,0,0,0,0,0,0,0,0,0,0,0,0,0,0,0)';
      BIDIRECTIONAL='TRUE';
      INPUT_LOAD='(-0.01,0.01)';
      OUTPUT_LOAD='(1.0,-1.0)';
    'DDR6_SA_DQS_DP8':
      PIN_NUMBER='(0,0,0,0,0,0,0,0,0,0,0,0,0,DN64,0,0,0,0,0,0,0,0,0,0,0,0,0,0,0,0,0,0,0,0,0,0,0,0,0,0,0,0)';
      BIDIRECTIONAL='TRUE';
      INPUT_LOAD='(-0.01,0.01)';
      OUTPUT_LOAD='(1.0,-1.0)';
    'DDR6_SA_DQS_DP7':
      PIN_NUMBER='(0,0,0,0,0,0,0,0,0,0,0,0,0,DY61,0,0,0,0,0,0,0,0,0,0,0,0,0,0,0,0,0,0,0,0,0,0,0,0,0,0,0,0)';
      BIDIRECTIONAL='TRUE';
      INPUT_LOAD='(-0.01,0.01)';
      OUTPUT_LOAD='(1.0,-1.0)';
    'DDR6_SA_DQS_DP6':
      PIN_NUMBER='(0,0,0,0,0,0,0,0,0,0,0,0,0,DN70,0,0,0,0,0,0,0,0,0,0,0,0,0,0,0,0,0,0,0,0,0,0,0,0,0,0,0,0)';
      BIDIRECTIONAL='TRUE';
      INPUT_LOAD='(-0.01,0.01)';
      OUTPUT_LOAD='(1.0,-1.0)';
    'DDR6_SA_DQS_DP5':
      PIN_NUMBER='(0,0,0,0,0,0,0,0,0,0,0,0,0,DY73,0,0,0,0,0,0,0,0,0,0,0,0,0,0,0,0,0,0,0,0,0,0,0,0,0,0,0,0)';
      BIDIRECTIONAL='TRUE';
      INPUT_LOAD='(-0.01,0.01)';
      OUTPUT_LOAD='(1.0,-1.0)';
    'DDR6_SA_DQS_DP4':
      PIN_NUMBER='(0,0,0,0,0,0,0,0,0,0,0,0,0,DJ58,0,0,0,0,0,0,0,0,0,0,0,0,0,0,0,0,0,0,0,0,0,0,0,0,0,0,0,0)';
      BIDIRECTIONAL='TRUE';
      INPUT_LOAD='(-0.01,0.01)';
      OUTPUT_LOAD='(1.0,-1.0)';
    'DDR6_SA_DQS_DP3':
      PIN_NUMBER='(0,0,0,0,0,0,0,0,0,0,0,0,0,DJ64,0,0,0,0,0,0,0,0,0,0,0,0,0,0,0,0,0,0,0,0,0,0,0,0,0,0,0,0)';
      BIDIRECTIONAL='TRUE';
      INPUT_LOAD='(-0.01,0.01)';
      OUTPUT_LOAD='(1.0,-1.0)';
    'DDR6_SA_DQS_DP2':
      PIN_NUMBER='(0,0,0,0,0,0,0,0,0,0,0,0,0,DV61,0,0,0,0,0,0,0,0,0,0,0,0,0,0,0,0,0,0,0,0,0,0,0,0,0,0,0,0)';
      BIDIRECTIONAL='TRUE';
      INPUT_LOAD='(-0.01,0.01)';
      OUTPUT_LOAD='(1.0,-1.0)';
    'DDR6_SA_DQS_DP1':
      PIN_NUMBER='(0,0,0,0,0,0,0,0,0,0,0,0,0,DL70,0,0,0,0,0,0,0,0,0,0,0,0,0,0,0,0,0,0,0,0,0,0,0,0,0,0,0,0)';
      BIDIRECTIONAL='TRUE';
      INPUT_LOAD='(-0.01,0.01)';
      OUTPUT_LOAD='(1.0,-1.0)';
    'DDR6_SA_DQS_DP0':
      PIN_NUMBER='(0,0,0,0,0,0,0,0,0,0,0,0,0,DT73,0,0,0,0,0,0,0,0,0,0,0,0,0,0,0,0,0,0,0,0,0,0,0,0,0,0,0,0)';
      BIDIRECTIONAL='TRUE';
      INPUT_LOAD='(-0.01,0.01)';
      OUTPUT_LOAD='(1.0,-1.0)';
    'DDR6_SA_ECC7':
      PIN_NUMBER='(0,0,0,0,0,0,0,0,0,0,0,0,0,DN56,0,0,0,0,0,0,0,0,0,0,0,0,0,0,0,0,0,0,0,0,0,0,0,0,0,0,0,0)';
      BIDIRECTIONAL='TRUE';
      INPUT_LOAD='(-0.01,0.01)';
      OUTPUT_LOAD='(1.0,-1.0)';
    'DDR6_SA_ECC6':
      PIN_NUMBER='(0,0,0,0,0,0,0,0,0,0,0,0,0,DP57,0,0,0,0,0,0,0,0,0,0,0,0,0,0,0,0,0,0,0,0,0,0,0,0,0,0,0,0)';
      BIDIRECTIONAL='TRUE';
      INPUT_LOAD='(-0.01,0.01)';
      OUTPUT_LOAD='(1.0,-1.0)';
    'DDR6_SA_ECC5':
      PIN_NUMBER='(0,0,0,0,0,0,0,0,0,0,0,0,0,DL56,0,0,0,0,0,0,0,0,0,0,0,0,0,0,0,0,0,0,0,0,0,0,0,0,0,0,0,0)';
      BIDIRECTIONAL='TRUE';
      INPUT_LOAD='(-0.01,0.01)';
      OUTPUT_LOAD='(1.0,-1.0)';
    'DDR6_SA_ECC4':
      PIN_NUMBER='(0,0,0,0,0,0,0,0,0,0,0,0,0,DK57,0,0,0,0,0,0,0,0,0,0,0,0,0,0,0,0,0,0,0,0,0,0,0,0,0,0,0,0)';
      BIDIRECTIONAL='TRUE';
      INPUT_LOAD='(-0.01,0.01)';
      OUTPUT_LOAD='(1.0,-1.0)';
    'DDR6_SA_ECC3':
      PIN_NUMBER='(0,0,0,0,0,0,0,0,0,0,0,0,0,DP59,0,0,0,0,0,0,0,0,0,0,0,0,0,0,0,0,0,0,0,0,0,0,0,0,0,0,0,0)';
      BIDIRECTIONAL='TRUE';
      INPUT_LOAD='(-0.01,0.01)';
      OUTPUT_LOAD='(1.0,-1.0)';
    'DDR6_SA_ECC2':
      PIN_NUMBER='(0,0,0,0,0,0,0,0,0,0,0,0,0,DN60,0,0,0,0,0,0,0,0,0,0,0,0,0,0,0,0,0,0,0,0,0,0,0,0,0,0,0,0)';
      BIDIRECTIONAL='TRUE';
      INPUT_LOAD='(-0.01,0.01)';
      OUTPUT_LOAD='(1.0,-1.0)';
    'DDR6_SA_ECC1':
      PIN_NUMBER='(0,0,0,0,0,0,0,0,0,0,0,0,0,DK59,0,0,0,0,0,0,0,0,0,0,0,0,0,0,0,0,0,0,0,0,0,0,0,0,0,0,0,0)';
      BIDIRECTIONAL='TRUE';
      INPUT_LOAD='(-0.01,0.01)';
      OUTPUT_LOAD='(1.0,-1.0)';
    'DDR6_SA_ECC0':
      PIN_NUMBER='(0,0,0,0,0,0,0,0,0,0,0,0,0,DL60,0,0,0,0,0,0,0,0,0,0,0,0,0,0,0,0,0,0,0,0,0,0,0,0,0,0,0,0)';
      BIDIRECTIONAL='TRUE';
      INPUT_LOAD='(-0.01,0.01)';
      OUTPUT_LOAD='(1.0,-1.0)';
    'DDR6_SA_PAR':
      PIN_NUMBER='(0,0,0,0,0,0,0,0,0,0,0,0,0,DL43,0,0,0,0,0,0,0,0,0,0,0,0,0,0,0,0,0,0,0,0,0,0,0,0,0,0,0,0)';
      OUTPUT_LOAD='(1.0,-1.0)';
    'DDR6_SB_CA6':
      PIN_NUMBER='(0,0,0,0,0,0,0,0,0,0,0,0,0,DT42,0,0,0,0,0,0,0,0,0,0,0,0,0,0,0,0,0,0,0,0,0,0,0,0,0,0,0,0)';
      OUTPUT_LOAD='(1.0,-1.0)';
    'DDR6_SB_CA5':
      PIN_NUMBER='(0,0,0,0,0,0,0,0,0,0,0,0,0,EA43,0,0,0,0,0,0,0,0,0,0,0,0,0,0,0,0,0,0,0,0,0,0,0,0,0,0,0,0)';
      OUTPUT_LOAD='(1.0,-1.0)';
    'DDR6_SB_CA4':
      PIN_NUMBER='(0,0,0,0,0,0,0,0,0,0,0,0,0,DU43,0,0,0,0,0,0,0,0,0,0,0,0,0,0,0,0,0,0,0,0,0,0,0,0,0,0,0,0)';
      OUTPUT_LOAD='(1.0,-1.0)';
    'DDR6_SB_CA3':
      PIN_NUMBER='(0,0,0,0,0,0,0,0,0,0,0,0,0,DY44,0,0,0,0,0,0,0,0,0,0,0,0,0,0,0,0,0,0,0,0,0,0,0,0,0,0,0,0)';
      OUTPUT_LOAD='(1.0,-1.0)';
    'DDR6_SB_CA2':
      PIN_NUMBER='(0,0,0,0,0,0,0,0,0,0,0,0,0,DV44,0,0,0,0,0,0,0,0,0,0,0,0,0,0,0,0,0,0,0,0,0,0,0,0,0,0,0,0)';
      OUTPUT_LOAD='(1.0,-1.0)';
    'DDR6_SB_CA1':
      PIN_NUMBER='(0,0,0,0,0,0,0,0,0,0,0,0,0,DP44,0,0,0,0,0,0,0,0,0,0,0,0,0,0,0,0,0,0,0,0,0,0,0,0,0,0,0,0)';
      OUTPUT_LOAD='(1.0,-1.0)';
    'DDR6_SB_CA0':
      PIN_NUMBER='(0,0,0,0,0,0,0,0,0,0,0,0,0,DN43,0,0,0,0,0,0,0,0,0,0,0,0,0,0,0,0,0,0,0,0,0,0,0,0,0,0,0,0)';
      OUTPUT_LOAD='(1.0,-1.0)';
    'DDR6_SB_CS_N3':
      PIN_NUMBER='(0,0,0,0,0,0,0,0,0,0,0,0,0,DV40,0,0,0,0,0,0,0,0,0,0,0,0,0,0,0,0,0,0,0,0,0,0,0,0,0,0,0,0)';
      OUTPUT_LOAD='(1.0,-1.0)';
    'DDR6_SB_CS_N2':
      PIN_NUMBER='(0,0,0,0,0,0,0,0,0,0,0,0,0,DU41,0,0,0,0,0,0,0,0,0,0,0,0,0,0,0,0,0,0,0,0,0,0,0,0,0,0,0,0)';
      OUTPUT_LOAD='(1.0,-1.0)';
    'DDR6_SB_CS_N1':
      PIN_NUMBER='(0,0,0,0,0,0,0,0,0,0,0,0,0,DY40,0,0,0,0,0,0,0,0,0,0,0,0,0,0,0,0,0,0,0,0,0,0,0,0,0,0,0,0)';
      OUTPUT_LOAD='(1.0,-1.0)';
    'DDR6_SB_CS_N0':
      PIN_NUMBER='(0,0,0,0,0,0,0,0,0,0,0,0,0,EA41,0,0,0,0,0,0,0,0,0,0,0,0,0,0,0,0,0,0,0,0,0,0,0,0,0,0,0,0)';
      OUTPUT_LOAD='(1.0,-1.0)';
    'DDR6_SB_DQ31':
      PIN_NUMBER='(0,0,0,0,0,0,0,0,0,0,0,0,0,EM4,0,0,0,0,0,0,0,0,0,0,0,0,0,0,0,0,0,0,0,0,0,0,0,0,0,0,0,0)';
      BIDIRECTIONAL='TRUE';
      INPUT_LOAD='(-0.01,0.01)';
      OUTPUT_LOAD='(1.0,-1.0)';
    'DDR6_SB_DQ30':
      PIN_NUMBER='(0,0,0,0,0,0,0,0,0,0,0,0,0,EP4,0,0,0,0,0,0,0,0,0,0,0,0,0,0,0,0,0,0,0,0,0,0,0,0,0,0,0,0)';
      BIDIRECTIONAL='TRUE';
      INPUT_LOAD='(-0.01,0.01)';
      OUTPUT_LOAD='(1.0,-1.0)';
    'DDR6_SB_DQ29':
      PIN_NUMBER='(0,0,0,0,0,0,0,0,0,0,0,0,0,EJ5,0,0,0,0,0,0,0,0,0,0,0,0,0,0,0,0,0,0,0,0,0,0,0,0,0,0,0,0)';
      BIDIRECTIONAL='TRUE';
      INPUT_LOAD='(-0.01,0.01)';
      OUTPUT_LOAD='(1.0,-1.0)';
    'DDR6_SB_DQ28':
      PIN_NUMBER='(0,0,0,0,0,0,0,0,0,0,0,0,0,EK6,0,0,0,0,0,0,0,0,0,0,0,0,0,0,0,0,0,0,0,0,0,0,0,0,0,0,0,0)';
      BIDIRECTIONAL='TRUE';
      INPUT_LOAD='(-0.01,0.01)';
      OUTPUT_LOAD='(1.0,-1.0)';
    'DDR6_SB_DQ27':
      PIN_NUMBER='(0,0,0,0,0,0,0,0,0,0,0,0,0,ET8,0,0,0,0,0,0,0,0,0,0,0,0,0,0,0,0,0,0,0,0,0,0,0,0,0,0,0,0)';
      BIDIRECTIONAL='TRUE';
      INPUT_LOAD='(-0.01,0.01)';
      OUTPUT_LOAD='(1.0,-1.0)';
    'DDR6_SB_DQ26':
      PIN_NUMBER='(0,0,0,0,0,0,0,0,0,0,0,0,0,EP8,0,0,0,0,0,0,0,0,0,0,0,0,0,0,0,0,0,0,0,0,0,0,0,0,0,0,0,0)';
      BIDIRECTIONAL='TRUE';
      INPUT_LOAD='(-0.01,0.01)';
      OUTPUT_LOAD='(1.0,-1.0)';
    'DDR6_SB_DQ25':
      PIN_NUMBER='(0,0,0,0,0,0,0,0,0,0,0,0,0,EH8,0,0,0,0,0,0,0,0,0,0,0,0,0,0,0,0,0,0,0,0,0,0,0,0,0,0,0,0)';
      BIDIRECTIONAL='TRUE';
      INPUT_LOAD='(-0.01,0.01)';
      OUTPUT_LOAD='(1.0,-1.0)';
    'DDR6_SB_DQ24':
      PIN_NUMBER='(0,0,0,0,0,0,0,0,0,0,0,0,0,EK8,0,0,0,0,0,0,0,0,0,0,0,0,0,0,0,0,0,0,0,0,0,0,0,0,0,0,0,0)';
      BIDIRECTIONAL='TRUE';
      INPUT_LOAD='(-0.01,0.01)';
      OUTPUT_LOAD='(1.0,-1.0)';
    'DDR6_SB_DQ23':
      PIN_NUMBER='(0,0,0,0,0,0,0,0,0,0,0,0,0,DY22,0,0,0,0,0,0,0,0,0,0,0,0,0,0,0,0,0,0,0,0,0,0,0,0,0,0,0,0)';
      BIDIRECTIONAL='TRUE';
      INPUT_LOAD='(-0.01,0.01)';
      OUTPUT_LOAD='(1.0,-1.0)';
    'DDR6_SB_DQ22':
      PIN_NUMBER='(0,0,0,0,0,0,0,0,0,0,0,0,0,EA23,0,0,0,0,0,0,0,0,0,0,0,0,0,0,0,0,0,0,0,0,0,0,0,0,0,0,0,0)';
      BIDIRECTIONAL='TRUE';
      INPUT_LOAD='(-0.01,0.01)';
      OUTPUT_LOAD='(1.0,-1.0)';
    'DDR6_SB_DQ21':
      PIN_NUMBER='(0,0,0,0,0,0,0,0,0,0,0,0,0,DV22,0,0,0,0,0,0,0,0,0,0,0,0,0,0,0,0,0,0,0,0,0,0,0,0,0,0,0,0)';
      BIDIRECTIONAL='TRUE';
      INPUT_LOAD='(-0.01,0.01)';
      OUTPUT_LOAD='(1.0,-1.0)';
    'DDR6_SB_DQ20':
      PIN_NUMBER='(0,0,0,0,0,0,0,0,0,0,0,0,0,DU23,0,0,0,0,0,0,0,0,0,0,0,0,0,0,0,0,0,0,0,0,0,0,0,0,0,0,0,0)';
      BIDIRECTIONAL='TRUE';
      INPUT_LOAD='(-0.01,0.01)';
      OUTPUT_LOAD='(1.0,-1.0)';
    'DDR6_SB_DQ19':
      PIN_NUMBER='(0,0,0,0,0,0,0,0,0,0,0,0,0,EA25,0,0,0,0,0,0,0,0,0,0,0,0,0,0,0,0,0,0,0,0,0,0,0,0,0,0,0,0)';
      BIDIRECTIONAL='TRUE';
      INPUT_LOAD='(-0.01,0.01)';
      OUTPUT_LOAD='(1.0,-1.0)';
    'DDR6_SB_DQ18':
      PIN_NUMBER='(0,0,0,0,0,0,0,0,0,0,0,0,0,DY26,0,0,0,0,0,0,0,0,0,0,0,0,0,0,0,0,0,0,0,0,0,0,0,0,0,0,0,0)';
      BIDIRECTIONAL='TRUE';
      INPUT_LOAD='(-0.01,0.01)';
      OUTPUT_LOAD='(1.0,-1.0)';
    'DDR6_SB_DQ17':
      PIN_NUMBER='(0,0,0,0,0,0,0,0,0,0,0,0,0,DU25,0,0,0,0,0,0,0,0,0,0,0,0,0,0,0,0,0,0,0,0,0,0,0,0,0,0,0,0)';
      BIDIRECTIONAL='TRUE';
      INPUT_LOAD='(-0.01,0.01)';
      OUTPUT_LOAD='(1.0,-1.0)';
    'DDR6_SB_DQ16':
      PIN_NUMBER='(0,0,0,0,0,0,0,0,0,0,0,0,0,DV26,0,0,0,0,0,0,0,0,0,0,0,0,0,0,0,0,0,0,0,0,0,0,0,0,0,0,0,0)';
      BIDIRECTIONAL='TRUE';
      INPUT_LOAD='(-0.01,0.01)';
      OUTPUT_LOAD='(1.0,-1.0)';
    'DDR6_SB_DQ15':
      PIN_NUMBER='(0,0,0,0,0,0,0,0,0,0,0,0,0,DN25,0,0,0,0,0,0,0,0,0,0,0,0,0,0,0,0,0,0,0,0,0,0,0,0,0,0,0,0)';
      BIDIRECTIONAL='TRUE';
      INPUT_LOAD='(-0.01,0.01)';
      OUTPUT_LOAD='(1.0,-1.0)';
    'DDR6_SB_DQ14':
      PIN_NUMBER='(0,0,0,0,0,0,0,0,0,0,0,0,0,DP26,0,0,0,0,0,0,0,0,0,0,0,0,0,0,0,0,0,0,0,0,0,0,0,0,0,0,0,0)';
      BIDIRECTIONAL='TRUE';
      INPUT_LOAD='(-0.01,0.01)';
      OUTPUT_LOAD='(1.0,-1.0)';
    'DDR6_SB_DQ13':
      PIN_NUMBER='(0,0,0,0,0,0,0,0,0,0,0,0,0,DL25,0,0,0,0,0,0,0,0,0,0,0,0,0,0,0,0,0,0,0,0,0,0,0,0,0,0,0,0)';
      BIDIRECTIONAL='TRUE';
      INPUT_LOAD='(-0.01,0.01)';
      OUTPUT_LOAD='(1.0,-1.0)';
    'DDR6_SB_DQ12':
      PIN_NUMBER='(0,0,0,0,0,0,0,0,0,0,0,0,0,DK26,0,0,0,0,0,0,0,0,0,0,0,0,0,0,0,0,0,0,0,0,0,0,0,0,0,0,0,0)';
      BIDIRECTIONAL='TRUE';
      INPUT_LOAD='(-0.01,0.01)';
      OUTPUT_LOAD='(1.0,-1.0)';
    'DDR6_SB_DQ11':
      PIN_NUMBER='(0,0,0,0,0,0,0,0,0,0,0,0,0,DP28,0,0,0,0,0,0,0,0,0,0,0,0,0,0,0,0,0,0,0,0,0,0,0,0,0,0,0,0)';
      BIDIRECTIONAL='TRUE';
      INPUT_LOAD='(-0.01,0.01)';
      OUTPUT_LOAD='(1.0,-1.0)';
    'DDR6_SB_DQ10':
      PIN_NUMBER='(0,0,0,0,0,0,0,0,0,0,0,0,0,DL29,0,0,0,0,0,0,0,0,0,0,0,0,0,0,0,0,0,0,0,0,0,0,0,0,0,0,0,0)';
      BIDIRECTIONAL='TRUE';
      INPUT_LOAD='(-0.01,0.01)';
      OUTPUT_LOAD='(1.0,-1.0)';
    'DDR6_SB_DQ9':
      PIN_NUMBER='(0,0,0,0,0,0,0,0,0,0,0,0,0,DK28,0,0,0,0,0,0,0,0,0,0,0,0,0,0,0,0,0,0,0,0,0,0,0,0,0,0,0,0)';
      BIDIRECTIONAL='TRUE';
      INPUT_LOAD='(-0.01,0.01)';
      OUTPUT_LOAD='(1.0,-1.0)';
    'DDR6_SB_DQ8':
      PIN_NUMBER='(0,0,0,0,0,0,0,0,0,0,0,0,0,DN29,0,0,0,0,0,0,0,0,0,0,0,0,0,0,0,0,0,0,0,0,0,0,0,0,0,0,0,0)';
      BIDIRECTIONAL='TRUE';
      INPUT_LOAD='(-0.01,0.01)';
      OUTPUT_LOAD='(1.0,-1.0)';
    'DDR6_SB_DQ7':
      PIN_NUMBER='(0,0,0,0,0,0,0,0,0,0,0,0,0,DN31,0,0,0,0,0,0,0,0,0,0,0,0,0,0,0,0,0,0,0,0,0,0,0,0,0,0,0,0)';
      BIDIRECTIONAL='TRUE';
      INPUT_LOAD='(-0.01,0.01)';
      OUTPUT_LOAD='(1.0,-1.0)';
    'DDR6_SB_DQ6':
      PIN_NUMBER='(0,0,0,0,0,0,0,0,0,0,0,0,0,DP32,0,0,0,0,0,0,0,0,0,0,0,0,0,0,0,0,0,0,0,0,0,0,0,0,0,0,0,0)';
      BIDIRECTIONAL='TRUE';
      INPUT_LOAD='(-0.01,0.01)';
      OUTPUT_LOAD='(1.0,-1.0)';
    'DDR6_SB_DQ5':
      PIN_NUMBER='(0,0,0,0,0,0,0,0,0,0,0,0,0,DL31,0,0,0,0,0,0,0,0,0,0,0,0,0,0,0,0,0,0,0,0,0,0,0,0,0,0,0,0)';
      BIDIRECTIONAL='TRUE';
      INPUT_LOAD='(-0.01,0.01)';
      OUTPUT_LOAD='(1.0,-1.0)';
    'DDR6_SB_DQ4':
      PIN_NUMBER='(0,0,0,0,0,0,0,0,0,0,0,0,0,DK32,0,0,0,0,0,0,0,0,0,0,0,0,0,0,0,0,0,0,0,0,0,0,0,0,0,0,0,0)';
      BIDIRECTIONAL='TRUE';
      INPUT_LOAD='(-0.01,0.01)';
      OUTPUT_LOAD='(1.0,-1.0)';
    'DDR6_SB_DQ3':
      PIN_NUMBER='(0,0,0,0,0,0,0,0,0,0,0,0,0,DP34,0,0,0,0,0,0,0,0,0,0,0,0,0,0,0,0,0,0,0,0,0,0,0,0,0,0,0,0)';
      BIDIRECTIONAL='TRUE';
      INPUT_LOAD='(-0.01,0.01)';
      OUTPUT_LOAD='(1.0,-1.0)';
    'DDR6_SB_DQ2':
      PIN_NUMBER='(0,0,0,0,0,0,0,0,0,0,0,0,0,DN35,0,0,0,0,0,0,0,0,0,0,0,0,0,0,0,0,0,0,0,0,0,0,0,0,0,0,0,0)';
      BIDIRECTIONAL='TRUE';
      INPUT_LOAD='(-0.01,0.01)';
      OUTPUT_LOAD='(1.0,-1.0)';
    'DDR6_SB_DQ1':
      PIN_NUMBER='(0,0,0,0,0,0,0,0,0,0,0,0,0,DK34,0,0,0,0,0,0,0,0,0,0,0,0,0,0,0,0,0,0,0,0,0,0,0,0,0,0,0,0)';
      BIDIRECTIONAL='TRUE';
      INPUT_LOAD='(-0.01,0.01)';
      OUTPUT_LOAD='(1.0,-1.0)';
    'DDR6_SB_DQ0':
      PIN_NUMBER='(0,0,0,0,0,0,0,0,0,0,0,0,0,DL35,0,0,0,0,0,0,0,0,0,0,0,0,0,0,0,0,0,0,0,0,0,0,0,0,0,0,0,0)';
      BIDIRECTIONAL='TRUE';
      INPUT_LOAD='(-0.01,0.01)';
      OUTPUT_LOAD='(1.0,-1.0)';
    'DDR6_SB_DQS_DN9':
      PIN_NUMBER='(0,0,0,0,0,0,0,0,0,0,0,0,0,DV36,0,0,0,0,0,0,0,0,0,0,0,0,0,0,0,0,0,0,0,0,0,0,0,0,0,0,0,0)';
      BIDIRECTIONAL='TRUE';
      INPUT_LOAD='(-0.01,0.01)';
      OUTPUT_LOAD='(1.0,-1.0)';
    'DDR6_SB_DQS_DN8':
      PIN_NUMBER='(0,0,0,0,0,0,0,0,0,0,0,0,0,EM6,0,0,0,0,0,0,0,0,0,0,0,0,0,0,0,0,0,0,0,0,0,0,0,0,0,0,0,0)';
      BIDIRECTIONAL='TRUE';
      INPUT_LOAD='(-0.01,0.01)';
      OUTPUT_LOAD='(1.0,-1.0)';
    'DDR6_SB_DQS_DN7':
      PIN_NUMBER='(0,0,0,0,0,0,0,0,0,0,0,0,0,EB24,0,0,0,0,0,0,0,0,0,0,0,0,0,0,0,0,0,0,0,0,0,0,0,0,0,0,0,0)';
      BIDIRECTIONAL='TRUE';
      INPUT_LOAD='(-0.01,0.01)';
      OUTPUT_LOAD='(1.0,-1.0)';
    'DDR6_SB_DQS_DN6':
      PIN_NUMBER='(0,0,0,0,0,0,0,0,0,0,0,0,0,DN27,0,0,0,0,0,0,0,0,0,0,0,0,0,0,0,0,0,0,0,0,0,0,0,0,0,0,0,0)';
      BIDIRECTIONAL='TRUE';
      INPUT_LOAD='(-0.01,0.01)';
      OUTPUT_LOAD='(1.0,-1.0)';
    'DDR6_SB_DQS_DN5':
      PIN_NUMBER='(0,0,0,0,0,0,0,0,0,0,0,0,0,DR33,0,0,0,0,0,0,0,0,0,0,0,0,0,0,0,0,0,0,0,0,0,0,0,0,0,0,0,0)';
      BIDIRECTIONAL='TRUE';
      INPUT_LOAD='(-0.01,0.01)';
      OUTPUT_LOAD='(1.0,-1.0)';
    'DDR6_SB_DQS_DN4':
      PIN_NUMBER='(0,0,0,0,0,0,0,0,0,0,0,0,0,EB36,0,0,0,0,0,0,0,0,0,0,0,0,0,0,0,0,0,0,0,0,0,0,0,0,0,0,0,0)';
      BIDIRECTIONAL='TRUE';
      INPUT_LOAD='(-0.01,0.01)';
      OUTPUT_LOAD='(1.0,-1.0)';
    'DDR6_SB_DQS_DN3':
      PIN_NUMBER='(0,0,0,0,0,0,0,0,0,0,0,0,0,EP6,0,0,0,0,0,0,0,0,0,0,0,0,0,0,0,0,0,0,0,0,0,0,0,0,0,0,0,0)';
      BIDIRECTIONAL='TRUE';
      INPUT_LOAD='(-0.01,0.01)';
      OUTPUT_LOAD='(1.0,-1.0)';
    'DDR6_SB_DQS_DN2':
      PIN_NUMBER='(0,0,0,0,0,0,0,0,0,0,0,0,0,DV24,0,0,0,0,0,0,0,0,0,0,0,0,0,0,0,0,0,0,0,0,0,0,0,0,0,0,0,0)';
      BIDIRECTIONAL='TRUE';
      INPUT_LOAD='(-0.01,0.01)';
      OUTPUT_LOAD='(1.0,-1.0)';
    'DDR6_SB_DQS_DN1':
      PIN_NUMBER='(0,0,0,0,0,0,0,0,0,0,0,0,0,DJ27,0,0,0,0,0,0,0,0,0,0,0,0,0,0,0,0,0,0,0,0,0,0,0,0,0,0,0,0)';
      BIDIRECTIONAL='TRUE';
      INPUT_LOAD='(-0.01,0.01)';
      OUTPUT_LOAD='(1.0,-1.0)';
    'DDR6_SB_DQS_DN0':
      PIN_NUMBER='(0,0,0,0,0,0,0,0,0,0,0,0,0,DJ33,0,0,0,0,0,0,0,0,0,0,0,0,0,0,0,0,0,0,0,0,0,0,0,0,0,0,0,0)';
      BIDIRECTIONAL='TRUE';
      INPUT_LOAD='(-0.01,0.01)';
      OUTPUT_LOAD='(1.0,-1.0)';
    'DDR6_SB_DQS_DP9':
      PIN_NUMBER='(0,0,0,0,0,0,0,0,0,0,0,0,0,DT36,0,0,0,0,0,0,0,0,0,0,0,0,0,0,0,0,0,0,0,0,0,0,0,0,0,0,0,0)';
      BIDIRECTIONAL='TRUE';
      INPUT_LOAD='(-0.01,0.01)';
      OUTPUT_LOAD='(1.0,-1.0)';
    'DDR6_SB_DQS_DP8':
      PIN_NUMBER='(0,0,0,0,0,0,0,0,0,0,0,0,0,EN5,0,0,0,0,0,0,0,0,0,0,0,0,0,0,0,0,0,0,0,0,0,0,0,0,0,0,0,0)';
      BIDIRECTIONAL='TRUE';
      INPUT_LOAD='(-0.01,0.01)';
      OUTPUT_LOAD='(1.0,-1.0)';
    'DDR6_SB_DQS_DP7':
      PIN_NUMBER='(0,0,0,0,0,0,0,0,0,0,0,0,0,DY24,0,0,0,0,0,0,0,0,0,0,0,0,0,0,0,0,0,0,0,0,0,0,0,0,0,0,0,0)';
      BIDIRECTIONAL='TRUE';
      INPUT_LOAD='(-0.01,0.01)';
      OUTPUT_LOAD='(1.0,-1.0)';
    'DDR6_SB_DQS_DP6':
      PIN_NUMBER='(0,0,0,0,0,0,0,0,0,0,0,0,0,DR27,0,0,0,0,0,0,0,0,0,0,0,0,0,0,0,0,0,0,0,0,0,0,0,0,0,0,0,0)';
      BIDIRECTIONAL='TRUE';
      INPUT_LOAD='(-0.01,0.01)';
      OUTPUT_LOAD='(1.0,-1.0)';
    'DDR6_SB_DQS_DP5':
      PIN_NUMBER='(0,0,0,0,0,0,0,0,0,0,0,0,0,DN33,0,0,0,0,0,0,0,0,0,0,0,0,0,0,0,0,0,0,0,0,0,0,0,0,0,0,0,0)';
      BIDIRECTIONAL='TRUE';
      INPUT_LOAD='(-0.01,0.01)';
      OUTPUT_LOAD='(1.0,-1.0)';
    'DDR6_SB_DQS_DP4':
      PIN_NUMBER='(0,0,0,0,0,0,0,0,0,0,0,0,0,DY36,0,0,0,0,0,0,0,0,0,0,0,0,0,0,0,0,0,0,0,0,0,0,0,0,0,0,0,0)';
      BIDIRECTIONAL='TRUE';
      INPUT_LOAD='(-0.01,0.01)';
      OUTPUT_LOAD='(1.0,-1.0)';
    'DDR6_SB_DQS_DP3':
      PIN_NUMBER='(0,0,0,0,0,0,0,0,0,0,0,0,0,EN7,0,0,0,0,0,0,0,0,0,0,0,0,0,0,0,0,0,0,0,0,0,0,0,0,0,0,0,0)';
      BIDIRECTIONAL='TRUE';
      INPUT_LOAD='(-0.01,0.01)';
      OUTPUT_LOAD='(1.0,-1.0)';
    'DDR6_SB_DQS_DP2':
      PIN_NUMBER='(0,0,0,0,0,0,0,0,0,0,0,0,0,DT24,0,0,0,0,0,0,0,0,0,0,0,0,0,0,0,0,0,0,0,0,0,0,0,0,0,0,0,0)';
      BIDIRECTIONAL='TRUE';
      INPUT_LOAD='(-0.01,0.01)';
      OUTPUT_LOAD='(1.0,-1.0)';
    'DDR6_SB_DQS_DP1':
      PIN_NUMBER='(0,0,0,0,0,0,0,0,0,0,0,0,0,DL27,0,0,0,0,0,0,0,0,0,0,0,0,0,0,0,0,0,0,0,0,0,0,0,0,0,0,0,0)';
      BIDIRECTIONAL='TRUE';
      INPUT_LOAD='(-0.01,0.01)';
      OUTPUT_LOAD='(1.0,-1.0)';
    'DDR6_SB_DQS_DP0':
      PIN_NUMBER='(0,0,0,0,0,0,0,0,0,0,0,0,0,DL33,0,0,0,0,0,0,0,0,0,0,0,0,0,0,0,0,0,0,0,0,0,0,0,0,0,0,0,0)';
      BIDIRECTIONAL='TRUE';
      INPUT_LOAD='(-0.01,0.01)';
      OUTPUT_LOAD='(1.0,-1.0)';
    'DDR6_SB_ECC7':
      PIN_NUMBER='(0,0,0,0,0,0,0,0,0,0,0,0,0,EA37,0,0,0,0,0,0,0,0,0,0,0,0,0,0,0,0,0,0,0,0,0,0,0,0,0,0,0,0)';
      BIDIRECTIONAL='TRUE';
      INPUT_LOAD='(-0.01,0.01)';
      OUTPUT_LOAD='(1.0,-1.0)';
    'DDR6_SB_ECC6':
      PIN_NUMBER='(0,0,0,0,0,0,0,0,0,0,0,0,0,DY38,0,0,0,0,0,0,0,0,0,0,0,0,0,0,0,0,0,0,0,0,0,0,0,0,0,0,0,0)';
      BIDIRECTIONAL='TRUE';
      INPUT_LOAD='(-0.01,0.01)';
      OUTPUT_LOAD='(1.0,-1.0)';
    'DDR6_SB_ECC5':
      PIN_NUMBER='(0,0,0,0,0,0,0,0,0,0,0,0,0,DU37,0,0,0,0,0,0,0,0,0,0,0,0,0,0,0,0,0,0,0,0,0,0,0,0,0,0,0,0)';
      BIDIRECTIONAL='TRUE';
      INPUT_LOAD='(-0.01,0.01)';
      OUTPUT_LOAD='(1.0,-1.0)';
    'DDR6_SB_ECC4':
      PIN_NUMBER='(0,0,0,0,0,0,0,0,0,0,0,0,0,DV38,0,0,0,0,0,0,0,0,0,0,0,0,0,0,0,0,0,0,0,0,0,0,0,0,0,0,0,0)';
      BIDIRECTIONAL='TRUE';
      INPUT_LOAD='(-0.01,0.01)';
      OUTPUT_LOAD='(1.0,-1.0)';
    'DDR6_SB_ECC3':
      PIN_NUMBER='(0,0,0,0,0,0,0,0,0,0,0,0,0,DY34,0,0,0,0,0,0,0,0,0,0,0,0,0,0,0,0,0,0,0,0,0,0,0,0,0,0,0,0)';
      BIDIRECTIONAL='TRUE';
      INPUT_LOAD='(-0.01,0.01)';
      OUTPUT_LOAD='(1.0,-1.0)';
    'DDR6_SB_ECC2':
      PIN_NUMBER='(0,0,0,0,0,0,0,0,0,0,0,0,0,EA35,0,0,0,0,0,0,0,0,0,0,0,0,0,0,0,0,0,0,0,0,0,0,0,0,0,0,0,0)';
      BIDIRECTIONAL='TRUE';
      INPUT_LOAD='(-0.01,0.01)';
      OUTPUT_LOAD='(1.0,-1.0)';
    'DDR6_SB_ECC1':
      PIN_NUMBER='(0,0,0,0,0,0,0,0,0,0,0,0,0,DV34,0,0,0,0,0,0,0,0,0,0,0,0,0,0,0,0,0,0,0,0,0,0,0,0,0,0,0,0)';
      BIDIRECTIONAL='TRUE';
      INPUT_LOAD='(-0.01,0.01)';
      OUTPUT_LOAD='(1.0,-1.0)';
    'DDR6_SB_ECC0':
      PIN_NUMBER='(0,0,0,0,0,0,0,0,0,0,0,0,0,DU35,0,0,0,0,0,0,0,0,0,0,0,0,0,0,0,0,0,0,0,0,0,0,0,0,0,0,0,0)';
      BIDIRECTIONAL='TRUE';
      INPUT_LOAD='(-0.01,0.01)';
      OUTPUT_LOAD='(1.0,-1.0)';
    'DDR6_SB_PAR':
      PIN_NUMBER='(0,0,0,0,0,0,0,0,0,0,0,0,0,EB42,0,0,0,0,0,0,0,0,0,0,0,0,0,0,0,0,0,0,0,0,0,0,0,0,0,0,0,0)';
      OUTPUT_LOAD='(1.0,-1.0)';
    '-DDR7_ALERT':
      PIN_NUMBER='(0,0,0,0,0,0,0,0,0,0,0,0,0,0,CY51,0,0,0,0,0,0,0,0,0,0,0,0,0,0,0,0,0,0,0,0,0,0,0,0,0,0,0)';
      INPUT_LOAD='(-0.01,0.01)';
    'DDR7_A_RSP1':
      PIN_NUMBER='(0,0,0,0,0,0,0,0,0,0,0,0,0,0,EH47,0,0,0,0,0,0,0,0,0,0,0,0,0,0,0,0,0,0,0,0,0,0,0,0,0,0,0)';
      INPUT_LOAD='(-0.01,0.01)';
    'DDR7_A_RSP0':
      PIN_NUMBER='(0,0,0,0,0,0,0,0,0,0,0,0,0,0,EG48,0,0,0,0,0,0,0,0,0,0,0,0,0,0,0,0,0,0,0,0,0,0,0,0,0,0,0)';
      INPUT_LOAD='(-0.01,0.01)';
    'DDR7_B_RSP1':
      PIN_NUMBER='(0,0,0,0,0,0,0,0,0,0,0,0,0,0,ED47,0,0,0,0,0,0,0,0,0,0,0,0,0,0,0,0,0,0,0,0,0,0,0,0,0,0,0)';
      INPUT_LOAD='(-0.01,0.01)';
    'DDR7_B_RSP0':
      PIN_NUMBER='(0,0,0,0,0,0,0,0,0,0,0,0,0,0,EE48,0,0,0,0,0,0,0,0,0,0,0,0,0,0,0,0,0,0,0,0,0,0,0,0,0,0,0)';
      INPUT_LOAD='(-0.01,0.01)';
    'DDR7_CLK_DN1':
      PIN_NUMBER='(0,0,0,0,0,0,0,0,0,0,0,0,0,0,DD42,0,0,0,0,0,0,0,0,0,0,0,0,0,0,0,0,0,0,0,0,0,0,0,0,0,0,0)';
      OUTPUT_LOAD='(1.0,-1.0)';
    'DDR7_CLK_DN0':
      PIN_NUMBER='(0,0,0,0,0,0,0,0,0,0,0,0,0,0,DH42,0,0,0,0,0,0,0,0,0,0,0,0,0,0,0,0,0,0,0,0,0,0,0,0,0,0,0)';
      OUTPUT_LOAD='(1.0,-1.0)';
    'DDR7_CLK_DP1':
      PIN_NUMBER='(0,0,0,0,0,0,0,0,0,0,0,0,0,0,DB42,0,0,0,0,0,0,0,0,0,0,0,0,0,0,0,0,0,0,0,0,0,0,0,0,0,0,0)';
      OUTPUT_LOAD='(1.0,-1.0)';
    'DDR7_CLK_DP0':
      PIN_NUMBER='(0,0,0,0,0,0,0,0,0,0,0,0,0,0,DF42,0,0,0,0,0,0,0,0,0,0,0,0,0,0,0,0,0,0,0,0,0,0,0,0,0,0,0)';
      OUTPUT_LOAD='(1.0,-1.0)';
    'DDR7_SA_CA6':
      PIN_NUMBER='(0,0,0,0,0,0,0,0,0,0,0,0,0,0,DC41,0,0,0,0,0,0,0,0,0,0,0,0,0,0,0,0,0,0,0,0,0,0,0,0,0,0,0)';
      OUTPUT_LOAD='(1.0,-1.0)';
    'DDR7_SA_CA5':
      PIN_NUMBER='(0,0,0,0,0,0,0,0,0,0,0,0,0,0,DF47,0,0,0,0,0,0,0,0,0,0,0,0,0,0,0,0,0,0,0,0,0,0,0,0,0,0,0)';
      OUTPUT_LOAD='(1.0,-1.0)';
    'DDR7_SA_CA4':
      PIN_NUMBER='(0,0,0,0,0,0,0,0,0,0,0,0,0,0,DD47,0,0,0,0,0,0,0,0,0,0,0,0,0,0,0,0,0,0,0,0,0,0,0,0,0,0,0)';
      OUTPUT_LOAD='(1.0,-1.0)';
    'DDR7_SA_CA3':
      PIN_NUMBER='(0,0,0,0,0,0,0,0,0,0,0,0,0,0,DG48,0,0,0,0,0,0,0,0,0,0,0,0,0,0,0,0,0,0,0,0,0,0,0,0,0,0,0)';
      OUTPUT_LOAD='(1.0,-1.0)';
    'DDR7_SA_CA2':
      PIN_NUMBER='(0,0,0,0,0,0,0,0,0,0,0,0,0,0,DC48,0,0,0,0,0,0,0,0,0,0,0,0,0,0,0,0,0,0,0,0,0,0,0,0,0,0,0)';
      OUTPUT_LOAD='(1.0,-1.0)';
    'DDR7_SA_CA1':
      PIN_NUMBER='(0,0,0,0,0,0,0,0,0,0,0,0,0,0,DH49,0,0,0,0,0,0,0,0,0,0,0,0,0,0,0,0,0,0,0,0,0,0,0,0,0,0,0)';
      OUTPUT_LOAD='(1.0,-1.0)';
    'DDR7_SA_CA0':
      PIN_NUMBER='(0,0,0,0,0,0,0,0,0,0,0,0,0,0,DB49,0,0,0,0,0,0,0,0,0,0,0,0,0,0,0,0,0,0,0,0,0,0,0,0,0,0,0)';
      OUTPUT_LOAD='(1.0,-1.0)';
    'DDR7_SA_CS_N3':
      PIN_NUMBER='(0,0,0,0,0,0,0,0,0,0,0,0,0,0,DC50,0,0,0,0,0,0,0,0,0,0,0,0,0,0,0,0,0,0,0,0,0,0,0,0,0,0,0)';
      OUTPUT_LOAD='(1.0,-1.0)';
    'DDR7_SA_CS_N2':
      PIN_NUMBER='(0,0,0,0,0,0,0,0,0,0,0,0,0,0,DD51,0,0,0,0,0,0,0,0,0,0,0,0,0,0,0,0,0,0,0,0,0,0,0,0,0,0,0)';
      OUTPUT_LOAD='(1.0,-1.0)';
    'DDR7_SA_CS_N1':
      PIN_NUMBER='(0,0,0,0,0,0,0,0,0,0,0,0,0,0,DG50,0,0,0,0,0,0,0,0,0,0,0,0,0,0,0,0,0,0,0,0,0,0,0,0,0,0,0)';
      OUTPUT_LOAD='(1.0,-1.0)';
    'DDR7_SA_CS_N0':
      PIN_NUMBER='(0,0,0,0,0,0,0,0,0,0,0,0,0,0,DF51,0,0,0,0,0,0,0,0,0,0,0,0,0,0,0,0,0,0,0,0,0,0,0,0,0,0,0)';
      OUTPUT_LOAD='(1.0,-1.0)';
    'DDR7_SA_DQ31':
      PIN_NUMBER='(0,0,0,0,0,0,0,0,0,0,0,0,0,0,DF59,0,0,0,0,0,0,0,0,0,0,0,0,0,0,0,0,0,0,0,0,0,0,0,0,0,0,0)';
      BIDIRECTIONAL='TRUE';
      INPUT_LOAD='(-0.01,0.01)';
      OUTPUT_LOAD='(1.0,-1.0)';
    'DDR7_SA_DQ30':
      PIN_NUMBER='(0,0,0,0,0,0,0,0,0,0,0,0,0,0,DG60,0,0,0,0,0,0,0,0,0,0,0,0,0,0,0,0,0,0,0,0,0,0,0,0,0,0,0)';
      BIDIRECTIONAL='TRUE';
      INPUT_LOAD='(-0.01,0.01)';
      OUTPUT_LOAD='(1.0,-1.0)';
    'DDR7_SA_DQ29':
      PIN_NUMBER='(0,0,0,0,0,0,0,0,0,0,0,0,0,0,DD59,0,0,0,0,0,0,0,0,0,0,0,0,0,0,0,0,0,0,0,0,0,0,0,0,0,0,0)';
      BIDIRECTIONAL='TRUE';
      INPUT_LOAD='(-0.01,0.01)';
      OUTPUT_LOAD='(1.0,-1.0)';
    'DDR7_SA_DQ28':
      PIN_NUMBER='(0,0,0,0,0,0,0,0,0,0,0,0,0,0,DC60,0,0,0,0,0,0,0,0,0,0,0,0,0,0,0,0,0,0,0,0,0,0,0,0,0,0,0)';
      BIDIRECTIONAL='TRUE';
      INPUT_LOAD='(-0.01,0.01)';
      OUTPUT_LOAD='(1.0,-1.0)';
    'DDR7_SA_DQ27':
      PIN_NUMBER='(0,0,0,0,0,0,0,0,0,0,0,0,0,0,DG62,0,0,0,0,0,0,0,0,0,0,0,0,0,0,0,0,0,0,0,0,0,0,0,0,0,0,0)';
      BIDIRECTIONAL='TRUE';
      INPUT_LOAD='(-0.01,0.01)';
      OUTPUT_LOAD='(1.0,-1.0)';
    'DDR7_SA_DQ26':
      PIN_NUMBER='(0,0,0,0,0,0,0,0,0,0,0,0,0,0,DF63,0,0,0,0,0,0,0,0,0,0,0,0,0,0,0,0,0,0,0,0,0,0,0,0,0,0,0)';
      BIDIRECTIONAL='TRUE';
      INPUT_LOAD='(-0.01,0.01)';
      OUTPUT_LOAD='(1.0,-1.0)';
    'DDR7_SA_DQ25':
      PIN_NUMBER='(0,0,0,0,0,0,0,0,0,0,0,0,0,0,DC62,0,0,0,0,0,0,0,0,0,0,0,0,0,0,0,0,0,0,0,0,0,0,0,0,0,0,0)';
      BIDIRECTIONAL='TRUE';
      INPUT_LOAD='(-0.01,0.01)';
      OUTPUT_LOAD='(1.0,-1.0)';
    'DDR7_SA_DQ24':
      PIN_NUMBER='(0,0,0,0,0,0,0,0,0,0,0,0,0,0,DD63,0,0,0,0,0,0,0,0,0,0,0,0,0,0,0,0,0,0,0,0,0,0,0,0,0,0,0)';
      BIDIRECTIONAL='TRUE';
      INPUT_LOAD='(-0.01,0.01)';
      OUTPUT_LOAD='(1.0,-1.0)';
    'DDR7_SA_DQ23':
      PIN_NUMBER='(0,0,0,0,0,0,0,0,0,0,0,0,0,0,DF65,0,0,0,0,0,0,0,0,0,0,0,0,0,0,0,0,0,0,0,0,0,0,0,0,0,0,0)';
      BIDIRECTIONAL='TRUE';
      INPUT_LOAD='(-0.01,0.01)';
      OUTPUT_LOAD='(1.0,-1.0)';
    'DDR7_SA_DQ22':
      PIN_NUMBER='(0,0,0,0,0,0,0,0,0,0,0,0,0,0,DG66,0,0,0,0,0,0,0,0,0,0,0,0,0,0,0,0,0,0,0,0,0,0,0,0,0,0,0)';
      BIDIRECTIONAL='TRUE';
      INPUT_LOAD='(-0.01,0.01)';
      OUTPUT_LOAD='(1.0,-1.0)';
    'DDR7_SA_DQ21':
      PIN_NUMBER='(0,0,0,0,0,0,0,0,0,0,0,0,0,0,DD65,0,0,0,0,0,0,0,0,0,0,0,0,0,0,0,0,0,0,0,0,0,0,0,0,0,0,0)';
      BIDIRECTIONAL='TRUE';
      INPUT_LOAD='(-0.01,0.01)';
      OUTPUT_LOAD='(1.0,-1.0)';
    'DDR7_SA_DQ20':
      PIN_NUMBER='(0,0,0,0,0,0,0,0,0,0,0,0,0,0,DC66,0,0,0,0,0,0,0,0,0,0,0,0,0,0,0,0,0,0,0,0,0,0,0,0,0,0,0)';
      BIDIRECTIONAL='TRUE';
      INPUT_LOAD='(-0.01,0.01)';
      OUTPUT_LOAD='(1.0,-1.0)';
    'DDR7_SA_DQ19':
      PIN_NUMBER='(0,0,0,0,0,0,0,0,0,0,0,0,0,0,DG68,0,0,0,0,0,0,0,0,0,0,0,0,0,0,0,0,0,0,0,0,0,0,0,0,0,0,0)';
      BIDIRECTIONAL='TRUE';
      INPUT_LOAD='(-0.01,0.01)';
      OUTPUT_LOAD='(1.0,-1.0)';
    'DDR7_SA_DQ18':
      PIN_NUMBER='(0,0,0,0,0,0,0,0,0,0,0,0,0,0,DF69,0,0,0,0,0,0,0,0,0,0,0,0,0,0,0,0,0,0,0,0,0,0,0,0,0,0,0)';
      BIDIRECTIONAL='TRUE';
      INPUT_LOAD='(-0.01,0.01)';
      OUTPUT_LOAD='(1.0,-1.0)';
    'DDR7_SA_DQ17':
      PIN_NUMBER='(0,0,0,0,0,0,0,0,0,0,0,0,0,0,DC68,0,0,0,0,0,0,0,0,0,0,0,0,0,0,0,0,0,0,0,0,0,0,0,0,0,0,0)';
      BIDIRECTIONAL='TRUE';
      INPUT_LOAD='(-0.01,0.01)';
      OUTPUT_LOAD='(1.0,-1.0)';
    'DDR7_SA_DQ16':
      PIN_NUMBER='(0,0,0,0,0,0,0,0,0,0,0,0,0,0,DD69,0,0,0,0,0,0,0,0,0,0,0,0,0,0,0,0,0,0,0,0,0,0,0,0,0,0,0)';
      BIDIRECTIONAL='TRUE';
      INPUT_LOAD='(-0.01,0.01)';
      OUTPUT_LOAD='(1.0,-1.0)';
    'DDR7_SA_DQ15':
      PIN_NUMBER='(0,0,0,0,0,0,0,0,0,0,0,0,0,0,DF71,0,0,0,0,0,0,0,0,0,0,0,0,0,0,0,0,0,0,0,0,0,0,0,0,0,0,0)';
      BIDIRECTIONAL='TRUE';
      INPUT_LOAD='(-0.01,0.01)';
      OUTPUT_LOAD='(1.0,-1.0)';
    'DDR7_SA_DQ14':
      PIN_NUMBER='(0,0,0,0,0,0,0,0,0,0,0,0,0,0,DG72,0,0,0,0,0,0,0,0,0,0,0,0,0,0,0,0,0,0,0,0,0,0,0,0,0,0,0)';
      BIDIRECTIONAL='TRUE';
      INPUT_LOAD='(-0.01,0.01)';
      OUTPUT_LOAD='(1.0,-1.0)';
    'DDR7_SA_DQ13':
      PIN_NUMBER='(0,0,0,0,0,0,0,0,0,0,0,0,0,0,DD71,0,0,0,0,0,0,0,0,0,0,0,0,0,0,0,0,0,0,0,0,0,0,0,0,0,0,0)';
      BIDIRECTIONAL='TRUE';
      INPUT_LOAD='(-0.01,0.01)';
      OUTPUT_LOAD='(1.0,-1.0)';
    'DDR7_SA_DQ12':
      PIN_NUMBER='(0,0,0,0,0,0,0,0,0,0,0,0,0,0,DC72,0,0,0,0,0,0,0,0,0,0,0,0,0,0,0,0,0,0,0,0,0,0,0,0,0,0,0)';
      BIDIRECTIONAL='TRUE';
      INPUT_LOAD='(-0.01,0.01)';
      OUTPUT_LOAD='(1.0,-1.0)';
    'DDR7_SA_DQ11':
      PIN_NUMBER='(0,0,0,0,0,0,0,0,0,0,0,0,0,0,DG74,0,0,0,0,0,0,0,0,0,0,0,0,0,0,0,0,0,0,0,0,0,0,0,0,0,0,0)';
      BIDIRECTIONAL='TRUE';
      INPUT_LOAD='(-0.01,0.01)';
      OUTPUT_LOAD='(1.0,-1.0)';
    'DDR7_SA_DQ10':
      PIN_NUMBER='(0,0,0,0,0,0,0,0,0,0,0,0,0,0,DF75,0,0,0,0,0,0,0,0,0,0,0,0,0,0,0,0,0,0,0,0,0,0,0,0,0,0,0)';
      BIDIRECTIONAL='TRUE';
      INPUT_LOAD='(-0.01,0.01)';
      OUTPUT_LOAD='(1.0,-1.0)';
    'DDR7_SA_DQ9':
      PIN_NUMBER='(0,0,0,0,0,0,0,0,0,0,0,0,0,0,DC74,0,0,0,0,0,0,0,0,0,0,0,0,0,0,0,0,0,0,0,0,0,0,0,0,0,0,0)';
      BIDIRECTIONAL='TRUE';
      INPUT_LOAD='(-0.01,0.01)';
      OUTPUT_LOAD='(1.0,-1.0)';
    'DDR7_SA_DQ8':
      PIN_NUMBER='(0,0,0,0,0,0,0,0,0,0,0,0,0,0,DD75,0,0,0,0,0,0,0,0,0,0,0,0,0,0,0,0,0,0,0,0,0,0,0,0,0,0,0)';
      BIDIRECTIONAL='TRUE';
      INPUT_LOAD='(-0.01,0.01)';
      OUTPUT_LOAD='(1.0,-1.0)';
    'DDR7_SA_DQ7':
      PIN_NUMBER='(0,0,0,0,0,0,0,0,0,0,0,0,0,0,DN74,0,0,0,0,0,0,0,0,0,0,0,0,0,0,0,0,0,0,0,0,0,0,0,0,0,0,0)';
      BIDIRECTIONAL='TRUE';
      INPUT_LOAD='(-0.01,0.01)';
      OUTPUT_LOAD='(1.0,-1.0)';
    'DDR7_SA_DQ6':
      PIN_NUMBER='(0,0,0,0,0,0,0,0,0,0,0,0,0,0,DP75,0,0,0,0,0,0,0,0,0,0,0,0,0,0,0,0,0,0,0,0,0,0,0,0,0,0,0)';
      BIDIRECTIONAL='TRUE';
      INPUT_LOAD='(-0.01,0.01)';
      OUTPUT_LOAD='(1.0,-1.0)';
    'DDR7_SA_DQ5':
      PIN_NUMBER='(0,0,0,0,0,0,0,0,0,0,0,0,0,0,DL74,0,0,0,0,0,0,0,0,0,0,0,0,0,0,0,0,0,0,0,0,0,0,0,0,0,0,0)';
      BIDIRECTIONAL='TRUE';
      INPUT_LOAD='(-0.01,0.01)';
      OUTPUT_LOAD='(1.0,-1.0)';
    'DDR7_SA_DQ4':
      PIN_NUMBER='(0,0,0,0,0,0,0,0,0,0,0,0,0,0,DK75,0,0,0,0,0,0,0,0,0,0,0,0,0,0,0,0,0,0,0,0,0,0,0,0,0,0,0)';
      BIDIRECTIONAL='TRUE';
      INPUT_LOAD='(-0.01,0.01)';
      OUTPUT_LOAD='(1.0,-1.0)';
    'DDR7_SA_DQ3':
      PIN_NUMBER='(0,0,0,0,0,0,0,0,0,0,0,0,0,0,DP77,0,0,0,0,0,0,0,0,0,0,0,0,0,0,0,0,0,0,0,0,0,0,0,0,0,0,0)';
      BIDIRECTIONAL='TRUE';
      INPUT_LOAD='(-0.01,0.01)';
      OUTPUT_LOAD='(1.0,-1.0)';
    'DDR7_SA_DQ2':
      PIN_NUMBER='(0,0,0,0,0,0,0,0,0,0,0,0,0,0,DW78,0,0,0,0,0,0,0,0,0,0,0,0,0,0,0,0,0,0,0,0,0,0,0,0,0,0,0)';
      BIDIRECTIONAL='TRUE';
      INPUT_LOAD='(-0.01,0.01)';
      OUTPUT_LOAD='(1.0,-1.0)';
    'DDR7_SA_DQ1':
      PIN_NUMBER='(0,0,0,0,0,0,0,0,0,0,0,0,0,0,DT77,0,0,0,0,0,0,0,0,0,0,0,0,0,0,0,0,0,0,0,0,0,0,0,0,0,0,0)';
      BIDIRECTIONAL='TRUE';
      INPUT_LOAD='(-0.01,0.01)';
      OUTPUT_LOAD='(1.0,-1.0)';
    'DDR7_SA_DQ0':
      PIN_NUMBER='(0,0,0,0,0,0,0,0,0,0,0,0,0,0,DY79,0,0,0,0,0,0,0,0,0,0,0,0,0,0,0,0,0,0,0,0,0,0,0,0,0,0,0)';
      BIDIRECTIONAL='TRUE';
      INPUT_LOAD='(-0.01,0.01)';
      OUTPUT_LOAD='(1.0,-1.0)';
    'DDR7_SA_DQS_DN9':
      PIN_NUMBER='(0,0,0,0,0,0,0,0,0,0,0,0,0,0,DH55,0,0,0,0,0,0,0,0,0,0,0,0,0,0,0,0,0,0,0,0,0,0,0,0,0,0,0)';
      BIDIRECTIONAL='TRUE';
      INPUT_LOAD='(-0.01,0.01)';
      OUTPUT_LOAD='(1.0,-1.0)';
    'DDR7_SA_DQS_DN8':
      PIN_NUMBER='(0,0,0,0,0,0,0,0,0,0,0,0,0,0,DH61,0,0,0,0,0,0,0,0,0,0,0,0,0,0,0,0,0,0,0,0,0,0,0,0,0,0,0)';
      BIDIRECTIONAL='TRUE';
      INPUT_LOAD='(-0.01,0.01)';
      OUTPUT_LOAD='(1.0,-1.0)';
    'DDR7_SA_DQS_DN7':
      PIN_NUMBER='(0,0,0,0,0,0,0,0,0,0,0,0,0,0,DH67,0,0,0,0,0,0,0,0,0,0,0,0,0,0,0,0,0,0,0,0,0,0,0,0,0,0,0)';
      BIDIRECTIONAL='TRUE';
      INPUT_LOAD='(-0.01,0.01)';
      OUTPUT_LOAD='(1.0,-1.0)';
    'DDR7_SA_DQS_DN6':
      PIN_NUMBER='(0,0,0,0,0,0,0,0,0,0,0,0,0,0,DH73,0,0,0,0,0,0,0,0,0,0,0,0,0,0,0,0,0,0,0,0,0,0,0,0,0,0,0)';
      BIDIRECTIONAL='TRUE';
      INPUT_LOAD='(-0.01,0.01)';
      OUTPUT_LOAD='(1.0,-1.0)';
    'DDR7_SA_DQS_DN5':
      PIN_NUMBER='(0,0,0,0,0,0,0,0,0,0,0,0,0,0,DR76,0,0,0,0,0,0,0,0,0,0,0,0,0,0,0,0,0,0,0,0,0,0,0,0,0,0,0)';
      BIDIRECTIONAL='TRUE';
      INPUT_LOAD='(-0.01,0.01)';
      OUTPUT_LOAD='(1.0,-1.0)';
    'DDR7_SA_DQS_DN4':
      PIN_NUMBER='(0,0,0,0,0,0,0,0,0,0,0,0,0,0,DD55,0,0,0,0,0,0,0,0,0,0,0,0,0,0,0,0,0,0,0,0,0,0,0,0,0,0,0)';
      BIDIRECTIONAL='TRUE';
      INPUT_LOAD='(-0.01,0.01)';
      OUTPUT_LOAD='(1.0,-1.0)';
    'DDR7_SA_DQS_DN3':
      PIN_NUMBER='(0,0,0,0,0,0,0,0,0,0,0,0,0,0,DD61,0,0,0,0,0,0,0,0,0,0,0,0,0,0,0,0,0,0,0,0,0,0,0,0,0,0,0)';
      BIDIRECTIONAL='TRUE';
      INPUT_LOAD='(-0.01,0.01)';
      OUTPUT_LOAD='(1.0,-1.0)';
    'DDR7_SA_DQS_DN2':
      PIN_NUMBER='(0,0,0,0,0,0,0,0,0,0,0,0,0,0,DD67,0,0,0,0,0,0,0,0,0,0,0,0,0,0,0,0,0,0,0,0,0,0,0,0,0,0,0)';
      BIDIRECTIONAL='TRUE';
      INPUT_LOAD='(-0.01,0.01)';
      OUTPUT_LOAD='(1.0,-1.0)';
    'DDR7_SA_DQS_DN1':
      PIN_NUMBER='(0,0,0,0,0,0,0,0,0,0,0,0,0,0,DB73,0,0,0,0,0,0,0,0,0,0,0,0,0,0,0,0,0,0,0,0,0,0,0,0,0,0,0)';
      BIDIRECTIONAL='TRUE';
      INPUT_LOAD='(-0.01,0.01)';
      OUTPUT_LOAD='(1.0,-1.0)';
    'DDR7_SA_DQS_DN0':
      PIN_NUMBER='(0,0,0,0,0,0,0,0,0,0,0,0,0,0,DJ76,0,0,0,0,0,0,0,0,0,0,0,0,0,0,0,0,0,0,0,0,0,0,0,0,0,0,0)';
      BIDIRECTIONAL='TRUE';
      INPUT_LOAD='(-0.01,0.01)';
      OUTPUT_LOAD='(1.0,-1.0)';
    'DDR7_SA_DQS_DP9':
      PIN_NUMBER='(0,0,0,0,0,0,0,0,0,0,0,0,0,0,DF55,0,0,0,0,0,0,0,0,0,0,0,0,0,0,0,0,0,0,0,0,0,0,0,0,0,0,0)';
      BIDIRECTIONAL='TRUE';
      INPUT_LOAD='(-0.01,0.01)';
      OUTPUT_LOAD='(1.0,-1.0)';
    'DDR7_SA_DQS_DP8':
      PIN_NUMBER='(0,0,0,0,0,0,0,0,0,0,0,0,0,0,DF61,0,0,0,0,0,0,0,0,0,0,0,0,0,0,0,0,0,0,0,0,0,0,0,0,0,0,0)';
      BIDIRECTIONAL='TRUE';
      INPUT_LOAD='(-0.01,0.01)';
      OUTPUT_LOAD='(1.0,-1.0)';
    'DDR7_SA_DQS_DP7':
      PIN_NUMBER='(0,0,0,0,0,0,0,0,0,0,0,0,0,0,DF67,0,0,0,0,0,0,0,0,0,0,0,0,0,0,0,0,0,0,0,0,0,0,0,0,0,0,0)';
      BIDIRECTIONAL='TRUE';
      INPUT_LOAD='(-0.01,0.01)';
      OUTPUT_LOAD='(1.0,-1.0)';
    'DDR7_SA_DQS_DP6':
      PIN_NUMBER='(0,0,0,0,0,0,0,0,0,0,0,0,0,0,DF73,0,0,0,0,0,0,0,0,0,0,0,0,0,0,0,0,0,0,0,0,0,0,0,0,0,0,0)';
      BIDIRECTIONAL='TRUE';
      INPUT_LOAD='(-0.01,0.01)';
      OUTPUT_LOAD='(1.0,-1.0)';
    'DDR7_SA_DQS_DP5':
      PIN_NUMBER='(0,0,0,0,0,0,0,0,0,0,0,0,0,0,DN76,0,0,0,0,0,0,0,0,0,0,0,0,0,0,0,0,0,0,0,0,0,0,0,0,0,0,0)';
      BIDIRECTIONAL='TRUE';
      INPUT_LOAD='(-0.01,0.01)';
      OUTPUT_LOAD='(1.0,-1.0)';
    'DDR7_SA_DQS_DP4':
      PIN_NUMBER='(0,0,0,0,0,0,0,0,0,0,0,0,0,0,DB55,0,0,0,0,0,0,0,0,0,0,0,0,0,0,0,0,0,0,0,0,0,0,0,0,0,0,0)';
      BIDIRECTIONAL='TRUE';
      INPUT_LOAD='(-0.01,0.01)';
      OUTPUT_LOAD='(1.0,-1.0)';
    'DDR7_SA_DQS_DP3':
      PIN_NUMBER='(0,0,0,0,0,0,0,0,0,0,0,0,0,0,DB61,0,0,0,0,0,0,0,0,0,0,0,0,0,0,0,0,0,0,0,0,0,0,0,0,0,0,0)';
      BIDIRECTIONAL='TRUE';
      INPUT_LOAD='(-0.01,0.01)';
      OUTPUT_LOAD='(1.0,-1.0)';
    'DDR7_SA_DQS_DP2':
      PIN_NUMBER='(0,0,0,0,0,0,0,0,0,0,0,0,0,0,DB67,0,0,0,0,0,0,0,0,0,0,0,0,0,0,0,0,0,0,0,0,0,0,0,0,0,0,0)';
      BIDIRECTIONAL='TRUE';
      INPUT_LOAD='(-0.01,0.01)';
      OUTPUT_LOAD='(1.0,-1.0)';
    'DDR7_SA_DQS_DP1':
      PIN_NUMBER='(0,0,0,0,0,0,0,0,0,0,0,0,0,0,DD73,0,0,0,0,0,0,0,0,0,0,0,0,0,0,0,0,0,0,0,0,0,0,0,0,0,0,0)';
      BIDIRECTIONAL='TRUE';
      INPUT_LOAD='(-0.01,0.01)';
      OUTPUT_LOAD='(1.0,-1.0)';
    'DDR7_SA_DQS_DP0':
      PIN_NUMBER='(0,0,0,0,0,0,0,0,0,0,0,0,0,0,DL76,0,0,0,0,0,0,0,0,0,0,0,0,0,0,0,0,0,0,0,0,0,0,0,0,0,0,0)';
      BIDIRECTIONAL='TRUE';
      INPUT_LOAD='(-0.01,0.01)';
      OUTPUT_LOAD='(1.0,-1.0)';
    'DDR7_SA_ECC7':
      PIN_NUMBER='(0,0,0,0,0,0,0,0,0,0,0,0,0,0,DF53,0,0,0,0,0,0,0,0,0,0,0,0,0,0,0,0,0,0,0,0,0,0,0,0,0,0,0)';
      BIDIRECTIONAL='TRUE';
      INPUT_LOAD='(-0.01,0.01)';
      OUTPUT_LOAD='(1.0,-1.0)';
    'DDR7_SA_ECC6':
      PIN_NUMBER='(0,0,0,0,0,0,0,0,0,0,0,0,0,0,DG54,0,0,0,0,0,0,0,0,0,0,0,0,0,0,0,0,0,0,0,0,0,0,0,0,0,0,0)';
      BIDIRECTIONAL='TRUE';
      INPUT_LOAD='(-0.01,0.01)';
      OUTPUT_LOAD='(1.0,-1.0)';
    'DDR7_SA_ECC5':
      PIN_NUMBER='(0,0,0,0,0,0,0,0,0,0,0,0,0,0,DD53,0,0,0,0,0,0,0,0,0,0,0,0,0,0,0,0,0,0,0,0,0,0,0,0,0,0,0)';
      BIDIRECTIONAL='TRUE';
      INPUT_LOAD='(-0.01,0.01)';
      OUTPUT_LOAD='(1.0,-1.0)';
    'DDR7_SA_ECC4':
      PIN_NUMBER='(0,0,0,0,0,0,0,0,0,0,0,0,0,0,DC54,0,0,0,0,0,0,0,0,0,0,0,0,0,0,0,0,0,0,0,0,0,0,0,0,0,0,0)';
      BIDIRECTIONAL='TRUE';
      INPUT_LOAD='(-0.01,0.01)';
      OUTPUT_LOAD='(1.0,-1.0)';
    'DDR7_SA_ECC3':
      PIN_NUMBER='(0,0,0,0,0,0,0,0,0,0,0,0,0,0,DG56,0,0,0,0,0,0,0,0,0,0,0,0,0,0,0,0,0,0,0,0,0,0,0,0,0,0,0)';
      BIDIRECTIONAL='TRUE';
      INPUT_LOAD='(-0.01,0.01)';
      OUTPUT_LOAD='(1.0,-1.0)';
    'DDR7_SA_ECC2':
      PIN_NUMBER='(0,0,0,0,0,0,0,0,0,0,0,0,0,0,DF57,0,0,0,0,0,0,0,0,0,0,0,0,0,0,0,0,0,0,0,0,0,0,0,0,0,0,0)';
      BIDIRECTIONAL='TRUE';
      INPUT_LOAD='(-0.01,0.01)';
      OUTPUT_LOAD='(1.0,-1.0)';
    'DDR7_SA_ECC1':
      PIN_NUMBER='(0,0,0,0,0,0,0,0,0,0,0,0,0,0,DC56,0,0,0,0,0,0,0,0,0,0,0,0,0,0,0,0,0,0,0,0,0,0,0,0,0,0,0)';
      BIDIRECTIONAL='TRUE';
      INPUT_LOAD='(-0.01,0.01)';
      OUTPUT_LOAD='(1.0,-1.0)';
    'DDR7_SA_ECC0':
      PIN_NUMBER='(0,0,0,0,0,0,0,0,0,0,0,0,0,0,DD57,0,0,0,0,0,0,0,0,0,0,0,0,0,0,0,0,0,0,0,0,0,0,0,0,0,0,0)';
      BIDIRECTIONAL='TRUE';
      INPUT_LOAD='(-0.01,0.01)';
      OUTPUT_LOAD='(1.0,-1.0)';
    'DDR7_SA_PAR':
      PIN_NUMBER='(0,0,0,0,0,0,0,0,0,0,0,0,0,0,DD40,0,0,0,0,0,0,0,0,0,0,0,0,0,0,0,0,0,0,0,0,0,0,0,0,0,0,0)';
      OUTPUT_LOAD='(1.0,-1.0)';
    'DDR7_SB_CA6':
      PIN_NUMBER='(0,0,0,0,0,0,0,0,0,0,0,0,0,0,DJ39,0,0,0,0,0,0,0,0,0,0,0,0,0,0,0,0,0,0,0,0,0,0,0,0,0,0,0)';
      OUTPUT_LOAD='(1.0,-1.0)';
    'DDR7_SB_CA5':
      PIN_NUMBER='(0,0,0,0,0,0,0,0,0,0,0,0,0,0,DP40,0,0,0,0,0,0,0,0,0,0,0,0,0,0,0,0,0,0,0,0,0,0,0,0,0,0,0)';
      OUTPUT_LOAD='(1.0,-1.0)';
    'DDR7_SB_CA4':
      PIN_NUMBER='(0,0,0,0,0,0,0,0,0,0,0,0,0,0,DK40,0,0,0,0,0,0,0,0,0,0,0,0,0,0,0,0,0,0,0,0,0,0,0,0,0,0,0)';
      OUTPUT_LOAD='(1.0,-1.0)';
    'DDR7_SB_CA3':
      PIN_NUMBER='(0,0,0,0,0,0,0,0,0,0,0,0,0,0,DN41,0,0,0,0,0,0,0,0,0,0,0,0,0,0,0,0,0,0,0,0,0,0,0,0,0,0,0)';
      OUTPUT_LOAD='(1.0,-1.0)';
    'DDR7_SB_CA2':
      PIN_NUMBER='(0,0,0,0,0,0,0,0,0,0,0,0,0,0,DL41,0,0,0,0,0,0,0,0,0,0,0,0,0,0,0,0,0,0,0,0,0,0,0,0,0,0,0)';
      OUTPUT_LOAD='(1.0,-1.0)';
    'DDR7_SB_CA1':
      PIN_NUMBER='(0,0,0,0,0,0,0,0,0,0,0,0,0,0,DG41,0,0,0,0,0,0,0,0,0,0,0,0,0,0,0,0,0,0,0,0,0,0,0,0,0,0,0)';
      OUTPUT_LOAD='(1.0,-1.0)';
    'DDR7_SB_CA0':
      PIN_NUMBER='(0,0,0,0,0,0,0,0,0,0,0,0,0,0,DF40,0,0,0,0,0,0,0,0,0,0,0,0,0,0,0,0,0,0,0,0,0,0,0,0,0,0,0)';
      OUTPUT_LOAD='(1.0,-1.0)';
    'DDR7_SB_CS_N3':
      PIN_NUMBER='(0,0,0,0,0,0,0,0,0,0,0,0,0,0,DP38,0,0,0,0,0,0,0,0,0,0,0,0,0,0,0,0,0,0,0,0,0,0,0,0,0,0,0)';
      OUTPUT_LOAD='(1.0,-1.0)';
    'DDR7_SB_CS_N2':
      PIN_NUMBER='(0,0,0,0,0,0,0,0,0,0,0,0,0,0,DK38,0,0,0,0,0,0,0,0,0,0,0,0,0,0,0,0,0,0,0,0,0,0,0,0,0,0,0)';
      OUTPUT_LOAD='(1.0,-1.0)';
    'DDR7_SB_CS_N1':
      PIN_NUMBER='(0,0,0,0,0,0,0,0,0,0,0,0,0,0,DN37,0,0,0,0,0,0,0,0,0,0,0,0,0,0,0,0,0,0,0,0,0,0,0,0,0,0,0)';
      OUTPUT_LOAD='(1.0,-1.0)';
    'DDR7_SB_CS_N0':
      PIN_NUMBER='(0,0,0,0,0,0,0,0,0,0,0,0,0,0,DL37,0,0,0,0,0,0,0,0,0,0,0,0,0,0,0,0,0,0,0,0,0,0,0,0,0,0,0)';
      OUTPUT_LOAD='(1.0,-1.0)';
    'DDR7_SB_DQ31':
      PIN_NUMBER='(0,0,0,0,0,0,0,0,0,0,0,0,0,0,DC17,0,0,0,0,0,0,0,0,0,0,0,0,0,0,0,0,0,0,0,0,0,0,0,0,0,0,0)';
      BIDIRECTIONAL='TRUE';
      INPUT_LOAD='(-0.01,0.01)';
      OUTPUT_LOAD='(1.0,-1.0)';
    'DDR7_SB_DQ30':
      PIN_NUMBER='(0,0,0,0,0,0,0,0,0,0,0,0,0,0,DJ17,0,0,0,0,0,0,0,0,0,0,0,0,0,0,0,0,0,0,0,0,0,0,0,0,0,0,0)';
      BIDIRECTIONAL='TRUE';
      INPUT_LOAD='(-0.01,0.01)';
      OUTPUT_LOAD='(1.0,-1.0)';
    'DDR7_SB_DQ29':
      PIN_NUMBER='(0,0,0,0,0,0,0,0,0,0,0,0,0,0,DA17,0,0,0,0,0,0,0,0,0,0,0,0,0,0,0,0,0,0,0,0,0,0,0,0,0,0,0)';
      BIDIRECTIONAL='TRUE';
      INPUT_LOAD='(-0.01,0.01)';
      OUTPUT_LOAD='(1.0,-1.0)';
    'DDR7_SB_DQ28':
      PIN_NUMBER='(0,0,0,0,0,0,0,0,0,0,0,0,0,0,DG17,0,0,0,0,0,0,0,0,0,0,0,0,0,0,0,0,0,0,0,0,0,0,0,0,0,0,0)';
      BIDIRECTIONAL='TRUE';
      INPUT_LOAD='(-0.01,0.01)';
      OUTPUT_LOAD='(1.0,-1.0)';
    'DDR7_SB_DQ27':
      PIN_NUMBER='(0,0,0,0,0,0,0,0,0,0,0,0,0,0,DG19,0,0,0,0,0,0,0,0,0,0,0,0,0,0,0,0,0,0,0,0,0,0,0,0,0,0,0)';
      BIDIRECTIONAL='TRUE';
      INPUT_LOAD='(-0.01,0.01)';
      OUTPUT_LOAD='(1.0,-1.0)';
    'DDR7_SB_DQ26':
      PIN_NUMBER='(0,0,0,0,0,0,0,0,0,0,0,0,0,0,DF20,0,0,0,0,0,0,0,0,0,0,0,0,0,0,0,0,0,0,0,0,0,0,0,0,0,0,0)';
      BIDIRECTIONAL='TRUE';
      INPUT_LOAD='(-0.01,0.01)';
      OUTPUT_LOAD='(1.0,-1.0)';
    'DDR7_SB_DQ25':
      PIN_NUMBER='(0,0,0,0,0,0,0,0,0,0,0,0,0,0,DC19,0,0,0,0,0,0,0,0,0,0,0,0,0,0,0,0,0,0,0,0,0,0,0,0,0,0,0)';
      BIDIRECTIONAL='TRUE';
      INPUT_LOAD='(-0.01,0.01)';
      OUTPUT_LOAD='(1.0,-1.0)';
    'DDR7_SB_DQ24':
      PIN_NUMBER='(0,0,0,0,0,0,0,0,0,0,0,0,0,0,DD20,0,0,0,0,0,0,0,0,0,0,0,0,0,0,0,0,0,0,0,0,0,0,0,0,0,0,0)';
      BIDIRECTIONAL='TRUE';
      INPUT_LOAD='(-0.01,0.01)';
      OUTPUT_LOAD='(1.0,-1.0)';
    'DDR7_SB_DQ23':
      PIN_NUMBER='(0,0,0,0,0,0,0,0,0,0,0,0,0,0,DN19,0,0,0,0,0,0,0,0,0,0,0,0,0,0,0,0,0,0,0,0,0,0,0,0,0,0,0)';
      BIDIRECTIONAL='TRUE';
      INPUT_LOAD='(-0.01,0.01)';
      OUTPUT_LOAD='(1.0,-1.0)';
    'DDR7_SB_DQ22':
      PIN_NUMBER='(0,0,0,0,0,0,0,0,0,0,0,0,0,0,DP20,0,0,0,0,0,0,0,0,0,0,0,0,0,0,0,0,0,0,0,0,0,0,0,0,0,0,0)';
      BIDIRECTIONAL='TRUE';
      INPUT_LOAD='(-0.01,0.01)';
      OUTPUT_LOAD='(1.0,-1.0)';
    'DDR7_SB_DQ21':
      PIN_NUMBER='(0,0,0,0,0,0,0,0,0,0,0,0,0,0,DL19,0,0,0,0,0,0,0,0,0,0,0,0,0,0,0,0,0,0,0,0,0,0,0,0,0,0,0)';
      BIDIRECTIONAL='TRUE';
      INPUT_LOAD='(-0.01,0.01)';
      OUTPUT_LOAD='(1.0,-1.0)';
    'DDR7_SB_DQ20':
      PIN_NUMBER='(0,0,0,0,0,0,0,0,0,0,0,0,0,0,DK20,0,0,0,0,0,0,0,0,0,0,0,0,0,0,0,0,0,0,0,0,0,0,0,0,0,0,0)';
      BIDIRECTIONAL='TRUE';
      INPUT_LOAD='(-0.01,0.01)';
      OUTPUT_LOAD='(1.0,-1.0)';
    'DDR7_SB_DQ19':
      PIN_NUMBER='(0,0,0,0,0,0,0,0,0,0,0,0,0,0,DP22,0,0,0,0,0,0,0,0,0,0,0,0,0,0,0,0,0,0,0,0,0,0,0,0,0,0,0)';
      BIDIRECTIONAL='TRUE';
      INPUT_LOAD='(-0.01,0.01)';
      OUTPUT_LOAD='(1.0,-1.0)';
    'DDR7_SB_DQ18':
      PIN_NUMBER='(0,0,0,0,0,0,0,0,0,0,0,0,0,0,DN23,0,0,0,0,0,0,0,0,0,0,0,0,0,0,0,0,0,0,0,0,0,0,0,0,0,0,0)';
      BIDIRECTIONAL='TRUE';
      INPUT_LOAD='(-0.01,0.01)';
      OUTPUT_LOAD='(1.0,-1.0)';
    'DDR7_SB_DQ17':
      PIN_NUMBER='(0,0,0,0,0,0,0,0,0,0,0,0,0,0,DK22,0,0,0,0,0,0,0,0,0,0,0,0,0,0,0,0,0,0,0,0,0,0,0,0,0,0,0)';
      BIDIRECTIONAL='TRUE';
      INPUT_LOAD='(-0.01,0.01)';
      OUTPUT_LOAD='(1.0,-1.0)';
    'DDR7_SB_DQ16':
      PIN_NUMBER='(0,0,0,0,0,0,0,0,0,0,0,0,0,0,DL23,0,0,0,0,0,0,0,0,0,0,0,0,0,0,0,0,0,0,0,0,0,0,0,0,0,0,0)';
      BIDIRECTIONAL='TRUE';
      INPUT_LOAD='(-0.01,0.01)';
      OUTPUT_LOAD='(1.0,-1.0)';
    'DDR7_SB_DQ15':
      PIN_NUMBER='(0,0,0,0,0,0,0,0,0,0,0,0,0,0,DF22,0,0,0,0,0,0,0,0,0,0,0,0,0,0,0,0,0,0,0,0,0,0,0,0,0,0,0)';
      BIDIRECTIONAL='TRUE';
      INPUT_LOAD='(-0.01,0.01)';
      OUTPUT_LOAD='(1.0,-1.0)';
    'DDR7_SB_DQ14':
      PIN_NUMBER='(0,0,0,0,0,0,0,0,0,0,0,0,0,0,DG23,0,0,0,0,0,0,0,0,0,0,0,0,0,0,0,0,0,0,0,0,0,0,0,0,0,0,0)';
      BIDIRECTIONAL='TRUE';
      INPUT_LOAD='(-0.01,0.01)';
      OUTPUT_LOAD='(1.0,-1.0)';
    'DDR7_SB_DQ13':
      PIN_NUMBER='(0,0,0,0,0,0,0,0,0,0,0,0,0,0,DD22,0,0,0,0,0,0,0,0,0,0,0,0,0,0,0,0,0,0,0,0,0,0,0,0,0,0,0)';
      BIDIRECTIONAL='TRUE';
      INPUT_LOAD='(-0.01,0.01)';
      OUTPUT_LOAD='(1.0,-1.0)';
    'DDR7_SB_DQ12':
      PIN_NUMBER='(0,0,0,0,0,0,0,0,0,0,0,0,0,0,DC23,0,0,0,0,0,0,0,0,0,0,0,0,0,0,0,0,0,0,0,0,0,0,0,0,0,0,0)';
      BIDIRECTIONAL='TRUE';
      INPUT_LOAD='(-0.01,0.01)';
      OUTPUT_LOAD='(1.0,-1.0)';
    'DDR7_SB_DQ11':
      PIN_NUMBER='(0,0,0,0,0,0,0,0,0,0,0,0,0,0,DG25,0,0,0,0,0,0,0,0,0,0,0,0,0,0,0,0,0,0,0,0,0,0,0,0,0,0,0)';
      BIDIRECTIONAL='TRUE';
      INPUT_LOAD='(-0.01,0.01)';
      OUTPUT_LOAD='(1.0,-1.0)';
    'DDR7_SB_DQ10':
      PIN_NUMBER='(0,0,0,0,0,0,0,0,0,0,0,0,0,0,DF26,0,0,0,0,0,0,0,0,0,0,0,0,0,0,0,0,0,0,0,0,0,0,0,0,0,0,0)';
      BIDIRECTIONAL='TRUE';
      INPUT_LOAD='(-0.01,0.01)';
      OUTPUT_LOAD='(1.0,-1.0)';
    'DDR7_SB_DQ9':
      PIN_NUMBER='(0,0,0,0,0,0,0,0,0,0,0,0,0,0,DC25,0,0,0,0,0,0,0,0,0,0,0,0,0,0,0,0,0,0,0,0,0,0,0,0,0,0,0)';
      BIDIRECTIONAL='TRUE';
      INPUT_LOAD='(-0.01,0.01)';
      OUTPUT_LOAD='(1.0,-1.0)';
    'DDR7_SB_DQ8':
      PIN_NUMBER='(0,0,0,0,0,0,0,0,0,0,0,0,0,0,DD26,0,0,0,0,0,0,0,0,0,0,0,0,0,0,0,0,0,0,0,0,0,0,0,0,0,0,0)';
      BIDIRECTIONAL='TRUE';
      INPUT_LOAD='(-0.01,0.01)';
      OUTPUT_LOAD='(1.0,-1.0)';
    'DDR7_SB_DQ7':
      PIN_NUMBER='(0,0,0,0,0,0,0,0,0,0,0,0,0,0,DD28,0,0,0,0,0,0,0,0,0,0,0,0,0,0,0,0,0,0,0,0,0,0,0,0,0,0,0)';
      BIDIRECTIONAL='TRUE';
      INPUT_LOAD='(-0.01,0.01)';
      OUTPUT_LOAD='(1.0,-1.0)';
    'DDR7_SB_DQ6':
      PIN_NUMBER='(0,0,0,0,0,0,0,0,0,0,0,0,0,0,DG29,0,0,0,0,0,0,0,0,0,0,0,0,0,0,0,0,0,0,0,0,0,0,0,0,0,0,0)';
      BIDIRECTIONAL='TRUE';
      INPUT_LOAD='(-0.01,0.01)';
      OUTPUT_LOAD='(1.0,-1.0)';
    'DDR7_SB_DQ5':
      PIN_NUMBER='(0,0,0,0,0,0,0,0,0,0,0,0,0,0,DF28,0,0,0,0,0,0,0,0,0,0,0,0,0,0,0,0,0,0,0,0,0,0,0,0,0,0,0)';
      BIDIRECTIONAL='TRUE';
      INPUT_LOAD='(-0.01,0.01)';
      OUTPUT_LOAD='(1.0,-1.0)';
    'DDR7_SB_DQ4':
      PIN_NUMBER='(0,0,0,0,0,0,0,0,0,0,0,0,0,0,DC29,0,0,0,0,0,0,0,0,0,0,0,0,0,0,0,0,0,0,0,0,0,0,0,0,0,0,0)';
      BIDIRECTIONAL='TRUE';
      INPUT_LOAD='(-0.01,0.01)';
      OUTPUT_LOAD='(1.0,-1.0)';
    'DDR7_SB_DQ3':
      PIN_NUMBER='(0,0,0,0,0,0,0,0,0,0,0,0,0,0,DG31,0,0,0,0,0,0,0,0,0,0,0,0,0,0,0,0,0,0,0,0,0,0,0,0,0,0,0)';
      BIDIRECTIONAL='TRUE';
      INPUT_LOAD='(-0.01,0.01)';
      OUTPUT_LOAD='(1.0,-1.0)';
    'DDR7_SB_DQ2':
      PIN_NUMBER='(0,0,0,0,0,0,0,0,0,0,0,0,0,0,DF32,0,0,0,0,0,0,0,0,0,0,0,0,0,0,0,0,0,0,0,0,0,0,0,0,0,0,0)';
      BIDIRECTIONAL='TRUE';
      INPUT_LOAD='(-0.01,0.01)';
      OUTPUT_LOAD='(1.0,-1.0)';
    'DDR7_SB_DQ1':
      PIN_NUMBER='(0,0,0,0,0,0,0,0,0,0,0,0,0,0,DC31,0,0,0,0,0,0,0,0,0,0,0,0,0,0,0,0,0,0,0,0,0,0,0,0,0,0,0)';
      BIDIRECTIONAL='TRUE';
      INPUT_LOAD='(-0.01,0.01)';
      OUTPUT_LOAD='(1.0,-1.0)';
    'DDR7_SB_DQ0':
      PIN_NUMBER='(0,0,0,0,0,0,0,0,0,0,0,0,0,0,DD32,0,0,0,0,0,0,0,0,0,0,0,0,0,0,0,0,0,0,0,0,0,0,0,0,0,0,0)';
      BIDIRECTIONAL='TRUE';
      INPUT_LOAD='(-0.01,0.01)';
      OUTPUT_LOAD='(1.0,-1.0)';
    'DDR7_SB_DQS_DN9':
      PIN_NUMBER='(0,0,0,0,0,0,0,0,0,0,0,0,0,0,DD36,0,0,0,0,0,0,0,0,0,0,0,0,0,0,0,0,0,0,0,0,0,0,0,0,0,0,0)';
      BIDIRECTIONAL='TRUE';
      INPUT_LOAD='(-0.01,0.01)';
      OUTPUT_LOAD='(1.0,-1.0)';
    'DDR7_SB_DQS_DN8':
      PIN_NUMBER='(0,0,0,0,0,0,0,0,0,0,0,0,0,0,DF18,0,0,0,0,0,0,0,0,0,0,0,0,0,0,0,0,0,0,0,0,0,0,0,0,0,0,0)';
      BIDIRECTIONAL='TRUE';
      INPUT_LOAD='(-0.01,0.01)';
      OUTPUT_LOAD='(1.0,-1.0)';
    'DDR7_SB_DQS_DN7':
      PIN_NUMBER='(0,0,0,0,0,0,0,0,0,0,0,0,0,0,DR21,0,0,0,0,0,0,0,0,0,0,0,0,0,0,0,0,0,0,0,0,0,0,0,0,0,0,0)';
      BIDIRECTIONAL='TRUE';
      INPUT_LOAD='(-0.01,0.01)';
      OUTPUT_LOAD='(1.0,-1.0)';
    'DDR7_SB_DQS_DN6':
      PIN_NUMBER='(0,0,0,0,0,0,0,0,0,0,0,0,0,0,DH24,0,0,0,0,0,0,0,0,0,0,0,0,0,0,0,0,0,0,0,0,0,0,0,0,0,0,0)';
      BIDIRECTIONAL='TRUE';
      INPUT_LOAD='(-0.01,0.01)';
      OUTPUT_LOAD='(1.0,-1.0)';
    'DDR7_SB_DQS_DN5':
      PIN_NUMBER='(0,0,0,0,0,0,0,0,0,0,0,0,0,0,DH30,0,0,0,0,0,0,0,0,0,0,0,0,0,0,0,0,0,0,0,0,0,0,0,0,0,0,0)';
      BIDIRECTIONAL='TRUE';
      INPUT_LOAD='(-0.01,0.01)';
      OUTPUT_LOAD='(1.0,-1.0)';
    'DDR7_SB_DQS_DN4':
      PIN_NUMBER='(0,0,0,0,0,0,0,0,0,0,0,0,0,0,DH36,0,0,0,0,0,0,0,0,0,0,0,0,0,0,0,0,0,0,0,0,0,0,0,0,0,0,0)';
      BIDIRECTIONAL='TRUE';
      INPUT_LOAD='(-0.01,0.01)';
      OUTPUT_LOAD='(1.0,-1.0)';
    'DDR7_SB_DQS_DN3':
      PIN_NUMBER='(0,0,0,0,0,0,0,0,0,0,0,0,0,0,DB18,0,0,0,0,0,0,0,0,0,0,0,0,0,0,0,0,0,0,0,0,0,0,0,0,0,0,0)';
      BIDIRECTIONAL='TRUE';
      INPUT_LOAD='(-0.01,0.01)';
      OUTPUT_LOAD='(1.0,-1.0)';
    'DDR7_SB_DQS_DN2':
      PIN_NUMBER='(0,0,0,0,0,0,0,0,0,0,0,0,0,0,DL21,0,0,0,0,0,0,0,0,0,0,0,0,0,0,0,0,0,0,0,0,0,0,0,0,0,0,0)';
      BIDIRECTIONAL='TRUE';
      INPUT_LOAD='(-0.01,0.01)';
      OUTPUT_LOAD='(1.0,-1.0)';
    'DDR7_SB_DQS_DN1':
      PIN_NUMBER='(0,0,0,0,0,0,0,0,0,0,0,0,0,0,DD24,0,0,0,0,0,0,0,0,0,0,0,0,0,0,0,0,0,0,0,0,0,0,0,0,0,0,0)';
      BIDIRECTIONAL='TRUE';
      INPUT_LOAD='(-0.01,0.01)';
      OUTPUT_LOAD='(1.0,-1.0)';
    'DDR7_SB_DQS_DN0':
      PIN_NUMBER='(0,0,0,0,0,0,0,0,0,0,0,0,0,0,DD30,0,0,0,0,0,0,0,0,0,0,0,0,0,0,0,0,0,0,0,0,0,0,0,0,0,0,0)';
      BIDIRECTIONAL='TRUE';
      INPUT_LOAD='(-0.01,0.01)';
      OUTPUT_LOAD='(1.0,-1.0)';
    'DDR7_SB_DQS_DP9':
      PIN_NUMBER='(0,0,0,0,0,0,0,0,0,0,0,0,0,0,DB36,0,0,0,0,0,0,0,0,0,0,0,0,0,0,0,0,0,0,0,0,0,0,0,0,0,0,0)';
      BIDIRECTIONAL='TRUE';
      INPUT_LOAD='(-0.01,0.01)';
      OUTPUT_LOAD='(1.0,-1.0)';
    'DDR7_SB_DQS_DP8':
      PIN_NUMBER='(0,0,0,0,0,0,0,0,0,0,0,0,0,0,DH18,0,0,0,0,0,0,0,0,0,0,0,0,0,0,0,0,0,0,0,0,0,0,0,0,0,0,0)';
      BIDIRECTIONAL='TRUE';
      INPUT_LOAD='(-0.01,0.01)';
      OUTPUT_LOAD='(1.0,-1.0)';
    'DDR7_SB_DQS_DP7':
      PIN_NUMBER='(0,0,0,0,0,0,0,0,0,0,0,0,0,0,DN21,0,0,0,0,0,0,0,0,0,0,0,0,0,0,0,0,0,0,0,0,0,0,0,0,0,0,0)';
      BIDIRECTIONAL='TRUE';
      INPUT_LOAD='(-0.01,0.01)';
      OUTPUT_LOAD='(1.0,-1.0)';
    'DDR7_SB_DQS_DP6':
      PIN_NUMBER='(0,0,0,0,0,0,0,0,0,0,0,0,0,0,DF24,0,0,0,0,0,0,0,0,0,0,0,0,0,0,0,0,0,0,0,0,0,0,0,0,0,0,0)';
      BIDIRECTIONAL='TRUE';
      INPUT_LOAD='(-0.01,0.01)';
      OUTPUT_LOAD='(1.0,-1.0)';
    'DDR7_SB_DQS_DP5':
      PIN_NUMBER='(0,0,0,0,0,0,0,0,0,0,0,0,0,0,DF30,0,0,0,0,0,0,0,0,0,0,0,0,0,0,0,0,0,0,0,0,0,0,0,0,0,0,0)';
      BIDIRECTIONAL='TRUE';
      INPUT_LOAD='(-0.01,0.01)';
      OUTPUT_LOAD='(1.0,-1.0)';
    'DDR7_SB_DQS_DP4':
      PIN_NUMBER='(0,0,0,0,0,0,0,0,0,0,0,0,0,0,DF36,0,0,0,0,0,0,0,0,0,0,0,0,0,0,0,0,0,0,0,0,0,0,0,0,0,0,0)';
      BIDIRECTIONAL='TRUE';
      INPUT_LOAD='(-0.01,0.01)';
      OUTPUT_LOAD='(1.0,-1.0)';
    'DDR7_SB_DQS_DP3':
      PIN_NUMBER='(0,0,0,0,0,0,0,0,0,0,0,0,0,0,DD18,0,0,0,0,0,0,0,0,0,0,0,0,0,0,0,0,0,0,0,0,0,0,0,0,0,0,0)';
      BIDIRECTIONAL='TRUE';
      INPUT_LOAD='(-0.01,0.01)';
      OUTPUT_LOAD='(1.0,-1.0)';
    'DDR7_SB_DQS_DP2':
      PIN_NUMBER='(0,0,0,0,0,0,0,0,0,0,0,0,0,0,DJ21,0,0,0,0,0,0,0,0,0,0,0,0,0,0,0,0,0,0,0,0,0,0,0,0,0,0,0)';
      BIDIRECTIONAL='TRUE';
      INPUT_LOAD='(-0.01,0.01)';
      OUTPUT_LOAD='(1.0,-1.0)';
    'DDR7_SB_DQS_DP1':
      PIN_NUMBER='(0,0,0,0,0,0,0,0,0,0,0,0,0,0,DB24,0,0,0,0,0,0,0,0,0,0,0,0,0,0,0,0,0,0,0,0,0,0,0,0,0,0,0)';
      BIDIRECTIONAL='TRUE';
      INPUT_LOAD='(-0.01,0.01)';
      OUTPUT_LOAD='(1.0,-1.0)';
    'DDR7_SB_DQS_DP0':
      PIN_NUMBER='(0,0,0,0,0,0,0,0,0,0,0,0,0,0,DB30,0,0,0,0,0,0,0,0,0,0,0,0,0,0,0,0,0,0,0,0,0,0,0,0,0,0,0)';
      BIDIRECTIONAL='TRUE';
      INPUT_LOAD='(-0.01,0.01)';
      OUTPUT_LOAD='(1.0,-1.0)';
    'DDR7_SB_ECC7':
      PIN_NUMBER='(0,0,0,0,0,0,0,0,0,0,0,0,0,0,DC37,0,0,0,0,0,0,0,0,0,0,0,0,0,0,0,0,0,0,0,0,0,0,0,0,0,0,0)';
      BIDIRECTIONAL='TRUE';
      INPUT_LOAD='(-0.01,0.01)';
      OUTPUT_LOAD='(1.0,-1.0)';
    'DDR7_SB_ECC6':
      PIN_NUMBER='(0,0,0,0,0,0,0,0,0,0,0,0,0,0,DD38,0,0,0,0,0,0,0,0,0,0,0,0,0,0,0,0,0,0,0,0,0,0,0,0,0,0,0)';
      BIDIRECTIONAL='TRUE';
      INPUT_LOAD='(-0.01,0.01)';
      OUTPUT_LOAD='(1.0,-1.0)';
    'DDR7_SB_ECC5':
      PIN_NUMBER='(0,0,0,0,0,0,0,0,0,0,0,0,0,0,DG37,0,0,0,0,0,0,0,0,0,0,0,0,0,0,0,0,0,0,0,0,0,0,0,0,0,0,0)';
      BIDIRECTIONAL='TRUE';
      INPUT_LOAD='(-0.01,0.01)';
      OUTPUT_LOAD='(1.0,-1.0)';
    'DDR7_SB_ECC4':
      PIN_NUMBER='(0,0,0,0,0,0,0,0,0,0,0,0,0,0,DF38,0,0,0,0,0,0,0,0,0,0,0,0,0,0,0,0,0,0,0,0,0,0,0,0,0,0,0)';
      BIDIRECTIONAL='TRUE';
      INPUT_LOAD='(-0.01,0.01)';
      OUTPUT_LOAD='(1.0,-1.0)';
    'DDR7_SB_ECC3':
      PIN_NUMBER='(0,0,0,0,0,0,0,0,0,0,0,0,0,0,DF34,0,0,0,0,0,0,0,0,0,0,0,0,0,0,0,0,0,0,0,0,0,0,0,0,0,0,0)';
      BIDIRECTIONAL='TRUE';
      INPUT_LOAD='(-0.01,0.01)';
      OUTPUT_LOAD='(1.0,-1.0)';
    'DDR7_SB_ECC2':
      PIN_NUMBER='(0,0,0,0,0,0,0,0,0,0,0,0,0,0,DG35,0,0,0,0,0,0,0,0,0,0,0,0,0,0,0,0,0,0,0,0,0,0,0,0,0,0,0)';
      BIDIRECTIONAL='TRUE';
      INPUT_LOAD='(-0.01,0.01)';
      OUTPUT_LOAD='(1.0,-1.0)';
    'DDR7_SB_ECC1':
      PIN_NUMBER='(0,0,0,0,0,0,0,0,0,0,0,0,0,0,DD34,0,0,0,0,0,0,0,0,0,0,0,0,0,0,0,0,0,0,0,0,0,0,0,0,0,0,0)';
      BIDIRECTIONAL='TRUE';
      INPUT_LOAD='(-0.01,0.01)';
      OUTPUT_LOAD='(1.0,-1.0)';
    'DDR7_SB_ECC0':
      PIN_NUMBER='(0,0,0,0,0,0,0,0,0,0,0,0,0,0,DC35,0,0,0,0,0,0,0,0,0,0,0,0,0,0,0,0,0,0,0,0,0,0,0,0,0,0,0)';
      BIDIRECTIONAL='TRUE';
      INPUT_LOAD='(-0.01,0.01)';
      OUTPUT_LOAD='(1.0,-1.0)';
    'DDR7_SB_PAR':
      PIN_NUMBER='(0,0,0,0,0,0,0,0,0,0,0,0,0,0,DR39,0,0,0,0,0,0,0,0,0,0,0,0,0,0,0,0,0,0,0,0,0,0,0,0,0,0,0)';
      OUTPUT_LOAD='(1.0,-1.0)';
    'DMI_RX_DN7':
      PIN_NUMBER='(0,0,0,0,0,0,0,0,0,0,0,0,0,0,0,BU17,0,0,0,0,0,0,0,0,0,0,0,0,0,0,0,0,0,0,0,0,0,0,0,0,0,0)';
      INPUT_LOAD='(-0.01,0.01)';
    'DMI_RX_DN6':
      PIN_NUMBER='(0,0,0,0,0,0,0,0,0,0,0,0,0,0,0,BP18,0,0,0,0,0,0,0,0,0,0,0,0,0,0,0,0,0,0,0,0,0,0,0,0,0,0)';
      INPUT_LOAD='(-0.01,0.01)';
    'DMI_RX_DN5':
      PIN_NUMBER='(0,0,0,0,0,0,0,0,0,0,0,0,0,0,0,BN17,0,0,0,0,0,0,0,0,0,0,0,0,0,0,0,0,0,0,0,0,0,0,0,0,0,0)';
      INPUT_LOAD='(-0.01,0.01)';
    'DMI_RX_DN4':
      PIN_NUMBER='(0,0,0,0,0,0,0,0,0,0,0,0,0,0,0,BK18,0,0,0,0,0,0,0,0,0,0,0,0,0,0,0,0,0,0,0,0,0,0,0,0,0,0)';
      INPUT_LOAD='(-0.01,0.01)';
    'DMI_RX_DN3':
      PIN_NUMBER='(0,0,0,0,0,0,0,0,0,0,0,0,0,0,0,BJ17,0,0,0,0,0,0,0,0,0,0,0,0,0,0,0,0,0,0,0,0,0,0,0,0,0,0)';
      INPUT_LOAD='(-0.01,0.01)';
    'DMI_RX_DN2':
      PIN_NUMBER='(0,0,0,0,0,0,0,0,0,0,0,0,0,0,0,BF18,0,0,0,0,0,0,0,0,0,0,0,0,0,0,0,0,0,0,0,0,0,0,0,0,0,0)';
      INPUT_LOAD='(-0.01,0.01)';
    'DMI_RX_DN1':
      PIN_NUMBER='(0,0,0,0,0,0,0,0,0,0,0,0,0,0,0,BE17,0,0,0,0,0,0,0,0,0,0,0,0,0,0,0,0,0,0,0,0,0,0,0,0,0,0)';
      INPUT_LOAD='(-0.01,0.01)';
    'DMI_RX_DN0':
      PIN_NUMBER='(0,0,0,0,0,0,0,0,0,0,0,0,0,0,0,BB18,0,0,0,0,0,0,0,0,0,0,0,0,0,0,0,0,0,0,0,0,0,0,0,0,0,0)';
      INPUT_LOAD='(-0.01,0.01)';
    'DMI_RX_DP7':
      PIN_NUMBER='(0,0,0,0,0,0,0,0,0,0,0,0,0,0,0,BT18,0,0,0,0,0,0,0,0,0,0,0,0,0,0,0,0,0,0,0,0,0,0,0,0,0,0)';
      INPUT_LOAD='(-0.01,0.01)';
    'DMI_RX_DP6':
      PIN_NUMBER='(0,0,0,0,0,0,0,0,0,0,0,0,0,0,0,BR19,0,0,0,0,0,0,0,0,0,0,0,0,0,0,0,0,0,0,0,0,0,0,0,0,0,0)';
      INPUT_LOAD='(-0.01,0.01)';
    'DMI_RX_DP5':
      PIN_NUMBER='(0,0,0,0,0,0,0,0,0,0,0,0,0,0,0,BM18,0,0,0,0,0,0,0,0,0,0,0,0,0,0,0,0,0,0,0,0,0,0,0,0,0,0)';
      INPUT_LOAD='(-0.01,0.01)';
    'DMI_RX_DP4':
      PIN_NUMBER='(0,0,0,0,0,0,0,0,0,0,0,0,0,0,0,BL19,0,0,0,0,0,0,0,0,0,0,0,0,0,0,0,0,0,0,0,0,0,0,0,0,0,0)';
      INPUT_LOAD='(-0.01,0.01)';
    'DMI_RX_DP3':
      PIN_NUMBER='(0,0,0,0,0,0,0,0,0,0,0,0,0,0,0,BH18,0,0,0,0,0,0,0,0,0,0,0,0,0,0,0,0,0,0,0,0,0,0,0,0,0,0)';
      INPUT_LOAD='(-0.01,0.01)';
    'DMI_RX_DP2':
      PIN_NUMBER='(0,0,0,0,0,0,0,0,0,0,0,0,0,0,0,BG19,0,0,0,0,0,0,0,0,0,0,0,0,0,0,0,0,0,0,0,0,0,0,0,0,0,0)';
      INPUT_LOAD='(-0.01,0.01)';
    'DMI_RX_DP1':
      PIN_NUMBER='(0,0,0,0,0,0,0,0,0,0,0,0,0,0,0,BD18,0,0,0,0,0,0,0,0,0,0,0,0,0,0,0,0,0,0,0,0,0,0,0,0,0,0)';
      INPUT_LOAD='(-0.01,0.01)';
    'DMI_RX_DP0':
      PIN_NUMBER='(0,0,0,0,0,0,0,0,0,0,0,0,0,0,0,BC19,0,0,0,0,0,0,0,0,0,0,0,0,0,0,0,0,0,0,0,0,0,0,0,0,0,0)';
      INPUT_LOAD='(-0.01,0.01)';
    'DMI_TX_DN7':
      PIN_NUMBER='(0,0,0,0,0,0,0,0,0,0,0,0,0,0,0,CN17,0,0,0,0,0,0,0,0,0,0,0,0,0,0,0,0,0,0,0,0,0,0,0,0,0,0)';
      OUTPUT_LOAD='(1.0,-1.0)';
    'DMI_TX_DN6':
      PIN_NUMBER='(0,0,0,0,0,0,0,0,0,0,0,0,0,0,0,CK18,0,0,0,0,0,0,0,0,0,0,0,0,0,0,0,0,0,0,0,0,0,0,0,0,0,0)';
      OUTPUT_LOAD='(1.0,-1.0)';
    'DMI_TX_DN5':
      PIN_NUMBER='(0,0,0,0,0,0,0,0,0,0,0,0,0,0,0,CJ17,0,0,0,0,0,0,0,0,0,0,0,0,0,0,0,0,0,0,0,0,0,0,0,0,0,0)';
      OUTPUT_LOAD='(1.0,-1.0)';
    'DMI_TX_DN4':
      PIN_NUMBER='(0,0,0,0,0,0,0,0,0,0,0,0,0,0,0,CF18,0,0,0,0,0,0,0,0,0,0,0,0,0,0,0,0,0,0,0,0,0,0,0,0,0,0)';
      OUTPUT_LOAD='(1.0,-1.0)';
    'DMI_TX_DN3':
      PIN_NUMBER='(0,0,0,0,0,0,0,0,0,0,0,0,0,0,0,CE17,0,0,0,0,0,0,0,0,0,0,0,0,0,0,0,0,0,0,0,0,0,0,0,0,0,0)';
      OUTPUT_LOAD='(1.0,-1.0)';
    'DMI_TX_DN2':
      PIN_NUMBER='(0,0,0,0,0,0,0,0,0,0,0,0,0,0,0,CB18,0,0,0,0,0,0,0,0,0,0,0,0,0,0,0,0,0,0,0,0,0,0,0,0,0,0)';
      OUTPUT_LOAD='(1.0,-1.0)';
    'DMI_TX_DN1':
      PIN_NUMBER='(0,0,0,0,0,0,0,0,0,0,0,0,0,0,0,CA17,0,0,0,0,0,0,0,0,0,0,0,0,0,0,0,0,0,0,0,0,0,0,0,0,0,0)';
      OUTPUT_LOAD='(1.0,-1.0)';
    'DMI_TX_DN0':
      PIN_NUMBER='(0,0,0,0,0,0,0,0,0,0,0,0,0,0,0,BW19,0,0,0,0,0,0,0,0,0,0,0,0,0,0,0,0,0,0,0,0,0,0,0,0,0,0)';
      OUTPUT_LOAD='(1.0,-1.0)';
    'DMI_TX_DP7':
      PIN_NUMBER='(0,0,0,0,0,0,0,0,0,0,0,0,0,0,0,CM18,0,0,0,0,0,0,0,0,0,0,0,0,0,0,0,0,0,0,0,0,0,0,0,0,0,0)';
      OUTPUT_LOAD='(1.0,-1.0)';
    'DMI_TX_DP6':
      PIN_NUMBER='(0,0,0,0,0,0,0,0,0,0,0,0,0,0,0,CL19,0,0,0,0,0,0,0,0,0,0,0,0,0,0,0,0,0,0,0,0,0,0,0,0,0,0)';
      OUTPUT_LOAD='(1.0,-1.0)';
    'DMI_TX_DP5':
      PIN_NUMBER='(0,0,0,0,0,0,0,0,0,0,0,0,0,0,0,CH18,0,0,0,0,0,0,0,0,0,0,0,0,0,0,0,0,0,0,0,0,0,0,0,0,0,0)';
      OUTPUT_LOAD='(1.0,-1.0)';
    'DMI_TX_DP4':
      PIN_NUMBER='(0,0,0,0,0,0,0,0,0,0,0,0,0,0,0,CG19,0,0,0,0,0,0,0,0,0,0,0,0,0,0,0,0,0,0,0,0,0,0,0,0,0,0)';
      OUTPUT_LOAD='(1.0,-1.0)';
    'DMI_TX_DP3':
      PIN_NUMBER='(0,0,0,0,0,0,0,0,0,0,0,0,0,0,0,CD18,0,0,0,0,0,0,0,0,0,0,0,0,0,0,0,0,0,0,0,0,0,0,0,0,0,0)';
      OUTPUT_LOAD='(1.0,-1.0)';
    'DMI_TX_DP2':
      PIN_NUMBER='(0,0,0,0,0,0,0,0,0,0,0,0,0,0,0,CC19,0,0,0,0,0,0,0,0,0,0,0,0,0,0,0,0,0,0,0,0,0,0,0,0,0,0)';
      OUTPUT_LOAD='(1.0,-1.0)';
    'DMI_TX_DP1':
      PIN_NUMBER='(0,0,0,0,0,0,0,0,0,0,0,0,0,0,0,BY18,0,0,0,0,0,0,0,0,0,0,0,0,0,0,0,0,0,0,0,0,0,0,0,0,0,0)';
      OUTPUT_LOAD='(1.0,-1.0)';
    'DMI_TX_DP0':
      PIN_NUMBER='(0,0,0,0,0,0,0,0,0,0,0,0,0,0,0,CA19,0,0,0,0,0,0,0,0,0,0,0,0,0,0,0,0,0,0,0,0,0,0,0,0,0,0)';
      OUTPUT_LOAD='(1.0,-1.0)';
    'PE0_RX_DN15':
      PIN_NUMBER='(0,0,0,0,0,0,0,0,0,0,0,0,0,0,0,0,BA9,0,0,0,0,0,0,0,0,0,0,0,0,0,0,0,0,0,0,0,0,0,0,0,0,0)';
      INPUT_LOAD='(-0.01,0.01)';
    'PE0_RX_DN14':
      PIN_NUMBER='(0,0,0,0,0,0,0,0,0,0,0,0,0,0,0,0,AV10,0,0,0,0,0,0,0,0,0,0,0,0,0,0,0,0,0,0,0,0,0,0,0,0,0)';
      INPUT_LOAD='(-0.01,0.01)';
    'PE0_RX_DN13':
      PIN_NUMBER='(0,0,0,0,0,0,0,0,0,0,0,0,0,0,0,0,AU9,0,0,0,0,0,0,0,0,0,0,0,0,0,0,0,0,0,0,0,0,0,0,0,0,0)';
      INPUT_LOAD='(-0.01,0.01)';
    'PE0_RX_DN12':
      PIN_NUMBER='(0,0,0,0,0,0,0,0,0,0,0,0,0,0,0,0,AP10,0,0,0,0,0,0,0,0,0,0,0,0,0,0,0,0,0,0,0,0,0,0,0,0,0)';
      INPUT_LOAD='(-0.01,0.01)';
    'PE0_RX_DN11':
      PIN_NUMBER='(0,0,0,0,0,0,0,0,0,0,0,0,0,0,0,0,AM10,0,0,0,0,0,0,0,0,0,0,0,0,0,0,0,0,0,0,0,0,0,0,0,0,0)';
      INPUT_LOAD='(-0.01,0.01)';
    'PE0_RX_DN10':
      PIN_NUMBER='(0,0,0,0,0,0,0,0,0,0,0,0,0,0,0,0,AK10,0,0,0,0,0,0,0,0,0,0,0,0,0,0,0,0,0,0,0,0,0,0,0,0,0)';
      INPUT_LOAD='(-0.01,0.01)';
    'PE0_RX_DN9':
      PIN_NUMBER='(0,0,0,0,0,0,0,0,0,0,0,0,0,0,0,0,AJ9,0,0,0,0,0,0,0,0,0,0,0,0,0,0,0,0,0,0,0,0,0,0,0,0,0)';
      INPUT_LOAD='(-0.01,0.01)';
    'PE0_RX_DN8':
      PIN_NUMBER='(0,0,0,0,0,0,0,0,0,0,0,0,0,0,0,0,AF10,0,0,0,0,0,0,0,0,0,0,0,0,0,0,0,0,0,0,0,0,0,0,0,0,0)';
      INPUT_LOAD='(-0.01,0.01)';
    'PE0_RX_DN7':
      PIN_NUMBER='(0,0,0,0,0,0,0,0,0,0,0,0,0,0,0,0,AE9,0,0,0,0,0,0,0,0,0,0,0,0,0,0,0,0,0,0,0,0,0,0,0,0,0)';
      INPUT_LOAD='(-0.01,0.01)';
    'PE0_RX_DN6':
      PIN_NUMBER='(0,0,0,0,0,0,0,0,0,0,0,0,0,0,0,0,AB10,0,0,0,0,0,0,0,0,0,0,0,0,0,0,0,0,0,0,0,0,0,0,0,0,0)';
      INPUT_LOAD='(-0.01,0.01)';
    'PE0_RX_DN5':
      PIN_NUMBER='(0,0,0,0,0,0,0,0,0,0,0,0,0,0,0,0,AA9,0,0,0,0,0,0,0,0,0,0,0,0,0,0,0,0,0,0,0,0,0,0,0,0,0)';
      INPUT_LOAD='(-0.01,0.01)';
    'PE0_RX_DN4':
      PIN_NUMBER='(0,0,0,0,0,0,0,0,0,0,0,0,0,0,0,0,V10,0,0,0,0,0,0,0,0,0,0,0,0,0,0,0,0,0,0,0,0,0,0,0,0,0)';
      INPUT_LOAD='(-0.01,0.01)';
    'PE0_RX_DN3':
      PIN_NUMBER='(0,0,0,0,0,0,0,0,0,0,0,0,0,0,0,0,T10,0,0,0,0,0,0,0,0,0,0,0,0,0,0,0,0,0,0,0,0,0,0,0,0,0)';
      INPUT_LOAD='(-0.01,0.01)';
    'PE0_RX_DN2':
      PIN_NUMBER='(0,0,0,0,0,0,0,0,0,0,0,0,0,0,0,0,P10,0,0,0,0,0,0,0,0,0,0,0,0,0,0,0,0,0,0,0,0,0,0,0,0,0)';
      INPUT_LOAD='(-0.01,0.01)';
    'PE0_RX_DN1':
      PIN_NUMBER='(0,0,0,0,0,0,0,0,0,0,0,0,0,0,0,0,M10,0,0,0,0,0,0,0,0,0,0,0,0,0,0,0,0,0,0,0,0,0,0,0,0,0)';
      INPUT_LOAD='(-0.01,0.01)';
    'PE0_RX_DN0':
      PIN_NUMBER='(0,0,0,0,0,0,0,0,0,0,0,0,0,0,0,0,K10,0,0,0,0,0,0,0,0,0,0,0,0,0,0,0,0,0,0,0,0,0,0,0,0,0)';
      INPUT_LOAD='(-0.01,0.01)';
    'PE0_RX_DP15':
      PIN_NUMBER='(0,0,0,0,0,0,0,0,0,0,0,0,0,0,0,0,AY10,0,0,0,0,0,0,0,0,0,0,0,0,0,0,0,0,0,0,0,0,0,0,0,0,0)';
      INPUT_LOAD='(-0.01,0.01)';
    'PE0_RX_DP14':
      PIN_NUMBER='(0,0,0,0,0,0,0,0,0,0,0,0,0,0,0,0,AW11,0,0,0,0,0,0,0,0,0,0,0,0,0,0,0,0,0,0,0,0,0,0,0,0,0)';
      INPUT_LOAD='(-0.01,0.01)';
    'PE0_RX_DP13':
      PIN_NUMBER='(0,0,0,0,0,0,0,0,0,0,0,0,0,0,0,0,AT10,0,0,0,0,0,0,0,0,0,0,0,0,0,0,0,0,0,0,0,0,0,0,0,0,0)';
      INPUT_LOAD='(-0.01,0.01)';
    'PE0_RX_DP12':
      PIN_NUMBER='(0,0,0,0,0,0,0,0,0,0,0,0,0,0,0,0,AR11,0,0,0,0,0,0,0,0,0,0,0,0,0,0,0,0,0,0,0,0,0,0,0,0,0)';
      INPUT_LOAD='(-0.01,0.01)';
    'PE0_RX_DP11':
      PIN_NUMBER='(0,0,0,0,0,0,0,0,0,0,0,0,0,0,0,0,AN9,0,0,0,0,0,0,0,0,0,0,0,0,0,0,0,0,0,0,0,0,0,0,0,0,0)';
      INPUT_LOAD='(-0.01,0.01)';
    'PE0_RX_DP10':
      PIN_NUMBER='(0,0,0,0,0,0,0,0,0,0,0,0,0,0,0,0,AL11,0,0,0,0,0,0,0,0,0,0,0,0,0,0,0,0,0,0,0,0,0,0,0,0,0)';
      INPUT_LOAD='(-0.01,0.01)';
    'PE0_RX_DP9':
      PIN_NUMBER='(0,0,0,0,0,0,0,0,0,0,0,0,0,0,0,0,AH10,0,0,0,0,0,0,0,0,0,0,0,0,0,0,0,0,0,0,0,0,0,0,0,0,0)';
      INPUT_LOAD='(-0.01,0.01)';
    'PE0_RX_DP8':
      PIN_NUMBER='(0,0,0,0,0,0,0,0,0,0,0,0,0,0,0,0,AG11,0,0,0,0,0,0,0,0,0,0,0,0,0,0,0,0,0,0,0,0,0,0,0,0,0)';
      INPUT_LOAD='(-0.01,0.01)';
    'PE0_RX_DP7':
      PIN_NUMBER='(0,0,0,0,0,0,0,0,0,0,0,0,0,0,0,0,AD10,0,0,0,0,0,0,0,0,0,0,0,0,0,0,0,0,0,0,0,0,0,0,0,0,0)';
      INPUT_LOAD='(-0.01,0.01)';
    'PE0_RX_DP6':
      PIN_NUMBER='(0,0,0,0,0,0,0,0,0,0,0,0,0,0,0,0,AC11,0,0,0,0,0,0,0,0,0,0,0,0,0,0,0,0,0,0,0,0,0,0,0,0,0)';
      INPUT_LOAD='(-0.01,0.01)';
    'PE0_RX_DP5':
      PIN_NUMBER='(0,0,0,0,0,0,0,0,0,0,0,0,0,0,0,0,Y10,0,0,0,0,0,0,0,0,0,0,0,0,0,0,0,0,0,0,0,0,0,0,0,0,0)';
      INPUT_LOAD='(-0.01,0.01)';
    'PE0_RX_DP4':
      PIN_NUMBER='(0,0,0,0,0,0,0,0,0,0,0,0,0,0,0,0,W11,0,0,0,0,0,0,0,0,0,0,0,0,0,0,0,0,0,0,0,0,0,0,0,0,0)';
      INPUT_LOAD='(-0.01,0.01)';
    'PE0_RX_DP3':
      PIN_NUMBER='(0,0,0,0,0,0,0,0,0,0,0,0,0,0,0,0,U9,0,0,0,0,0,0,0,0,0,0,0,0,0,0,0,0,0,0,0,0,0,0,0,0,0)';
      INPUT_LOAD='(-0.01,0.01)';
    'PE0_RX_DP2':
      PIN_NUMBER='(0,0,0,0,0,0,0,0,0,0,0,0,0,0,0,0,R11,0,0,0,0,0,0,0,0,0,0,0,0,0,0,0,0,0,0,0,0,0,0,0,0,0)';
      INPUT_LOAD='(-0.01,0.01)';
    'PE0_RX_DP1':
      PIN_NUMBER='(0,0,0,0,0,0,0,0,0,0,0,0,0,0,0,0,N9,0,0,0,0,0,0,0,0,0,0,0,0,0,0,0,0,0,0,0,0,0,0,0,0,0)';
      INPUT_LOAD='(-0.01,0.01)';
    'PE0_RX_DP0':
      PIN_NUMBER='(0,0,0,0,0,0,0,0,0,0,0,0,0,0,0,0,L11,0,0,0,0,0,0,0,0,0,0,0,0,0,0,0,0,0,0,0,0,0,0,0,0,0)';
      INPUT_LOAD='(-0.01,0.01)';
    'PE0_TX_DN15':
      PIN_NUMBER='(0,0,0,0,0,0,0,0,0,0,0,0,0,0,0,0,BB14,0,0,0,0,0,0,0,0,0,0,0,0,0,0,0,0,0,0,0,0,0,0,0,0,0)';
      OUTPUT_LOAD='(1.0,-1.0)';
    'PE0_TX_DN14':
      PIN_NUMBER='(0,0,0,0,0,0,0,0,0,0,0,0,0,0,0,0,BA13,0,0,0,0,0,0,0,0,0,0,0,0,0,0,0,0,0,0,0,0,0,0,0,0,0)';
      OUTPUT_LOAD='(1.0,-1.0)';
    'PE0_TX_DN13':
      PIN_NUMBER='(0,0,0,0,0,0,0,0,0,0,0,0,0,0,0,0,AV14,0,0,0,0,0,0,0,0,0,0,0,0,0,0,0,0,0,0,0,0,0,0,0,0,0)';
      OUTPUT_LOAD='(1.0,-1.0)';
    'PE0_TX_DN12':
      PIN_NUMBER='(0,0,0,0,0,0,0,0,0,0,0,0,0,0,0,0,AU13,0,0,0,0,0,0,0,0,0,0,0,0,0,0,0,0,0,0,0,0,0,0,0,0,0)';
      OUTPUT_LOAD='(1.0,-1.0)';
    'PE0_TX_DN11':
      PIN_NUMBER='(0,0,0,0,0,0,0,0,0,0,0,0,0,0,0,0,AP14,0,0,0,0,0,0,0,0,0,0,0,0,0,0,0,0,0,0,0,0,0,0,0,0,0)';
      OUTPUT_LOAD='(1.0,-1.0)';
    'PE0_TX_DN10':
      PIN_NUMBER='(0,0,0,0,0,0,0,0,0,0,0,0,0,0,0,0,AN13,0,0,0,0,0,0,0,0,0,0,0,0,0,0,0,0,0,0,0,0,0,0,0,0,0)';
      OUTPUT_LOAD='(1.0,-1.0)';
    'PE0_TX_DN9':
      PIN_NUMBER='(0,0,0,0,0,0,0,0,0,0,0,0,0,0,0,0,AK14,0,0,0,0,0,0,0,0,0,0,0,0,0,0,0,0,0,0,0,0,0,0,0,0,0)';
      OUTPUT_LOAD='(1.0,-1.0)';
    'PE0_TX_DN8':
      PIN_NUMBER='(0,0,0,0,0,0,0,0,0,0,0,0,0,0,0,0,AJ13,0,0,0,0,0,0,0,0,0,0,0,0,0,0,0,0,0,0,0,0,0,0,0,0,0)';
      OUTPUT_LOAD='(1.0,-1.0)';
    'PE0_TX_DN7':
      PIN_NUMBER='(0,0,0,0,0,0,0,0,0,0,0,0,0,0,0,0,AF14,0,0,0,0,0,0,0,0,0,0,0,0,0,0,0,0,0,0,0,0,0,0,0,0,0)';
      OUTPUT_LOAD='(1.0,-1.0)';
    'PE0_TX_DN6':
      PIN_NUMBER='(0,0,0,0,0,0,0,0,0,0,0,0,0,0,0,0,AE13,0,0,0,0,0,0,0,0,0,0,0,0,0,0,0,0,0,0,0,0,0,0,0,0,0)';
      OUTPUT_LOAD='(1.0,-1.0)';
    'PE0_TX_DN5':
      PIN_NUMBER='(0,0,0,0,0,0,0,0,0,0,0,0,0,0,0,0,AB14,0,0,0,0,0,0,0,0,0,0,0,0,0,0,0,0,0,0,0,0,0,0,0,0,0)';
      OUTPUT_LOAD='(1.0,-1.0)';
    'PE0_TX_DN4':
      PIN_NUMBER='(0,0,0,0,0,0,0,0,0,0,0,0,0,0,0,0,AA13,0,0,0,0,0,0,0,0,0,0,0,0,0,0,0,0,0,0,0,0,0,0,0,0,0)';
      OUTPUT_LOAD='(1.0,-1.0)';
    'PE0_TX_DN3':
      PIN_NUMBER='(0,0,0,0,0,0,0,0,0,0,0,0,0,0,0,0,V14,0,0,0,0,0,0,0,0,0,0,0,0,0,0,0,0,0,0,0,0,0,0,0,0,0)';
      OUTPUT_LOAD='(1.0,-1.0)';
    'PE0_TX_DN2':
      PIN_NUMBER='(0,0,0,0,0,0,0,0,0,0,0,0,0,0,0,0,U13,0,0,0,0,0,0,0,0,0,0,0,0,0,0,0,0,0,0,0,0,0,0,0,0,0)';
      OUTPUT_LOAD='(1.0,-1.0)';
    'PE0_TX_DN1':
      PIN_NUMBER='(0,0,0,0,0,0,0,0,0,0,0,0,0,0,0,0,P14,0,0,0,0,0,0,0,0,0,0,0,0,0,0,0,0,0,0,0,0,0,0,0,0,0)';
      OUTPUT_LOAD='(1.0,-1.0)';
    'PE0_TX_DN0':
      PIN_NUMBER='(0,0,0,0,0,0,0,0,0,0,0,0,0,0,0,0,N13,0,0,0,0,0,0,0,0,0,0,0,0,0,0,0,0,0,0,0,0,0,0,0,0,0)';
      OUTPUT_LOAD='(1.0,-1.0)';
    'PE0_TX_DP15':
      PIN_NUMBER='(0,0,0,0,0,0,0,0,0,0,0,0,0,0,0,0,BC15,0,0,0,0,0,0,0,0,0,0,0,0,0,0,0,0,0,0,0,0,0,0,0,0,0)';
      OUTPUT_LOAD='(1.0,-1.0)';
    'PE0_TX_DP14':
      PIN_NUMBER='(0,0,0,0,0,0,0,0,0,0,0,0,0,0,0,0,AY14,0,0,0,0,0,0,0,0,0,0,0,0,0,0,0,0,0,0,0,0,0,0,0,0,0)';
      OUTPUT_LOAD='(1.0,-1.0)';
    'PE0_TX_DP13':
      PIN_NUMBER='(0,0,0,0,0,0,0,0,0,0,0,0,0,0,0,0,AW15,0,0,0,0,0,0,0,0,0,0,0,0,0,0,0,0,0,0,0,0,0,0,0,0,0)';
      OUTPUT_LOAD='(1.0,-1.0)';
    'PE0_TX_DP12':
      PIN_NUMBER='(0,0,0,0,0,0,0,0,0,0,0,0,0,0,0,0,AT14,0,0,0,0,0,0,0,0,0,0,0,0,0,0,0,0,0,0,0,0,0,0,0,0,0)';
      OUTPUT_LOAD='(1.0,-1.0)';
    'PE0_TX_DP11':
      PIN_NUMBER='(0,0,0,0,0,0,0,0,0,0,0,0,0,0,0,0,AR15,0,0,0,0,0,0,0,0,0,0,0,0,0,0,0,0,0,0,0,0,0,0,0,0,0)';
      OUTPUT_LOAD='(1.0,-1.0)';
    'PE0_TX_DP10':
      PIN_NUMBER='(0,0,0,0,0,0,0,0,0,0,0,0,0,0,0,0,AM14,0,0,0,0,0,0,0,0,0,0,0,0,0,0,0,0,0,0,0,0,0,0,0,0,0)';
      OUTPUT_LOAD='(1.0,-1.0)';
    'PE0_TX_DP9':
      PIN_NUMBER='(0,0,0,0,0,0,0,0,0,0,0,0,0,0,0,0,AL15,0,0,0,0,0,0,0,0,0,0,0,0,0,0,0,0,0,0,0,0,0,0,0,0,0)';
      OUTPUT_LOAD='(1.0,-1.0)';
    'PE0_TX_DP8':
      PIN_NUMBER='(0,0,0,0,0,0,0,0,0,0,0,0,0,0,0,0,AH14,0,0,0,0,0,0,0,0,0,0,0,0,0,0,0,0,0,0,0,0,0,0,0,0,0)';
      OUTPUT_LOAD='(1.0,-1.0)';
    'PE0_TX_DP7':
      PIN_NUMBER='(0,0,0,0,0,0,0,0,0,0,0,0,0,0,0,0,AG15,0,0,0,0,0,0,0,0,0,0,0,0,0,0,0,0,0,0,0,0,0,0,0,0,0)';
      OUTPUT_LOAD='(1.0,-1.0)';
    'PE0_TX_DP6':
      PIN_NUMBER='(0,0,0,0,0,0,0,0,0,0,0,0,0,0,0,0,AD14,0,0,0,0,0,0,0,0,0,0,0,0,0,0,0,0,0,0,0,0,0,0,0,0,0)';
      OUTPUT_LOAD='(1.0,-1.0)';
    'PE0_TX_DP5':
      PIN_NUMBER='(0,0,0,0,0,0,0,0,0,0,0,0,0,0,0,0,AC15,0,0,0,0,0,0,0,0,0,0,0,0,0,0,0,0,0,0,0,0,0,0,0,0,0)';
      OUTPUT_LOAD='(1.0,-1.0)';
    'PE0_TX_DP4':
      PIN_NUMBER='(0,0,0,0,0,0,0,0,0,0,0,0,0,0,0,0,Y14,0,0,0,0,0,0,0,0,0,0,0,0,0,0,0,0,0,0,0,0,0,0,0,0,0)';
      OUTPUT_LOAD='(1.0,-1.0)';
    'PE0_TX_DP3':
      PIN_NUMBER='(0,0,0,0,0,0,0,0,0,0,0,0,0,0,0,0,W15,0,0,0,0,0,0,0,0,0,0,0,0,0,0,0,0,0,0,0,0,0,0,0,0,0)';
      OUTPUT_LOAD='(1.0,-1.0)';
    'PE0_TX_DP2':
      PIN_NUMBER='(0,0,0,0,0,0,0,0,0,0,0,0,0,0,0,0,T14,0,0,0,0,0,0,0,0,0,0,0,0,0,0,0,0,0,0,0,0,0,0,0,0,0)';
      OUTPUT_LOAD='(1.0,-1.0)';
    'PE0_TX_DP1':
      PIN_NUMBER='(0,0,0,0,0,0,0,0,0,0,0,0,0,0,0,0,R15,0,0,0,0,0,0,0,0,0,0,0,0,0,0,0,0,0,0,0,0,0,0,0,0,0)';
      OUTPUT_LOAD='(1.0,-1.0)';
    'PE0_TX_DP0':
      PIN_NUMBER='(0,0,0,0,0,0,0,0,0,0,0,0,0,0,0,0,M14,0,0,0,0,0,0,0,0,0,0,0,0,0,0,0,0,0,0,0,0,0,0,0,0,0)';
      OUTPUT_LOAD='(1.0,-1.0)';
    'PE1_RX_DN15':
      PIN_NUMBER='(0,0,0,0,0,0,0,0,0,0,0,0,0,0,0,0,0,BC11,0,0,0,0,0,0,0,0,0,0,0,0,0,0,0,0,0,0,0,0,0,0,0,0)';
      INPUT_LOAD='(-0.01,0.01)';
    'PE1_RX_DN14':
      PIN_NUMBER='(0,0,0,0,0,0,0,0,0,0,0,0,0,0,0,0,0,BF10,0,0,0,0,0,0,0,0,0,0,0,0,0,0,0,0,0,0,0,0,0,0,0,0)';
      INPUT_LOAD='(-0.01,0.01)';
    'PE1_RX_DN13':
      PIN_NUMBER='(0,0,0,0,0,0,0,0,0,0,0,0,0,0,0,0,0,BG11,0,0,0,0,0,0,0,0,0,0,0,0,0,0,0,0,0,0,0,0,0,0,0,0)';
      INPUT_LOAD='(-0.01,0.01)';
    'PE1_RX_DN12':
      PIN_NUMBER='(0,0,0,0,0,0,0,0,0,0,0,0,0,0,0,0,0,BK10,0,0,0,0,0,0,0,0,0,0,0,0,0,0,0,0,0,0,0,0,0,0,0,0)';
      INPUT_LOAD='(-0.01,0.01)';
    'PE1_RX_DN11':
      PIN_NUMBER='(0,0,0,0,0,0,0,0,0,0,0,0,0,0,0,0,0,BL11,0,0,0,0,0,0,0,0,0,0,0,0,0,0,0,0,0,0,0,0,0,0,0,0)';
      INPUT_LOAD='(-0.01,0.01)';
    'PE1_RX_DN10':
      PIN_NUMBER='(0,0,0,0,0,0,0,0,0,0,0,0,0,0,0,0,0,BP10,0,0,0,0,0,0,0,0,0,0,0,0,0,0,0,0,0,0,0,0,0,0,0,0)';
      INPUT_LOAD='(-0.01,0.01)';
    'PE1_RX_DN9':
      PIN_NUMBER='(0,0,0,0,0,0,0,0,0,0,0,0,0,0,0,0,0,BR11,0,0,0,0,0,0,0,0,0,0,0,0,0,0,0,0,0,0,0,0,0,0,0,0)';
      INPUT_LOAD='(-0.01,0.01)';
    'PE1_RX_DN8':
      PIN_NUMBER='(0,0,0,0,0,0,0,0,0,0,0,0,0,0,0,0,0,BV10,0,0,0,0,0,0,0,0,0,0,0,0,0,0,0,0,0,0,0,0,0,0,0,0)';
      INPUT_LOAD='(-0.01,0.01)';
    'PE1_RX_DN7':
      PIN_NUMBER='(0,0,0,0,0,0,0,0,0,0,0,0,0,0,0,0,0,BW11,0,0,0,0,0,0,0,0,0,0,0,0,0,0,0,0,0,0,0,0,0,0,0,0)';
      INPUT_LOAD='(-0.01,0.01)';
    'PE1_RX_DN6':
      PIN_NUMBER='(0,0,0,0,0,0,0,0,0,0,0,0,0,0,0,0,0,CB10,0,0,0,0,0,0,0,0,0,0,0,0,0,0,0,0,0,0,0,0,0,0,0,0)';
      INPUT_LOAD='(-0.01,0.01)';
    'PE1_RX_DN5':
      PIN_NUMBER='(0,0,0,0,0,0,0,0,0,0,0,0,0,0,0,0,0,CC11,0,0,0,0,0,0,0,0,0,0,0,0,0,0,0,0,0,0,0,0,0,0,0,0)';
      INPUT_LOAD='(-0.01,0.01)';
    'PE1_RX_DN4':
      PIN_NUMBER='(0,0,0,0,0,0,0,0,0,0,0,0,0,0,0,0,0,CF10,0,0,0,0,0,0,0,0,0,0,0,0,0,0,0,0,0,0,0,0,0,0,0,0)';
      INPUT_LOAD='(-0.01,0.01)';
    'PE1_RX_DN3':
      PIN_NUMBER='(0,0,0,0,0,0,0,0,0,0,0,0,0,0,0,0,0,CG11,0,0,0,0,0,0,0,0,0,0,0,0,0,0,0,0,0,0,0,0,0,0,0,0)';
      INPUT_LOAD='(-0.01,0.01)';
    'PE1_RX_DN2':
      PIN_NUMBER='(0,0,0,0,0,0,0,0,0,0,0,0,0,0,0,0,0,CK10,0,0,0,0,0,0,0,0,0,0,0,0,0,0,0,0,0,0,0,0,0,0,0,0)';
      INPUT_LOAD='(-0.01,0.01)';
    'PE1_RX_DN1':
      PIN_NUMBER='(0,0,0,0,0,0,0,0,0,0,0,0,0,0,0,0,0,CL11,0,0,0,0,0,0,0,0,0,0,0,0,0,0,0,0,0,0,0,0,0,0,0,0)';
      INPUT_LOAD='(-0.01,0.01)';
    'PE1_RX_DN0':
      PIN_NUMBER='(0,0,0,0,0,0,0,0,0,0,0,0,0,0,0,0,0,CP10,0,0,0,0,0,0,0,0,0,0,0,0,0,0,0,0,0,0,0,0,0,0,0,0)';
      INPUT_LOAD='(-0.01,0.01)';
    'PE1_RX_DP15':
      PIN_NUMBER='(0,0,0,0,0,0,0,0,0,0,0,0,0,0,0,0,0,BD10,0,0,0,0,0,0,0,0,0,0,0,0,0,0,0,0,0,0,0,0,0,0,0,0)';
      INPUT_LOAD='(-0.01,0.01)';
    'PE1_RX_DP14':
      PIN_NUMBER='(0,0,0,0,0,0,0,0,0,0,0,0,0,0,0,0,0,BE9,0,0,0,0,0,0,0,0,0,0,0,0,0,0,0,0,0,0,0,0,0,0,0,0)';
      INPUT_LOAD='(-0.01,0.01)';
    'PE1_RX_DP13':
      PIN_NUMBER='(0,0,0,0,0,0,0,0,0,0,0,0,0,0,0,0,0,BH10,0,0,0,0,0,0,0,0,0,0,0,0,0,0,0,0,0,0,0,0,0,0,0,0)';
      INPUT_LOAD='(-0.01,0.01)';
    'PE1_RX_DP12':
      PIN_NUMBER='(0,0,0,0,0,0,0,0,0,0,0,0,0,0,0,0,0,BJ9,0,0,0,0,0,0,0,0,0,0,0,0,0,0,0,0,0,0,0,0,0,0,0,0)';
      INPUT_LOAD='(-0.01,0.01)';
    'PE1_RX_DP11':
      PIN_NUMBER='(0,0,0,0,0,0,0,0,0,0,0,0,0,0,0,0,0,BM10,0,0,0,0,0,0,0,0,0,0,0,0,0,0,0,0,0,0,0,0,0,0,0,0)';
      INPUT_LOAD='(-0.01,0.01)';
    'PE1_RX_DP10':
      PIN_NUMBER='(0,0,0,0,0,0,0,0,0,0,0,0,0,0,0,0,0,BN9,0,0,0,0,0,0,0,0,0,0,0,0,0,0,0,0,0,0,0,0,0,0,0,0)';
      INPUT_LOAD='(-0.01,0.01)';
    'PE1_RX_DP9':
      PIN_NUMBER='(0,0,0,0,0,0,0,0,0,0,0,0,0,0,0,0,0,BT10,0,0,0,0,0,0,0,0,0,0,0,0,0,0,0,0,0,0,0,0,0,0,0,0)';
      INPUT_LOAD='(-0.01,0.01)';
    'PE1_RX_DP8':
      PIN_NUMBER='(0,0,0,0,0,0,0,0,0,0,0,0,0,0,0,0,0,BU9,0,0,0,0,0,0,0,0,0,0,0,0,0,0,0,0,0,0,0,0,0,0,0,0)';
      INPUT_LOAD='(-0.01,0.01)';
    'PE1_RX_DP7':
      PIN_NUMBER='(0,0,0,0,0,0,0,0,0,0,0,0,0,0,0,0,0,BY10,0,0,0,0,0,0,0,0,0,0,0,0,0,0,0,0,0,0,0,0,0,0,0,0)';
      INPUT_LOAD='(-0.01,0.01)';
    'PE1_RX_DP6':
      PIN_NUMBER='(0,0,0,0,0,0,0,0,0,0,0,0,0,0,0,0,0,CA9,0,0,0,0,0,0,0,0,0,0,0,0,0,0,0,0,0,0,0,0,0,0,0,0)';
      INPUT_LOAD='(-0.01,0.01)';
    'PE1_RX_DP5':
      PIN_NUMBER='(0,0,0,0,0,0,0,0,0,0,0,0,0,0,0,0,0,CD10,0,0,0,0,0,0,0,0,0,0,0,0,0,0,0,0,0,0,0,0,0,0,0,0)';
      INPUT_LOAD='(-0.01,0.01)';
    'PE1_RX_DP4':
      PIN_NUMBER='(0,0,0,0,0,0,0,0,0,0,0,0,0,0,0,0,0,CE9,0,0,0,0,0,0,0,0,0,0,0,0,0,0,0,0,0,0,0,0,0,0,0,0)';
      INPUT_LOAD='(-0.01,0.01)';
    'PE1_RX_DP3':
      PIN_NUMBER='(0,0,0,0,0,0,0,0,0,0,0,0,0,0,0,0,0,CH10,0,0,0,0,0,0,0,0,0,0,0,0,0,0,0,0,0,0,0,0,0,0,0,0)';
      INPUT_LOAD='(-0.01,0.01)';
    'PE1_RX_DP2':
      PIN_NUMBER='(0,0,0,0,0,0,0,0,0,0,0,0,0,0,0,0,0,CJ9,0,0,0,0,0,0,0,0,0,0,0,0,0,0,0,0,0,0,0,0,0,0,0,0)';
      INPUT_LOAD='(-0.01,0.01)';
    'PE1_RX_DP1':
      PIN_NUMBER='(0,0,0,0,0,0,0,0,0,0,0,0,0,0,0,0,0,CM10,0,0,0,0,0,0,0,0,0,0,0,0,0,0,0,0,0,0,0,0,0,0,0,0)';
      INPUT_LOAD='(-0.01,0.01)';
    'PE1_RX_DP0':
      PIN_NUMBER='(0,0,0,0,0,0,0,0,0,0,0,0,0,0,0,0,0,CN9,0,0,0,0,0,0,0,0,0,0,0,0,0,0,0,0,0,0,0,0,0,0,0,0)';
      INPUT_LOAD='(-0.01,0.01)';
    'PE1_TX_DN15':
      PIN_NUMBER='(0,0,0,0,0,0,0,0,0,0,0,0,0,0,0,0,0,BE13,0,0,0,0,0,0,0,0,0,0,0,0,0,0,0,0,0,0,0,0,0,0,0,0)';
      OUTPUT_LOAD='(1.0,-1.0)';
    'PE1_TX_DN14':
      PIN_NUMBER='(0,0,0,0,0,0,0,0,0,0,0,0,0,0,0,0,0,BF14,0,0,0,0,0,0,0,0,0,0,0,0,0,0,0,0,0,0,0,0,0,0,0,0)';
      OUTPUT_LOAD='(1.0,-1.0)';
    'PE1_TX_DN13':
      PIN_NUMBER='(0,0,0,0,0,0,0,0,0,0,0,0,0,0,0,0,0,BJ13,0,0,0,0,0,0,0,0,0,0,0,0,0,0,0,0,0,0,0,0,0,0,0,0)';
      OUTPUT_LOAD='(1.0,-1.0)';
    'PE1_TX_DN12':
      PIN_NUMBER='(0,0,0,0,0,0,0,0,0,0,0,0,0,0,0,0,0,BK14,0,0,0,0,0,0,0,0,0,0,0,0,0,0,0,0,0,0,0,0,0,0,0,0)';
      OUTPUT_LOAD='(1.0,-1.0)';
    'PE1_TX_DN11':
      PIN_NUMBER='(0,0,0,0,0,0,0,0,0,0,0,0,0,0,0,0,0,BN13,0,0,0,0,0,0,0,0,0,0,0,0,0,0,0,0,0,0,0,0,0,0,0,0)';
      OUTPUT_LOAD='(1.0,-1.0)';
    'PE1_TX_DN10':
      PIN_NUMBER='(0,0,0,0,0,0,0,0,0,0,0,0,0,0,0,0,0,BP14,0,0,0,0,0,0,0,0,0,0,0,0,0,0,0,0,0,0,0,0,0,0,0,0)';
      OUTPUT_LOAD='(1.0,-1.0)';
    'PE1_TX_DN9':
      PIN_NUMBER='(0,0,0,0,0,0,0,0,0,0,0,0,0,0,0,0,0,BU13,0,0,0,0,0,0,0,0,0,0,0,0,0,0,0,0,0,0,0,0,0,0,0,0)';
      OUTPUT_LOAD='(1.0,-1.0)';
    'PE1_TX_DN8':
      PIN_NUMBER='(0,0,0,0,0,0,0,0,0,0,0,0,0,0,0,0,0,BV14,0,0,0,0,0,0,0,0,0,0,0,0,0,0,0,0,0,0,0,0,0,0,0,0)';
      OUTPUT_LOAD='(1.0,-1.0)';
    'PE1_TX_DN7':
      PIN_NUMBER='(0,0,0,0,0,0,0,0,0,0,0,0,0,0,0,0,0,CA13,0,0,0,0,0,0,0,0,0,0,0,0,0,0,0,0,0,0,0,0,0,0,0,0)';
      OUTPUT_LOAD='(1.0,-1.0)';
    'PE1_TX_DN6':
      PIN_NUMBER='(0,0,0,0,0,0,0,0,0,0,0,0,0,0,0,0,0,CB14,0,0,0,0,0,0,0,0,0,0,0,0,0,0,0,0,0,0,0,0,0,0,0,0)';
      OUTPUT_LOAD='(1.0,-1.0)';
    'PE1_TX_DN5':
      PIN_NUMBER='(0,0,0,0,0,0,0,0,0,0,0,0,0,0,0,0,0,CE13,0,0,0,0,0,0,0,0,0,0,0,0,0,0,0,0,0,0,0,0,0,0,0,0)';
      OUTPUT_LOAD='(1.0,-1.0)';
    'PE1_TX_DN4':
      PIN_NUMBER='(0,0,0,0,0,0,0,0,0,0,0,0,0,0,0,0,0,CF14,0,0,0,0,0,0,0,0,0,0,0,0,0,0,0,0,0,0,0,0,0,0,0,0)';
      OUTPUT_LOAD='(1.0,-1.0)';
    'PE1_TX_DN3':
      PIN_NUMBER='(0,0,0,0,0,0,0,0,0,0,0,0,0,0,0,0,0,CJ13,0,0,0,0,0,0,0,0,0,0,0,0,0,0,0,0,0,0,0,0,0,0,0,0)';
      OUTPUT_LOAD='(1.0,-1.0)';
    'PE1_TX_DN2':
      PIN_NUMBER='(0,0,0,0,0,0,0,0,0,0,0,0,0,0,0,0,0,CK14,0,0,0,0,0,0,0,0,0,0,0,0,0,0,0,0,0,0,0,0,0,0,0,0)';
      OUTPUT_LOAD='(1.0,-1.0)';
    'PE1_TX_DN1':
      PIN_NUMBER='(0,0,0,0,0,0,0,0,0,0,0,0,0,0,0,0,0,CN13,0,0,0,0,0,0,0,0,0,0,0,0,0,0,0,0,0,0,0,0,0,0,0,0)';
      OUTPUT_LOAD='(1.0,-1.0)';
    'PE1_TX_DN0':
      PIN_NUMBER='(0,0,0,0,0,0,0,0,0,0,0,0,0,0,0,0,0,CP14,0,0,0,0,0,0,0,0,0,0,0,0,0,0,0,0,0,0,0,0,0,0,0,0)';
      OUTPUT_LOAD='(1.0,-1.0)';
    'PE1_TX_DP15':
      PIN_NUMBER='(0,0,0,0,0,0,0,0,0,0,0,0,0,0,0,0,0,BD14,0,0,0,0,0,0,0,0,0,0,0,0,0,0,0,0,0,0,0,0,0,0,0,0)';
      OUTPUT_LOAD='(1.0,-1.0)';
    'PE1_TX_DP14':
      PIN_NUMBER='(0,0,0,0,0,0,0,0,0,0,0,0,0,0,0,0,0,BG15,0,0,0,0,0,0,0,0,0,0,0,0,0,0,0,0,0,0,0,0,0,0,0,0)';
      OUTPUT_LOAD='(1.0,-1.0)';
    'PE1_TX_DP13':
      PIN_NUMBER='(0,0,0,0,0,0,0,0,0,0,0,0,0,0,0,0,0,BH14,0,0,0,0,0,0,0,0,0,0,0,0,0,0,0,0,0,0,0,0,0,0,0,0)';
      OUTPUT_LOAD='(1.0,-1.0)';
    'PE1_TX_DP12':
      PIN_NUMBER='(0,0,0,0,0,0,0,0,0,0,0,0,0,0,0,0,0,BL15,0,0,0,0,0,0,0,0,0,0,0,0,0,0,0,0,0,0,0,0,0,0,0,0)';
      OUTPUT_LOAD='(1.0,-1.0)';
    'PE1_TX_DP11':
      PIN_NUMBER='(0,0,0,0,0,0,0,0,0,0,0,0,0,0,0,0,0,BM14,0,0,0,0,0,0,0,0,0,0,0,0,0,0,0,0,0,0,0,0,0,0,0,0)';
      OUTPUT_LOAD='(1.0,-1.0)';
    'PE1_TX_DP10':
      PIN_NUMBER='(0,0,0,0,0,0,0,0,0,0,0,0,0,0,0,0,0,BR15,0,0,0,0,0,0,0,0,0,0,0,0,0,0,0,0,0,0,0,0,0,0,0,0)';
      OUTPUT_LOAD='(1.0,-1.0)';
    'PE1_TX_DP9':
      PIN_NUMBER='(0,0,0,0,0,0,0,0,0,0,0,0,0,0,0,0,0,BT14,0,0,0,0,0,0,0,0,0,0,0,0,0,0,0,0,0,0,0,0,0,0,0,0)';
      OUTPUT_LOAD='(1.0,-1.0)';
    'PE1_TX_DP8':
      PIN_NUMBER='(0,0,0,0,0,0,0,0,0,0,0,0,0,0,0,0,0,BW15,0,0,0,0,0,0,0,0,0,0,0,0,0,0,0,0,0,0,0,0,0,0,0,0)';
      OUTPUT_LOAD='(1.0,-1.0)';
    'PE1_TX_DP7':
      PIN_NUMBER='(0,0,0,0,0,0,0,0,0,0,0,0,0,0,0,0,0,BY14,0,0,0,0,0,0,0,0,0,0,0,0,0,0,0,0,0,0,0,0,0,0,0,0)';
      OUTPUT_LOAD='(1.0,-1.0)';
    'PE1_TX_DP6':
      PIN_NUMBER='(0,0,0,0,0,0,0,0,0,0,0,0,0,0,0,0,0,CC15,0,0,0,0,0,0,0,0,0,0,0,0,0,0,0,0,0,0,0,0,0,0,0,0)';
      OUTPUT_LOAD='(1.0,-1.0)';
    'PE1_TX_DP5':
      PIN_NUMBER='(0,0,0,0,0,0,0,0,0,0,0,0,0,0,0,0,0,CD14,0,0,0,0,0,0,0,0,0,0,0,0,0,0,0,0,0,0,0,0,0,0,0,0)';
      OUTPUT_LOAD='(1.0,-1.0)';
    'PE1_TX_DP4':
      PIN_NUMBER='(0,0,0,0,0,0,0,0,0,0,0,0,0,0,0,0,0,CG15,0,0,0,0,0,0,0,0,0,0,0,0,0,0,0,0,0,0,0,0,0,0,0,0)';
      OUTPUT_LOAD='(1.0,-1.0)';
    'PE1_TX_DP3':
      PIN_NUMBER='(0,0,0,0,0,0,0,0,0,0,0,0,0,0,0,0,0,CH14,0,0,0,0,0,0,0,0,0,0,0,0,0,0,0,0,0,0,0,0,0,0,0,0)';
      OUTPUT_LOAD='(1.0,-1.0)';
    'PE1_TX_DP2':
      PIN_NUMBER='(0,0,0,0,0,0,0,0,0,0,0,0,0,0,0,0,0,CL15,0,0,0,0,0,0,0,0,0,0,0,0,0,0,0,0,0,0,0,0,0,0,0,0)';
      OUTPUT_LOAD='(1.0,-1.0)';
    'PE1_TX_DP1':
      PIN_NUMBER='(0,0,0,0,0,0,0,0,0,0,0,0,0,0,0,0,0,CM14,0,0,0,0,0,0,0,0,0,0,0,0,0,0,0,0,0,0,0,0,0,0,0,0)';
      OUTPUT_LOAD='(1.0,-1.0)';
    'PE1_TX_DP0':
      PIN_NUMBER='(0,0,0,0,0,0,0,0,0,0,0,0,0,0,0,0,0,CR15,0,0,0,0,0,0,0,0,0,0,0,0,0,0,0,0,0,0,0,0,0,0,0,0)';
      OUTPUT_LOAD='(1.0,-1.0)';
    'PE2_RX_DN15':
      PIN_NUMBER='(0,0,0,0,0,0,0,0,0,0,0,0,0,0,0,0,0,0,EH10,0,0,0,0,0,0,0,0,0,0,0,0,0,0,0,0,0,0,0,0,0,0,0)';
      INPUT_LOAD='(-0.01,0.01)';
    'PE2_RX_DN14':
      PIN_NUMBER='(0,0,0,0,0,0,0,0,0,0,0,0,0,0,0,0,0,0,EE9,0,0,0,0,0,0,0,0,0,0,0,0,0,0,0,0,0,0,0,0,0,0,0)';
      INPUT_LOAD='(-0.01,0.01)';
    'PE2_RX_DN13':
      PIN_NUMBER='(0,0,0,0,0,0,0,0,0,0,0,0,0,0,0,0,0,0,ED10,0,0,0,0,0,0,0,0,0,0,0,0,0,0,0,0,0,0,0,0,0,0,0)';
      INPUT_LOAD='(-0.01,0.01)';
    'PE2_RX_DN12':
      PIN_NUMBER='(0,0,0,0,0,0,0,0,0,0,0,0,0,0,0,0,0,0,EA9,0,0,0,0,0,0,0,0,0,0,0,0,0,0,0,0,0,0,0,0,0,0,0)';
      INPUT_LOAD='(-0.01,0.01)';
    'PE2_RX_DN11':
      PIN_NUMBER='(0,0,0,0,0,0,0,0,0,0,0,0,0,0,0,0,0,0,DY10,0,0,0,0,0,0,0,0,0,0,0,0,0,0,0,0,0,0,0,0,0,0,0)';
      INPUT_LOAD='(-0.01,0.01)';
    'PE2_RX_DN10':
      PIN_NUMBER='(0,0,0,0,0,0,0,0,0,0,0,0,0,0,0,0,0,0,DU9,0,0,0,0,0,0,0,0,0,0,0,0,0,0,0,0,0,0,0,0,0,0,0)';
      INPUT_LOAD='(-0.01,0.01)';
    'PE2_RX_DN9':
      PIN_NUMBER='(0,0,0,0,0,0,0,0,0,0,0,0,0,0,0,0,0,0,DT10,0,0,0,0,0,0,0,0,0,0,0,0,0,0,0,0,0,0,0,0,0,0,0)';
      INPUT_LOAD='(-0.01,0.01)';
    'PE2_RX_DN8':
      PIN_NUMBER='(0,0,0,0,0,0,0,0,0,0,0,0,0,0,0,0,0,0,DN9,0,0,0,0,0,0,0,0,0,0,0,0,0,0,0,0,0,0,0,0,0,0,0)';
      INPUT_LOAD='(-0.01,0.01)';
    'PE2_RX_DN7':
      PIN_NUMBER='(0,0,0,0,0,0,0,0,0,0,0,0,0,0,0,0,0,0,DM10,0,0,0,0,0,0,0,0,0,0,0,0,0,0,0,0,0,0,0,0,0,0,0)';
      INPUT_LOAD='(-0.01,0.01)';
    'PE2_RX_DN6':
      PIN_NUMBER='(0,0,0,0,0,0,0,0,0,0,0,0,0,0,0,0,0,0,DJ9,0,0,0,0,0,0,0,0,0,0,0,0,0,0,0,0,0,0,0,0,0,0,0)';
      INPUT_LOAD='(-0.01,0.01)';
    'PE2_RX_DN5':
      PIN_NUMBER='(0,0,0,0,0,0,0,0,0,0,0,0,0,0,0,0,0,0,DH10,0,0,0,0,0,0,0,0,0,0,0,0,0,0,0,0,0,0,0,0,0,0,0)';
      INPUT_LOAD='(-0.01,0.01)';
    'PE2_RX_DN4':
      PIN_NUMBER='(0,0,0,0,0,0,0,0,0,0,0,0,0,0,0,0,0,0,DE9,0,0,0,0,0,0,0,0,0,0,0,0,0,0,0,0,0,0,0,0,0,0,0)';
      INPUT_LOAD='(-0.01,0.01)';
    'PE2_RX_DN3':
      PIN_NUMBER='(0,0,0,0,0,0,0,0,0,0,0,0,0,0,0,0,0,0,DD10,0,0,0,0,0,0,0,0,0,0,0,0,0,0,0,0,0,0,0,0,0,0,0)';
      INPUT_LOAD='(-0.01,0.01)';
    'PE2_RX_DN2':
      PIN_NUMBER='(0,0,0,0,0,0,0,0,0,0,0,0,0,0,0,0,0,0,DA9,0,0,0,0,0,0,0,0,0,0,0,0,0,0,0,0,0,0,0,0,0,0,0)';
      INPUT_LOAD='(-0.01,0.01)';
    'PE2_RX_DN1':
      PIN_NUMBER='(0,0,0,0,0,0,0,0,0,0,0,0,0,0,0,0,0,0,CY10,0,0,0,0,0,0,0,0,0,0,0,0,0,0,0,0,0,0,0,0,0,0,0)';
      INPUT_LOAD='(-0.01,0.01)';
    'PE2_RX_DN0':
      PIN_NUMBER='(0,0,0,0,0,0,0,0,0,0,0,0,0,0,0,0,0,0,CU9,0,0,0,0,0,0,0,0,0,0,0,0,0,0,0,0,0,0,0,0,0,0,0)';
      INPUT_LOAD='(-0.01,0.01)';
    'PE2_RX_DP15':
      PIN_NUMBER='(0,0,0,0,0,0,0,0,0,0,0,0,0,0,0,0,0,0,EG11,0,0,0,0,0,0,0,0,0,0,0,0,0,0,0,0,0,0,0,0,0,0,0)';
      INPUT_LOAD='(-0.01,0.01)';
    'PE2_RX_DP14':
      PIN_NUMBER='(0,0,0,0,0,0,0,0,0,0,0,0,0,0,0,0,0,0,EF10,0,0,0,0,0,0,0,0,0,0,0,0,0,0,0,0,0,0,0,0,0,0,0)';
      INPUT_LOAD='(-0.01,0.01)';
    'PE2_RX_DP13':
      PIN_NUMBER='(0,0,0,0,0,0,0,0,0,0,0,0,0,0,0,0,0,0,EC11,0,0,0,0,0,0,0,0,0,0,0,0,0,0,0,0,0,0,0,0,0,0,0)';
      INPUT_LOAD='(-0.01,0.01)';
    'PE2_RX_DP12':
      PIN_NUMBER='(0,0,0,0,0,0,0,0,0,0,0,0,0,0,0,0,0,0,EB10,0,0,0,0,0,0,0,0,0,0,0,0,0,0,0,0,0,0,0,0,0,0,0)';
      INPUT_LOAD='(-0.01,0.01)';
    'PE2_RX_DP11':
      PIN_NUMBER='(0,0,0,0,0,0,0,0,0,0,0,0,0,0,0,0,0,0,DW11,0,0,0,0,0,0,0,0,0,0,0,0,0,0,0,0,0,0,0,0,0,0,0)';
      INPUT_LOAD='(-0.01,0.01)';
    'PE2_RX_DP10':
      PIN_NUMBER='(0,0,0,0,0,0,0,0,0,0,0,0,0,0,0,0,0,0,DV10,0,0,0,0,0,0,0,0,0,0,0,0,0,0,0,0,0,0,0,0,0,0,0)';
      INPUT_LOAD='(-0.01,0.01)';
    'PE2_RX_DP9':
      PIN_NUMBER='(0,0,0,0,0,0,0,0,0,0,0,0,0,0,0,0,0,0,DR11,0,0,0,0,0,0,0,0,0,0,0,0,0,0,0,0,0,0,0,0,0,0,0)';
      INPUT_LOAD='(-0.01,0.01)';
    'PE2_RX_DP8':
      PIN_NUMBER='(0,0,0,0,0,0,0,0,0,0,0,0,0,0,0,0,0,0,DP10,0,0,0,0,0,0,0,0,0,0,0,0,0,0,0,0,0,0,0,0,0,0,0)';
      INPUT_LOAD='(-0.01,0.01)';
    'PE2_RX_DP7':
      PIN_NUMBER='(0,0,0,0,0,0,0,0,0,0,0,0,0,0,0,0,0,0,DL11,0,0,0,0,0,0,0,0,0,0,0,0,0,0,0,0,0,0,0,0,0,0,0)';
      INPUT_LOAD='(-0.01,0.01)';
    'PE2_RX_DP6':
      PIN_NUMBER='(0,0,0,0,0,0,0,0,0,0,0,0,0,0,0,0,0,0,DK10,0,0,0,0,0,0,0,0,0,0,0,0,0,0,0,0,0,0,0,0,0,0,0)';
      INPUT_LOAD='(-0.01,0.01)';
    'PE2_RX_DP5':
      PIN_NUMBER='(0,0,0,0,0,0,0,0,0,0,0,0,0,0,0,0,0,0,DG11,0,0,0,0,0,0,0,0,0,0,0,0,0,0,0,0,0,0,0,0,0,0,0)';
      INPUT_LOAD='(-0.01,0.01)';
    'PE2_RX_DP4':
      PIN_NUMBER='(0,0,0,0,0,0,0,0,0,0,0,0,0,0,0,0,0,0,DF10,0,0,0,0,0,0,0,0,0,0,0,0,0,0,0,0,0,0,0,0,0,0,0)';
      INPUT_LOAD='(-0.01,0.01)';
    'PE2_RX_DP3':
      PIN_NUMBER='(0,0,0,0,0,0,0,0,0,0,0,0,0,0,0,0,0,0,DC11,0,0,0,0,0,0,0,0,0,0,0,0,0,0,0,0,0,0,0,0,0,0,0)';
      INPUT_LOAD='(-0.01,0.01)';
    'PE2_RX_DP2':
      PIN_NUMBER='(0,0,0,0,0,0,0,0,0,0,0,0,0,0,0,0,0,0,DB10,0,0,0,0,0,0,0,0,0,0,0,0,0,0,0,0,0,0,0,0,0,0,0)';
      INPUT_LOAD='(-0.01,0.01)';
    'PE2_RX_DP1':
      PIN_NUMBER='(0,0,0,0,0,0,0,0,0,0,0,0,0,0,0,0,0,0,CW11,0,0,0,0,0,0,0,0,0,0,0,0,0,0,0,0,0,0,0,0,0,0,0)';
      INPUT_LOAD='(-0.01,0.01)';
    'PE2_RX_DP0':
      PIN_NUMBER='(0,0,0,0,0,0,0,0,0,0,0,0,0,0,0,0,0,0,CV10,0,0,0,0,0,0,0,0,0,0,0,0,0,0,0,0,0,0,0,0,0,0,0)';
      INPUT_LOAD='(-0.01,0.01)';
    'PE2_TX_DN15':
      PIN_NUMBER='(0,0,0,0,0,0,0,0,0,0,0,0,0,0,0,0,0,0,EF14,0,0,0,0,0,0,0,0,0,0,0,0,0,0,0,0,0,0,0,0,0,0,0)';
      OUTPUT_LOAD='(1.0,-1.0)';
    'PE2_TX_DN14':
      PIN_NUMBER='(0,0,0,0,0,0,0,0,0,0,0,0,0,0,0,0,0,0,EE13,0,0,0,0,0,0,0,0,0,0,0,0,0,0,0,0,0,0,0,0,0,0,0)';
      OUTPUT_LOAD='(1.0,-1.0)';
    'PE2_TX_DN13':
      PIN_NUMBER='(0,0,0,0,0,0,0,0,0,0,0,0,0,0,0,0,0,0,EB14,0,0,0,0,0,0,0,0,0,0,0,0,0,0,0,0,0,0,0,0,0,0,0)';
      OUTPUT_LOAD='(1.0,-1.0)';
    'PE2_TX_DN12':
      PIN_NUMBER='(0,0,0,0,0,0,0,0,0,0,0,0,0,0,0,0,0,0,EA13,0,0,0,0,0,0,0,0,0,0,0,0,0,0,0,0,0,0,0,0,0,0,0)';
      OUTPUT_LOAD='(1.0,-1.0)';
    'PE2_TX_DN11':
      PIN_NUMBER='(0,0,0,0,0,0,0,0,0,0,0,0,0,0,0,0,0,0,DV14,0,0,0,0,0,0,0,0,0,0,0,0,0,0,0,0,0,0,0,0,0,0,0)';
      OUTPUT_LOAD='(1.0,-1.0)';
    'PE2_TX_DN10':
      PIN_NUMBER='(0,0,0,0,0,0,0,0,0,0,0,0,0,0,0,0,0,0,DU13,0,0,0,0,0,0,0,0,0,0,0,0,0,0,0,0,0,0,0,0,0,0,0)';
      OUTPUT_LOAD='(1.0,-1.0)';
    'PE2_TX_DN9':
      PIN_NUMBER='(0,0,0,0,0,0,0,0,0,0,0,0,0,0,0,0,0,0,DP14,0,0,0,0,0,0,0,0,0,0,0,0,0,0,0,0,0,0,0,0,0,0,0)';
      OUTPUT_LOAD='(1.0,-1.0)';
    'PE2_TX_DN8':
      PIN_NUMBER='(0,0,0,0,0,0,0,0,0,0,0,0,0,0,0,0,0,0,DN13,0,0,0,0,0,0,0,0,0,0,0,0,0,0,0,0,0,0,0,0,0,0,0)';
      OUTPUT_LOAD='(1.0,-1.0)';
    'PE2_TX_DN7':
      PIN_NUMBER='(0,0,0,0,0,0,0,0,0,0,0,0,0,0,0,0,0,0,DK14,0,0,0,0,0,0,0,0,0,0,0,0,0,0,0,0,0,0,0,0,0,0,0)';
      OUTPUT_LOAD='(1.0,-1.0)';
    'PE2_TX_DN6':
      PIN_NUMBER='(0,0,0,0,0,0,0,0,0,0,0,0,0,0,0,0,0,0,DJ13,0,0,0,0,0,0,0,0,0,0,0,0,0,0,0,0,0,0,0,0,0,0,0)';
      OUTPUT_LOAD='(1.0,-1.0)';
    'PE2_TX_DN5':
      PIN_NUMBER='(0,0,0,0,0,0,0,0,0,0,0,0,0,0,0,0,0,0,DF14,0,0,0,0,0,0,0,0,0,0,0,0,0,0,0,0,0,0,0,0,0,0,0)';
      OUTPUT_LOAD='(1.0,-1.0)';
    'PE2_TX_DN4':
      PIN_NUMBER='(0,0,0,0,0,0,0,0,0,0,0,0,0,0,0,0,0,0,DE13,0,0,0,0,0,0,0,0,0,0,0,0,0,0,0,0,0,0,0,0,0,0,0)';
      OUTPUT_LOAD='(1.0,-1.0)';
    'PE2_TX_DN3':
      PIN_NUMBER='(0,0,0,0,0,0,0,0,0,0,0,0,0,0,0,0,0,0,DB14,0,0,0,0,0,0,0,0,0,0,0,0,0,0,0,0,0,0,0,0,0,0,0)';
      OUTPUT_LOAD='(1.0,-1.0)';
    'PE2_TX_DN2':
      PIN_NUMBER='(0,0,0,0,0,0,0,0,0,0,0,0,0,0,0,0,0,0,DA13,0,0,0,0,0,0,0,0,0,0,0,0,0,0,0,0,0,0,0,0,0,0,0)';
      OUTPUT_LOAD='(1.0,-1.0)';
    'PE2_TX_DN1':
      PIN_NUMBER='(0,0,0,0,0,0,0,0,0,0,0,0,0,0,0,0,0,0,CV14,0,0,0,0,0,0,0,0,0,0,0,0,0,0,0,0,0,0,0,0,0,0,0)';
      OUTPUT_LOAD='(1.0,-1.0)';
    'PE2_TX_DN0':
      PIN_NUMBER='(0,0,0,0,0,0,0,0,0,0,0,0,0,0,0,0,0,0,CU13,0,0,0,0,0,0,0,0,0,0,0,0,0,0,0,0,0,0,0,0,0,0,0)';
      OUTPUT_LOAD='(1.0,-1.0)';
    'PE2_TX_DP15':
      PIN_NUMBER='(0,0,0,0,0,0,0,0,0,0,0,0,0,0,0,0,0,0,EG15,0,0,0,0,0,0,0,0,0,0,0,0,0,0,0,0,0,0,0,0,0,0,0)';
      OUTPUT_LOAD='(1.0,-1.0)';
    'PE2_TX_DP14':
      PIN_NUMBER='(0,0,0,0,0,0,0,0,0,0,0,0,0,0,0,0,0,0,ED14,0,0,0,0,0,0,0,0,0,0,0,0,0,0,0,0,0,0,0,0,0,0,0)';
      OUTPUT_LOAD='(1.0,-1.0)';
    'PE2_TX_DP13':
      PIN_NUMBER='(0,0,0,0,0,0,0,0,0,0,0,0,0,0,0,0,0,0,EC15,0,0,0,0,0,0,0,0,0,0,0,0,0,0,0,0,0,0,0,0,0,0,0)';
      OUTPUT_LOAD='(1.0,-1.0)';
    'PE2_TX_DP12':
      PIN_NUMBER='(0,0,0,0,0,0,0,0,0,0,0,0,0,0,0,0,0,0,DY14,0,0,0,0,0,0,0,0,0,0,0,0,0,0,0,0,0,0,0,0,0,0,0)';
      OUTPUT_LOAD='(1.0,-1.0)';
    'PE2_TX_DP11':
      PIN_NUMBER='(0,0,0,0,0,0,0,0,0,0,0,0,0,0,0,0,0,0,DW15,0,0,0,0,0,0,0,0,0,0,0,0,0,0,0,0,0,0,0,0,0,0,0)';
      OUTPUT_LOAD='(1.0,-1.0)';
    'PE2_TX_DP10':
      PIN_NUMBER='(0,0,0,0,0,0,0,0,0,0,0,0,0,0,0,0,0,0,DT14,0,0,0,0,0,0,0,0,0,0,0,0,0,0,0,0,0,0,0,0,0,0,0)';
      OUTPUT_LOAD='(1.0,-1.0)';
    'PE2_TX_DP9':
      PIN_NUMBER='(0,0,0,0,0,0,0,0,0,0,0,0,0,0,0,0,0,0,DR15,0,0,0,0,0,0,0,0,0,0,0,0,0,0,0,0,0,0,0,0,0,0,0)';
      OUTPUT_LOAD='(1.0,-1.0)';
    'PE2_TX_DP8':
      PIN_NUMBER='(0,0,0,0,0,0,0,0,0,0,0,0,0,0,0,0,0,0,DM14,0,0,0,0,0,0,0,0,0,0,0,0,0,0,0,0,0,0,0,0,0,0,0)';
      OUTPUT_LOAD='(1.0,-1.0)';
    'PE2_TX_DP7':
      PIN_NUMBER='(0,0,0,0,0,0,0,0,0,0,0,0,0,0,0,0,0,0,DL15,0,0,0,0,0,0,0,0,0,0,0,0,0,0,0,0,0,0,0,0,0,0,0)';
      OUTPUT_LOAD='(1.0,-1.0)';
    'PE2_TX_DP6':
      PIN_NUMBER='(0,0,0,0,0,0,0,0,0,0,0,0,0,0,0,0,0,0,DH14,0,0,0,0,0,0,0,0,0,0,0,0,0,0,0,0,0,0,0,0,0,0,0)';
      OUTPUT_LOAD='(1.0,-1.0)';
    'PE2_TX_DP5':
      PIN_NUMBER='(0,0,0,0,0,0,0,0,0,0,0,0,0,0,0,0,0,0,DG15,0,0,0,0,0,0,0,0,0,0,0,0,0,0,0,0,0,0,0,0,0,0,0)';
      OUTPUT_LOAD='(1.0,-1.0)';
    'PE2_TX_DP4':
      PIN_NUMBER='(0,0,0,0,0,0,0,0,0,0,0,0,0,0,0,0,0,0,DD14,0,0,0,0,0,0,0,0,0,0,0,0,0,0,0,0,0,0,0,0,0,0,0)';
      OUTPUT_LOAD='(1.0,-1.0)';
    'PE2_TX_DP3':
      PIN_NUMBER='(0,0,0,0,0,0,0,0,0,0,0,0,0,0,0,0,0,0,DC15,0,0,0,0,0,0,0,0,0,0,0,0,0,0,0,0,0,0,0,0,0,0,0)';
      OUTPUT_LOAD='(1.0,-1.0)';
    'PE2_TX_DP2':
      PIN_NUMBER='(0,0,0,0,0,0,0,0,0,0,0,0,0,0,0,0,0,0,CY14,0,0,0,0,0,0,0,0,0,0,0,0,0,0,0,0,0,0,0,0,0,0,0)';
      OUTPUT_LOAD='(1.0,-1.0)';
    'PE2_TX_DP1':
      PIN_NUMBER='(0,0,0,0,0,0,0,0,0,0,0,0,0,0,0,0,0,0,CW15,0,0,0,0,0,0,0,0,0,0,0,0,0,0,0,0,0,0,0,0,0,0,0)';
      OUTPUT_LOAD='(1.0,-1.0)';
    'PE2_TX_DP0':
      PIN_NUMBER='(0,0,0,0,0,0,0,0,0,0,0,0,0,0,0,0,0,0,CT14,0,0,0,0,0,0,0,0,0,0,0,0,0,0,0,0,0,0,0,0,0,0,0)';
      OUTPUT_LOAD='(1.0,-1.0)';
    'PE3_RX_DN15':
      PIN_NUMBER='(0,0,0,0,0,0,0,0,0,0,0,0,0,0,0,0,0,0,0,CU90,0,0,0,0,0,0,0,0,0,0,0,0,0,0,0,0,0,0,0,0,0,0)';
      INPUT_LOAD='(-0.01,0.01)';
    'PE3_RX_DN14':
      PIN_NUMBER='(0,0,0,0,0,0,0,0,0,0,0,0,0,0,0,0,0,0,0,CV89,0,0,0,0,0,0,0,0,0,0,0,0,0,0,0,0,0,0,0,0,0,0)';
      INPUT_LOAD='(-0.01,0.01)';
    'PE3_RX_DN13':
      PIN_NUMBER='(0,0,0,0,0,0,0,0,0,0,0,0,0,0,0,0,0,0,0,DA90,0,0,0,0,0,0,0,0,0,0,0,0,0,0,0,0,0,0,0,0,0,0)';
      INPUT_LOAD='(-0.01,0.01)';
    'PE3_RX_DN12':
      PIN_NUMBER='(0,0,0,0,0,0,0,0,0,0,0,0,0,0,0,0,0,0,0,DB89,0,0,0,0,0,0,0,0,0,0,0,0,0,0,0,0,0,0,0,0,0,0)';
      INPUT_LOAD='(-0.01,0.01)';
    'PE3_RX_DN11':
      PIN_NUMBER='(0,0,0,0,0,0,0,0,0,0,0,0,0,0,0,0,0,0,0,DD91,0,0,0,0,0,0,0,0,0,0,0,0,0,0,0,0,0,0,0,0,0,0)';
      INPUT_LOAD='(-0.01,0.01)';
    'PE3_RX_DN10':
      PIN_NUMBER='(0,0,0,0,0,0,0,0,0,0,0,0,0,0,0,0,0,0,0,DG90,0,0,0,0,0,0,0,0,0,0,0,0,0,0,0,0,0,0,0,0,0,0)';
      INPUT_LOAD='(-0.01,0.01)';
    'PE3_RX_DN9':
      PIN_NUMBER='(0,0,0,0,0,0,0,0,0,0,0,0,0,0,0,0,0,0,0,DH91,0,0,0,0,0,0,0,0,0,0,0,0,0,0,0,0,0,0,0,0,0,0)';
      INPUT_LOAD='(-0.01,0.01)';
    'PE3_RX_DN8':
      PIN_NUMBER='(0,0,0,0,0,0,0,0,0,0,0,0,0,0,0,0,0,0,0,DL90,0,0,0,0,0,0,0,0,0,0,0,0,0,0,0,0,0,0,0,0,0,0)';
      INPUT_LOAD='(-0.01,0.01)';
    'PE3_RX_DN7':
      PIN_NUMBER='(0,0,0,0,0,0,0,0,0,0,0,0,0,0,0,0,0,0,0,DN90,0,0,0,0,0,0,0,0,0,0,0,0,0,0,0,0,0,0,0,0,0,0)';
      INPUT_LOAD='(-0.01,0.01)';
    'PE3_RX_DN6':
      PIN_NUMBER='(0,0,0,0,0,0,0,0,0,0,0,0,0,0,0,0,0,0,0,DP89,0,0,0,0,0,0,0,0,0,0,0,0,0,0,0,0,0,0,0,0,0,0)';
      INPUT_LOAD='(-0.01,0.01)';
    'PE3_RX_DN5':
      PIN_NUMBER='(0,0,0,0,0,0,0,0,0,0,0,0,0,0,0,0,0,0,0,DU90,0,0,0,0,0,0,0,0,0,0,0,0,0,0,0,0,0,0,0,0,0,0)';
      INPUT_LOAD='(-0.01,0.01)';
    'PE3_RX_DN4':
      PIN_NUMBER='(0,0,0,0,0,0,0,0,0,0,0,0,0,0,0,0,0,0,0,DV89,0,0,0,0,0,0,0,0,0,0,0,0,0,0,0,0,0,0,0,0,0,0)';
      INPUT_LOAD='(-0.01,0.01)';
    'PE3_RX_DN3':
      PIN_NUMBER='(0,0,0,0,0,0,0,0,0,0,0,0,0,0,0,0,0,0,0,DY91,0,0,0,0,0,0,0,0,0,0,0,0,0,0,0,0,0,0,0,0,0,0)';
      INPUT_LOAD='(-0.01,0.01)';
    'PE3_RX_DN2':
      PIN_NUMBER='(0,0,0,0,0,0,0,0,0,0,0,0,0,0,0,0,0,0,0,EC90,0,0,0,0,0,0,0,0,0,0,0,0,0,0,0,0,0,0,0,0,0,0)';
      INPUT_LOAD='(-0.01,0.01)';
    'PE3_RX_DN1':
      PIN_NUMBER='(0,0,0,0,0,0,0,0,0,0,0,0,0,0,0,0,0,0,0,ED91,0,0,0,0,0,0,0,0,0,0,0,0,0,0,0,0,0,0,0,0,0,0)';
      INPUT_LOAD='(-0.01,0.01)';
    'PE3_RX_DN0':
      PIN_NUMBER='(0,0,0,0,0,0,0,0,0,0,0,0,0,0,0,0,0,0,0,EH89,0,0,0,0,0,0,0,0,0,0,0,0,0,0,0,0,0,0,0,0,0,0)';
      INPUT_LOAD='(-0.01,0.01)';
    'PE3_RX_DP15':
      PIN_NUMBER='(0,0,0,0,0,0,0,0,0,0,0,0,0,0,0,0,0,0,0,CT91,0,0,0,0,0,0,0,0,0,0,0,0,0,0,0,0,0,0,0,0,0,0)';
      INPUT_LOAD='(-0.01,0.01)';
    'PE3_RX_DP14':
      PIN_NUMBER='(0,0,0,0,0,0,0,0,0,0,0,0,0,0,0,0,0,0,0,CW90,0,0,0,0,0,0,0,0,0,0,0,0,0,0,0,0,0,0,0,0,0,0)';
      INPUT_LOAD='(-0.01,0.01)';
    'PE3_RX_DP13':
      PIN_NUMBER='(0,0,0,0,0,0,0,0,0,0,0,0,0,0,0,0,0,0,0,CY91,0,0,0,0,0,0,0,0,0,0,0,0,0,0,0,0,0,0,0,0,0,0)';
      INPUT_LOAD='(-0.01,0.01)';
    'PE3_RX_DP12':
      PIN_NUMBER='(0,0,0,0,0,0,0,0,0,0,0,0,0,0,0,0,0,0,0,DC90,0,0,0,0,0,0,0,0,0,0,0,0,0,0,0,0,0,0,0,0,0,0)';
      INPUT_LOAD='(-0.01,0.01)';
    'PE3_RX_DP11':
      PIN_NUMBER='(0,0,0,0,0,0,0,0,0,0,0,0,0,0,0,0,0,0,0,DE90,0,0,0,0,0,0,0,0,0,0,0,0,0,0,0,0,0,0,0,0,0,0)';
      INPUT_LOAD='(-0.01,0.01)';
    'PE3_RX_DP10':
      PIN_NUMBER='(0,0,0,0,0,0,0,0,0,0,0,0,0,0,0,0,0,0,0,DF89,0,0,0,0,0,0,0,0,0,0,0,0,0,0,0,0,0,0,0,0,0,0)';
      INPUT_LOAD='(-0.01,0.01)';
    'PE3_RX_DP9':
      PIN_NUMBER='(0,0,0,0,0,0,0,0,0,0,0,0,0,0,0,0,0,0,0,DJ90,0,0,0,0,0,0,0,0,0,0,0,0,0,0,0,0,0,0,0,0,0,0)';
      INPUT_LOAD='(-0.01,0.01)';
    'PE3_RX_DP8':
      PIN_NUMBER='(0,0,0,0,0,0,0,0,0,0,0,0,0,0,0,0,0,0,0,DK89,0,0,0,0,0,0,0,0,0,0,0,0,0,0,0,0,0,0,0,0,0,0)';
      INPUT_LOAD='(-0.01,0.01)';
    'PE3_RX_DP7':
      PIN_NUMBER='(0,0,0,0,0,0,0,0,0,0,0,0,0,0,0,0,0,0,0,DM91,0,0,0,0,0,0,0,0,0,0,0,0,0,0,0,0,0,0,0,0,0,0)';
      INPUT_LOAD='(-0.01,0.01)';
    'PE3_RX_DP6':
      PIN_NUMBER='(0,0,0,0,0,0,0,0,0,0,0,0,0,0,0,0,0,0,0,DR90,0,0,0,0,0,0,0,0,0,0,0,0,0,0,0,0,0,0,0,0,0,0)';
      INPUT_LOAD='(-0.01,0.01)';
    'PE3_RX_DP5':
      PIN_NUMBER='(0,0,0,0,0,0,0,0,0,0,0,0,0,0,0,0,0,0,0,DT91,0,0,0,0,0,0,0,0,0,0,0,0,0,0,0,0,0,0,0,0,0,0)';
      INPUT_LOAD='(-0.01,0.01)';
    'PE3_RX_DP4':
      PIN_NUMBER='(0,0,0,0,0,0,0,0,0,0,0,0,0,0,0,0,0,0,0,DW90,0,0,0,0,0,0,0,0,0,0,0,0,0,0,0,0,0,0,0,0,0,0)';
      INPUT_LOAD='(-0.01,0.01)';
    'PE3_RX_DP3':
      PIN_NUMBER='(0,0,0,0,0,0,0,0,0,0,0,0,0,0,0,0,0,0,0,EA90,0,0,0,0,0,0,0,0,0,0,0,0,0,0,0,0,0,0,0,0,0,0)';
      INPUT_LOAD='(-0.01,0.01)';
    'PE3_RX_DP2':
      PIN_NUMBER='(0,0,0,0,0,0,0,0,0,0,0,0,0,0,0,0,0,0,0,EB89,0,0,0,0,0,0,0,0,0,0,0,0,0,0,0,0,0,0,0,0,0,0)';
      INPUT_LOAD='(-0.01,0.01)';
    'PE3_RX_DP1':
      PIN_NUMBER='(0,0,0,0,0,0,0,0,0,0,0,0,0,0,0,0,0,0,0,EE90,0,0,0,0,0,0,0,0,0,0,0,0,0,0,0,0,0,0,0,0,0,0)';
      INPUT_LOAD='(-0.01,0.01)';
    'PE3_RX_DP0':
      PIN_NUMBER='(0,0,0,0,0,0,0,0,0,0,0,0,0,0,0,0,0,0,0,EJ90,0,0,0,0,0,0,0,0,0,0,0,0,0,0,0,0,0,0,0,0,0,0)';
      INPUT_LOAD='(-0.01,0.01)';
    'PE3_TX_DN15':
      PIN_NUMBER='(0,0,0,0,0,0,0,0,0,0,0,0,0,0,0,0,0,0,0,CP85,0,0,0,0,0,0,0,0,0,0,0,0,0,0,0,0,0,0,0,0,0,0)';
      OUTPUT_LOAD='(1.0,-1.0)';
    'PE3_TX_DN14':
      PIN_NUMBER='(0,0,0,0,0,0,0,0,0,0,0,0,0,0,0,0,0,0,0,CT87,0,0,0,0,0,0,0,0,0,0,0,0,0,0,0,0,0,0,0,0,0,0)';
      OUTPUT_LOAD='(1.0,-1.0)';
    'PE3_TX_DN13':
      PIN_NUMBER='(0,0,0,0,0,0,0,0,0,0,0,0,0,0,0,0,0,0,0,CV85,0,0,0,0,0,0,0,0,0,0,0,0,0,0,0,0,0,0,0,0,0,0)';
      OUTPUT_LOAD='(1.0,-1.0)';
    'PE3_TX_DN12':
      PIN_NUMBER='(0,0,0,0,0,0,0,0,0,0,0,0,0,0,0,0,0,0,0,CY87,0,0,0,0,0,0,0,0,0,0,0,0,0,0,0,0,0,0,0,0,0,0)';
      OUTPUT_LOAD='(1.0,-1.0)';
    'PE3_TX_DN11':
      PIN_NUMBER='(0,0,0,0,0,0,0,0,0,0,0,0,0,0,0,0,0,0,0,DB85,0,0,0,0,0,0,0,0,0,0,0,0,0,0,0,0,0,0,0,0,0,0)';
      OUTPUT_LOAD='(1.0,-1.0)';
    'PE3_TX_DN10':
      PIN_NUMBER='(0,0,0,0,0,0,0,0,0,0,0,0,0,0,0,0,0,0,0,DD87,0,0,0,0,0,0,0,0,0,0,0,0,0,0,0,0,0,0,0,0,0,0)';
      OUTPUT_LOAD='(1.0,-1.0)';
    'PE3_TX_DN9':
      PIN_NUMBER='(0,0,0,0,0,0,0,0,0,0,0,0,0,0,0,0,0,0,0,DF85,0,0,0,0,0,0,0,0,0,0,0,0,0,0,0,0,0,0,0,0,0,0)';
      OUTPUT_LOAD='(1.0,-1.0)';
    'PE3_TX_DN8':
      PIN_NUMBER='(0,0,0,0,0,0,0,0,0,0,0,0,0,0,0,0,0,0,0,DH87,0,0,0,0,0,0,0,0,0,0,0,0,0,0,0,0,0,0,0,0,0,0)';
      OUTPUT_LOAD='(1.0,-1.0)';
    'PE3_TX_DN7':
      PIN_NUMBER='(0,0,0,0,0,0,0,0,0,0,0,0,0,0,0,0,0,0,0,DK85,0,0,0,0,0,0,0,0,0,0,0,0,0,0,0,0,0,0,0,0,0,0)';
      OUTPUT_LOAD='(1.0,-1.0)';
    'PE3_TX_DN6':
      PIN_NUMBER='(0,0,0,0,0,0,0,0,0,0,0,0,0,0,0,0,0,0,0,DM87,0,0,0,0,0,0,0,0,0,0,0,0,0,0,0,0,0,0,0,0,0,0)';
      OUTPUT_LOAD='(1.0,-1.0)';
    'PE3_TX_DN5':
      PIN_NUMBER='(0,0,0,0,0,0,0,0,0,0,0,0,0,0,0,0,0,0,0,DP85,0,0,0,0,0,0,0,0,0,0,0,0,0,0,0,0,0,0,0,0,0,0)';
      OUTPUT_LOAD='(1.0,-1.0)';
    'PE3_TX_DN4':
      PIN_NUMBER='(0,0,0,0,0,0,0,0,0,0,0,0,0,0,0,0,0,0,0,DT87,0,0,0,0,0,0,0,0,0,0,0,0,0,0,0,0,0,0,0,0,0,0)';
      OUTPUT_LOAD='(1.0,-1.0)';
    'PE3_TX_DN3':
      PIN_NUMBER='(0,0,0,0,0,0,0,0,0,0,0,0,0,0,0,0,0,0,0,DV85,0,0,0,0,0,0,0,0,0,0,0,0,0,0,0,0,0,0,0,0,0,0)';
      OUTPUT_LOAD='(1.0,-1.0)';
    'PE3_TX_DN2':
      PIN_NUMBER='(0,0,0,0,0,0,0,0,0,0,0,0,0,0,0,0,0,0,0,DY87,0,0,0,0,0,0,0,0,0,0,0,0,0,0,0,0,0,0,0,0,0,0)';
      OUTPUT_LOAD='(1.0,-1.0)';
    'PE3_TX_DN1':
      PIN_NUMBER='(0,0,0,0,0,0,0,0,0,0,0,0,0,0,0,0,0,0,0,EB85,0,0,0,0,0,0,0,0,0,0,0,0,0,0,0,0,0,0,0,0,0,0)';
      OUTPUT_LOAD='(1.0,-1.0)';
    'PE3_TX_DN0':
      PIN_NUMBER='(0,0,0,0,0,0,0,0,0,0,0,0,0,0,0,0,0,0,0,EE86,0,0,0,0,0,0,0,0,0,0,0,0,0,0,0,0,0,0,0,0,0,0)';
      OUTPUT_LOAD='(1.0,-1.0)';
    'PE3_TX_DP15':
      PIN_NUMBER='(0,0,0,0,0,0,0,0,0,0,0,0,0,0,0,0,0,0,0,CR86,0,0,0,0,0,0,0,0,0,0,0,0,0,0,0,0,0,0,0,0,0,0)';
      OUTPUT_LOAD='(1.0,-1.0)';
    'PE3_TX_DP14':
      PIN_NUMBER='(0,0,0,0,0,0,0,0,0,0,0,0,0,0,0,0,0,0,0,CU86,0,0,0,0,0,0,0,0,0,0,0,0,0,0,0,0,0,0,0,0,0,0)';
      OUTPUT_LOAD='(1.0,-1.0)';
    'PE3_TX_DP13':
      PIN_NUMBER='(0,0,0,0,0,0,0,0,0,0,0,0,0,0,0,0,0,0,0,CW86,0,0,0,0,0,0,0,0,0,0,0,0,0,0,0,0,0,0,0,0,0,0)';
      OUTPUT_LOAD='(1.0,-1.0)';
    'PE3_TX_DP12':
      PIN_NUMBER='(0,0,0,0,0,0,0,0,0,0,0,0,0,0,0,0,0,0,0,DA86,0,0,0,0,0,0,0,0,0,0,0,0,0,0,0,0,0,0,0,0,0,0)';
      OUTPUT_LOAD='(1.0,-1.0)';
    'PE3_TX_DP11':
      PIN_NUMBER='(0,0,0,0,0,0,0,0,0,0,0,0,0,0,0,0,0,0,0,DC86,0,0,0,0,0,0,0,0,0,0,0,0,0,0,0,0,0,0,0,0,0,0)';
      OUTPUT_LOAD='(1.0,-1.0)';
    'PE3_TX_DP10':
      PIN_NUMBER='(0,0,0,0,0,0,0,0,0,0,0,0,0,0,0,0,0,0,0,DE86,0,0,0,0,0,0,0,0,0,0,0,0,0,0,0,0,0,0,0,0,0,0)';
      OUTPUT_LOAD='(1.0,-1.0)';
    'PE3_TX_DP9':
      PIN_NUMBER='(0,0,0,0,0,0,0,0,0,0,0,0,0,0,0,0,0,0,0,DG86,0,0,0,0,0,0,0,0,0,0,0,0,0,0,0,0,0,0,0,0,0,0)';
      OUTPUT_LOAD='(1.0,-1.0)';
    'PE3_TX_DP8':
      PIN_NUMBER='(0,0,0,0,0,0,0,0,0,0,0,0,0,0,0,0,0,0,0,DJ86,0,0,0,0,0,0,0,0,0,0,0,0,0,0,0,0,0,0,0,0,0,0)';
      OUTPUT_LOAD='(1.0,-1.0)';
    'PE3_TX_DP7':
      PIN_NUMBER='(0,0,0,0,0,0,0,0,0,0,0,0,0,0,0,0,0,0,0,DL86,0,0,0,0,0,0,0,0,0,0,0,0,0,0,0,0,0,0,0,0,0,0)';
      OUTPUT_LOAD='(1.0,-1.0)';
    'PE3_TX_DP6':
      PIN_NUMBER='(0,0,0,0,0,0,0,0,0,0,0,0,0,0,0,0,0,0,0,DN86,0,0,0,0,0,0,0,0,0,0,0,0,0,0,0,0,0,0,0,0,0,0)';
      OUTPUT_LOAD='(1.0,-1.0)';
    'PE3_TX_DP5':
      PIN_NUMBER='(0,0,0,0,0,0,0,0,0,0,0,0,0,0,0,0,0,0,0,DR86,0,0,0,0,0,0,0,0,0,0,0,0,0,0,0,0,0,0,0,0,0,0)';
      OUTPUT_LOAD='(1.0,-1.0)';
    'PE3_TX_DP4':
      PIN_NUMBER='(0,0,0,0,0,0,0,0,0,0,0,0,0,0,0,0,0,0,0,DU86,0,0,0,0,0,0,0,0,0,0,0,0,0,0,0,0,0,0,0,0,0,0)';
      OUTPUT_LOAD='(1.0,-1.0)';
    'PE3_TX_DP3':
      PIN_NUMBER='(0,0,0,0,0,0,0,0,0,0,0,0,0,0,0,0,0,0,0,DW86,0,0,0,0,0,0,0,0,0,0,0,0,0,0,0,0,0,0,0,0,0,0)';
      OUTPUT_LOAD='(1.0,-1.0)';
    'PE3_TX_DP2':
      PIN_NUMBER='(0,0,0,0,0,0,0,0,0,0,0,0,0,0,0,0,0,0,0,EA86,0,0,0,0,0,0,0,0,0,0,0,0,0,0,0,0,0,0,0,0,0,0)';
      OUTPUT_LOAD='(1.0,-1.0)';
    'PE3_TX_DP1':
      PIN_NUMBER='(0,0,0,0,0,0,0,0,0,0,0,0,0,0,0,0,0,0,0,EC86,0,0,0,0,0,0,0,0,0,0,0,0,0,0,0,0,0,0,0,0,0,0)';
      OUTPUT_LOAD='(1.0,-1.0)';
    'PE3_TX_DP0':
      PIN_NUMBER='(0,0,0,0,0,0,0,0,0,0,0,0,0,0,0,0,0,0,0,ED87,0,0,0,0,0,0,0,0,0,0,0,0,0,0,0,0,0,0,0,0,0,0)';
      OUTPUT_LOAD='(1.0,-1.0)';
    'PE4_RX_DN15':
      PIN_NUMBER='(0,0,0,0,0,0,0,0,0,0,0,0,0,0,0,0,0,0,0,0,BB89,0,0,0,0,0,0,0,0,0,0,0,0,0,0,0,0,0,0,0,0,0)';
      INPUT_LOAD='(-0.01,0.01)';
    'PE4_RX_DN14':
      PIN_NUMBER='(0,0,0,0,0,0,0,0,0,0,0,0,0,0,0,0,0,0,0,0,AY91,0,0,0,0,0,0,0,0,0,0,0,0,0,0,0,0,0,0,0,0,0)';
      INPUT_LOAD='(-0.01,0.01)';
    'PE4_RX_DN13':
      PIN_NUMBER='(0,0,0,0,0,0,0,0,0,0,0,0,0,0,0,0,0,0,0,0,AV89,0,0,0,0,0,0,0,0,0,0,0,0,0,0,0,0,0,0,0,0,0)';
      INPUT_LOAD='(-0.01,0.01)';
    'PE4_RX_DN12':
      PIN_NUMBER='(0,0,0,0,0,0,0,0,0,0,0,0,0,0,0,0,0,0,0,0,AT91,0,0,0,0,0,0,0,0,0,0,0,0,0,0,0,0,0,0,0,0,0)';
      INPUT_LOAD='(-0.01,0.01)';
    'PE4_RX_DN11':
      PIN_NUMBER='(0,0,0,0,0,0,0,0,0,0,0,0,0,0,0,0,0,0,0,0,AP89,0,0,0,0,0,0,0,0,0,0,0,0,0,0,0,0,0,0,0,0,0)';
      INPUT_LOAD='(-0.01,0.01)';
    'PE4_RX_DN10':
      PIN_NUMBER='(0,0,0,0,0,0,0,0,0,0,0,0,0,0,0,0,0,0,0,0,AM91,0,0,0,0,0,0,0,0,0,0,0,0,0,0,0,0,0,0,0,0,0)';
      INPUT_LOAD='(-0.01,0.01)';
    'PE4_RX_DN9':
      PIN_NUMBER='(0,0,0,0,0,0,0,0,0,0,0,0,0,0,0,0,0,0,0,0,AK89,0,0,0,0,0,0,0,0,0,0,0,0,0,0,0,0,0,0,0,0,0)';
      INPUT_LOAD='(-0.01,0.01)';
    'PE4_RX_DN8':
      PIN_NUMBER='(0,0,0,0,0,0,0,0,0,0,0,0,0,0,0,0,0,0,0,0,AH91,0,0,0,0,0,0,0,0,0,0,0,0,0,0,0,0,0,0,0,0,0)';
      INPUT_LOAD='(-0.01,0.01)';
    'PE4_RX_DN7':
      PIN_NUMBER='(0,0,0,0,0,0,0,0,0,0,0,0,0,0,0,0,0,0,0,0,AF89,0,0,0,0,0,0,0,0,0,0,0,0,0,0,0,0,0,0,0,0,0)';
      INPUT_LOAD='(-0.01,0.01)';
    'PE4_RX_DN6':
      PIN_NUMBER='(0,0,0,0,0,0,0,0,0,0,0,0,0,0,0,0,0,0,0,0,AD91,0,0,0,0,0,0,0,0,0,0,0,0,0,0,0,0,0,0,0,0,0)';
      INPUT_LOAD='(-0.01,0.01)';
    'PE4_RX_DN5':
      PIN_NUMBER='(0,0,0,0,0,0,0,0,0,0,0,0,0,0,0,0,0,0,0,0,AB89,0,0,0,0,0,0,0,0,0,0,0,0,0,0,0,0,0,0,0,0,0)';
      INPUT_LOAD='(-0.01,0.01)';
    'PE4_RX_DN4':
      PIN_NUMBER='(0,0,0,0,0,0,0,0,0,0,0,0,0,0,0,0,0,0,0,0,Y91,0,0,0,0,0,0,0,0,0,0,0,0,0,0,0,0,0,0,0,0,0)';
      INPUT_LOAD='(-0.01,0.01)';
    'PE4_RX_DN3':
      PIN_NUMBER='(0,0,0,0,0,0,0,0,0,0,0,0,0,0,0,0,0,0,0,0,V89,0,0,0,0,0,0,0,0,0,0,0,0,0,0,0,0,0,0,0,0,0)';
      INPUT_LOAD='(-0.01,0.01)';
    'PE4_RX_DN2':
      PIN_NUMBER='(0,0,0,0,0,0,0,0,0,0,0,0,0,0,0,0,0,0,0,0,T91,0,0,0,0,0,0,0,0,0,0,0,0,0,0,0,0,0,0,0,0,0)';
      INPUT_LOAD='(-0.01,0.01)';
    'PE4_RX_DN1':
      PIN_NUMBER='(0,0,0,0,0,0,0,0,0,0,0,0,0,0,0,0,0,0,0,0,P89,0,0,0,0,0,0,0,0,0,0,0,0,0,0,0,0,0,0,0,0,0)';
      INPUT_LOAD='(-0.01,0.01)';
    'PE4_RX_DN0':
      PIN_NUMBER='(0,0,0,0,0,0,0,0,0,0,0,0,0,0,0,0,0,0,0,0,J90,0,0,0,0,0,0,0,0,0,0,0,0,0,0,0,0,0,0,0,0,0)';
      INPUT_LOAD='(-0.01,0.01)';
    'PE4_RX_DP15':
      PIN_NUMBER='(0,0,0,0,0,0,0,0,0,0,0,0,0,0,0,0,0,0,0,0,BA90,0,0,0,0,0,0,0,0,0,0,0,0,0,0,0,0,0,0,0,0,0)';
      INPUT_LOAD='(-0.01,0.01)';
    'PE4_RX_DP14':
      PIN_NUMBER='(0,0,0,0,0,0,0,0,0,0,0,0,0,0,0,0,0,0,0,0,AW90,0,0,0,0,0,0,0,0,0,0,0,0,0,0,0,0,0,0,0,0,0)';
      INPUT_LOAD='(-0.01,0.01)';
    'PE4_RX_DP13':
      PIN_NUMBER='(0,0,0,0,0,0,0,0,0,0,0,0,0,0,0,0,0,0,0,0,AU90,0,0,0,0,0,0,0,0,0,0,0,0,0,0,0,0,0,0,0,0,0)';
      INPUT_LOAD='(-0.01,0.01)';
    'PE4_RX_DP12':
      PIN_NUMBER='(0,0,0,0,0,0,0,0,0,0,0,0,0,0,0,0,0,0,0,0,AR90,0,0,0,0,0,0,0,0,0,0,0,0,0,0,0,0,0,0,0,0,0)';
      INPUT_LOAD='(-0.01,0.01)';
    'PE4_RX_DP11':
      PIN_NUMBER='(0,0,0,0,0,0,0,0,0,0,0,0,0,0,0,0,0,0,0,0,AN90,0,0,0,0,0,0,0,0,0,0,0,0,0,0,0,0,0,0,0,0,0)';
      INPUT_LOAD='(-0.01,0.01)';
    'PE4_RX_DP10':
      PIN_NUMBER='(0,0,0,0,0,0,0,0,0,0,0,0,0,0,0,0,0,0,0,0,AL90,0,0,0,0,0,0,0,0,0,0,0,0,0,0,0,0,0,0,0,0,0)';
      INPUT_LOAD='(-0.01,0.01)';
    'PE4_RX_DP9':
      PIN_NUMBER='(0,0,0,0,0,0,0,0,0,0,0,0,0,0,0,0,0,0,0,0,AJ90,0,0,0,0,0,0,0,0,0,0,0,0,0,0,0,0,0,0,0,0,0)';
      INPUT_LOAD='(-0.01,0.01)';
    'PE4_RX_DP8':
      PIN_NUMBER='(0,0,0,0,0,0,0,0,0,0,0,0,0,0,0,0,0,0,0,0,AG90,0,0,0,0,0,0,0,0,0,0,0,0,0,0,0,0,0,0,0,0,0)';
      INPUT_LOAD='(-0.01,0.01)';
    'PE4_RX_DP7':
      PIN_NUMBER='(0,0,0,0,0,0,0,0,0,0,0,0,0,0,0,0,0,0,0,0,AE90,0,0,0,0,0,0,0,0,0,0,0,0,0,0,0,0,0,0,0,0,0)';
      INPUT_LOAD='(-0.01,0.01)';
    'PE4_RX_DP6':
      PIN_NUMBER='(0,0,0,0,0,0,0,0,0,0,0,0,0,0,0,0,0,0,0,0,AC90,0,0,0,0,0,0,0,0,0,0,0,0,0,0,0,0,0,0,0,0,0)';
      INPUT_LOAD='(-0.01,0.01)';
    'PE4_RX_DP5':
      PIN_NUMBER='(0,0,0,0,0,0,0,0,0,0,0,0,0,0,0,0,0,0,0,0,AA90,0,0,0,0,0,0,0,0,0,0,0,0,0,0,0,0,0,0,0,0,0)';
      INPUT_LOAD='(-0.01,0.01)';
    'PE4_RX_DP4':
      PIN_NUMBER='(0,0,0,0,0,0,0,0,0,0,0,0,0,0,0,0,0,0,0,0,W90,0,0,0,0,0,0,0,0,0,0,0,0,0,0,0,0,0,0,0,0,0)';
      INPUT_LOAD='(-0.01,0.01)';
    'PE4_RX_DP3':
      PIN_NUMBER='(0,0,0,0,0,0,0,0,0,0,0,0,0,0,0,0,0,0,0,0,U90,0,0,0,0,0,0,0,0,0,0,0,0,0,0,0,0,0,0,0,0,0)';
      INPUT_LOAD='(-0.01,0.01)';
    'PE4_RX_DP2':
      PIN_NUMBER='(0,0,0,0,0,0,0,0,0,0,0,0,0,0,0,0,0,0,0,0,R90,0,0,0,0,0,0,0,0,0,0,0,0,0,0,0,0,0,0,0,0,0)';
      INPUT_LOAD='(-0.01,0.01)';
    'PE4_RX_DP1':
      PIN_NUMBER='(0,0,0,0,0,0,0,0,0,0,0,0,0,0,0,0,0,0,0,0,N90,0,0,0,0,0,0,0,0,0,0,0,0,0,0,0,0,0,0,0,0,0)';
      INPUT_LOAD='(-0.01,0.01)';
    'PE4_RX_DP0':
      PIN_NUMBER='(0,0,0,0,0,0,0,0,0,0,0,0,0,0,0,0,0,0,0,0,K89,0,0,0,0,0,0,0,0,0,0,0,0,0,0,0,0,0,0,0,0,0)';
      INPUT_LOAD='(-0.01,0.01)';
    'PE4_TX_DN15':
      PIN_NUMBER='(0,0,0,0,0,0,0,0,0,0,0,0,0,0,0,0,0,0,0,0,BA86,0,0,0,0,0,0,0,0,0,0,0,0,0,0,0,0,0,0,0,0,0)';
      OUTPUT_LOAD='(1.0,-1.0)';
    'PE4_TX_DN14':
      PIN_NUMBER='(0,0,0,0,0,0,0,0,0,0,0,0,0,0,0,0,0,0,0,0,AW86,0,0,0,0,0,0,0,0,0,0,0,0,0,0,0,0,0,0,0,0,0)';
      OUTPUT_LOAD='(1.0,-1.0)';
    'PE4_TX_DN13':
      PIN_NUMBER='(0,0,0,0,0,0,0,0,0,0,0,0,0,0,0,0,0,0,0,0,AU86,0,0,0,0,0,0,0,0,0,0,0,0,0,0,0,0,0,0,0,0,0)';
      OUTPUT_LOAD='(1.0,-1.0)';
    'PE4_TX_DN12':
      PIN_NUMBER='(0,0,0,0,0,0,0,0,0,0,0,0,0,0,0,0,0,0,0,0,AR86,0,0,0,0,0,0,0,0,0,0,0,0,0,0,0,0,0,0,0,0,0)';
      OUTPUT_LOAD='(1.0,-1.0)';
    'PE4_TX_DN11':
      PIN_NUMBER='(0,0,0,0,0,0,0,0,0,0,0,0,0,0,0,0,0,0,0,0,AP85,0,0,0,0,0,0,0,0,0,0,0,0,0,0,0,0,0,0,0,0,0)';
      OUTPUT_LOAD='(1.0,-1.0)';
    'PE4_TX_DN10':
      PIN_NUMBER='(0,0,0,0,0,0,0,0,0,0,0,0,0,0,0,0,0,0,0,0,AL86,0,0,0,0,0,0,0,0,0,0,0,0,0,0,0,0,0,0,0,0,0)';
      OUTPUT_LOAD='(1.0,-1.0)';
    'PE4_TX_DN9':
      PIN_NUMBER='(0,0,0,0,0,0,0,0,0,0,0,0,0,0,0,0,0,0,0,0,AJ86,0,0,0,0,0,0,0,0,0,0,0,0,0,0,0,0,0,0,0,0,0)';
      OUTPUT_LOAD='(1.0,-1.0)';
    'PE4_TX_DN8':
      PIN_NUMBER='(0,0,0,0,0,0,0,0,0,0,0,0,0,0,0,0,0,0,0,0,AG86,0,0,0,0,0,0,0,0,0,0,0,0,0,0,0,0,0,0,0,0,0)';
      OUTPUT_LOAD='(1.0,-1.0)';
    'PE4_TX_DN7':
      PIN_NUMBER='(0,0,0,0,0,0,0,0,0,0,0,0,0,0,0,0,0,0,0,0,AE86,0,0,0,0,0,0,0,0,0,0,0,0,0,0,0,0,0,0,0,0,0)';
      OUTPUT_LOAD='(1.0,-1.0)';
    'PE4_TX_DN6':
      PIN_NUMBER='(0,0,0,0,0,0,0,0,0,0,0,0,0,0,0,0,0,0,0,0,AC86,0,0,0,0,0,0,0,0,0,0,0,0,0,0,0,0,0,0,0,0,0)';
      OUTPUT_LOAD='(1.0,-1.0)';
    'PE4_TX_DN5':
      PIN_NUMBER='(0,0,0,0,0,0,0,0,0,0,0,0,0,0,0,0,0,0,0,0,AA86,0,0,0,0,0,0,0,0,0,0,0,0,0,0,0,0,0,0,0,0,0)';
      OUTPUT_LOAD='(1.0,-1.0)';
    'PE4_TX_DN4':
      PIN_NUMBER='(0,0,0,0,0,0,0,0,0,0,0,0,0,0,0,0,0,0,0,0,W86,0,0,0,0,0,0,0,0,0,0,0,0,0,0,0,0,0,0,0,0,0)';
      OUTPUT_LOAD='(1.0,-1.0)';
    'PE4_TX_DN3':
      PIN_NUMBER='(0,0,0,0,0,0,0,0,0,0,0,0,0,0,0,0,0,0,0,0,U86,0,0,0,0,0,0,0,0,0,0,0,0,0,0,0,0,0,0,0,0,0)';
      OUTPUT_LOAD='(1.0,-1.0)';
    'PE4_TX_DN2':
      PIN_NUMBER='(0,0,0,0,0,0,0,0,0,0,0,0,0,0,0,0,0,0,0,0,R86,0,0,0,0,0,0,0,0,0,0,0,0,0,0,0,0,0,0,0,0,0)';
      OUTPUT_LOAD='(1.0,-1.0)';
    'PE4_TX_DN1':
      PIN_NUMBER='(0,0,0,0,0,0,0,0,0,0,0,0,0,0,0,0,0,0,0,0,P85,0,0,0,0,0,0,0,0,0,0,0,0,0,0,0,0,0,0,0,0,0)';
      OUTPUT_LOAD='(1.0,-1.0)';
    'PE4_TX_DN0':
      PIN_NUMBER='(0,0,0,0,0,0,0,0,0,0,0,0,0,0,0,0,0,0,0,0,L86,0,0,0,0,0,0,0,0,0,0,0,0,0,0,0,0,0,0,0,0,0)';
      OUTPUT_LOAD='(1.0,-1.0)';
    'PE4_TX_DP15':
      PIN_NUMBER='(0,0,0,0,0,0,0,0,0,0,0,0,0,0,0,0,0,0,0,0,BB85,0,0,0,0,0,0,0,0,0,0,0,0,0,0,0,0,0,0,0,0,0)';
      OUTPUT_LOAD='(1.0,-1.0)';
    'PE4_TX_DP14':
      PIN_NUMBER='(0,0,0,0,0,0,0,0,0,0,0,0,0,0,0,0,0,0,0,0,AY87,0,0,0,0,0,0,0,0,0,0,0,0,0,0,0,0,0,0,0,0,0)';
      OUTPUT_LOAD='(1.0,-1.0)';
    'PE4_TX_DP13':
      PIN_NUMBER='(0,0,0,0,0,0,0,0,0,0,0,0,0,0,0,0,0,0,0,0,AV85,0,0,0,0,0,0,0,0,0,0,0,0,0,0,0,0,0,0,0,0,0)';
      OUTPUT_LOAD='(1.0,-1.0)';
    'PE4_TX_DP12':
      PIN_NUMBER='(0,0,0,0,0,0,0,0,0,0,0,0,0,0,0,0,0,0,0,0,AT87,0,0,0,0,0,0,0,0,0,0,0,0,0,0,0,0,0,0,0,0,0)';
      OUTPUT_LOAD='(1.0,-1.0)';
    'PE4_TX_DP11':
      PIN_NUMBER='(0,0,0,0,0,0,0,0,0,0,0,0,0,0,0,0,0,0,0,0,AN86,0,0,0,0,0,0,0,0,0,0,0,0,0,0,0,0,0,0,0,0,0)';
      OUTPUT_LOAD='(1.0,-1.0)';
    'PE4_TX_DP10':
      PIN_NUMBER='(0,0,0,0,0,0,0,0,0,0,0,0,0,0,0,0,0,0,0,0,AM87,0,0,0,0,0,0,0,0,0,0,0,0,0,0,0,0,0,0,0,0,0)';
      OUTPUT_LOAD='(1.0,-1.0)';
    'PE4_TX_DP9':
      PIN_NUMBER='(0,0,0,0,0,0,0,0,0,0,0,0,0,0,0,0,0,0,0,0,AK85,0,0,0,0,0,0,0,0,0,0,0,0,0,0,0,0,0,0,0,0,0)';
      OUTPUT_LOAD='(1.0,-1.0)';
    'PE4_TX_DP8':
      PIN_NUMBER='(0,0,0,0,0,0,0,0,0,0,0,0,0,0,0,0,0,0,0,0,AH87,0,0,0,0,0,0,0,0,0,0,0,0,0,0,0,0,0,0,0,0,0)';
      OUTPUT_LOAD='(1.0,-1.0)';
    'PE4_TX_DP7':
      PIN_NUMBER='(0,0,0,0,0,0,0,0,0,0,0,0,0,0,0,0,0,0,0,0,AF85,0,0,0,0,0,0,0,0,0,0,0,0,0,0,0,0,0,0,0,0,0)';
      OUTPUT_LOAD='(1.0,-1.0)';
    'PE4_TX_DP6':
      PIN_NUMBER='(0,0,0,0,0,0,0,0,0,0,0,0,0,0,0,0,0,0,0,0,AD87,0,0,0,0,0,0,0,0,0,0,0,0,0,0,0,0,0,0,0,0,0)';
      OUTPUT_LOAD='(1.0,-1.0)';
    'PE4_TX_DP5':
      PIN_NUMBER='(0,0,0,0,0,0,0,0,0,0,0,0,0,0,0,0,0,0,0,0,AB85,0,0,0,0,0,0,0,0,0,0,0,0,0,0,0,0,0,0,0,0,0)';
      OUTPUT_LOAD='(1.0,-1.0)';
    'PE4_TX_DP4':
      PIN_NUMBER='(0,0,0,0,0,0,0,0,0,0,0,0,0,0,0,0,0,0,0,0,Y87,0,0,0,0,0,0,0,0,0,0,0,0,0,0,0,0,0,0,0,0,0)';
      OUTPUT_LOAD='(1.0,-1.0)';
    'PE4_TX_DP3':
      PIN_NUMBER='(0,0,0,0,0,0,0,0,0,0,0,0,0,0,0,0,0,0,0,0,V85,0,0,0,0,0,0,0,0,0,0,0,0,0,0,0,0,0,0,0,0,0)';
      OUTPUT_LOAD='(1.0,-1.0)';
    'PE4_TX_DP2':
      PIN_NUMBER='(0,0,0,0,0,0,0,0,0,0,0,0,0,0,0,0,0,0,0,0,T87,0,0,0,0,0,0,0,0,0,0,0,0,0,0,0,0,0,0,0,0,0)';
      OUTPUT_LOAD='(1.0,-1.0)';
    'PE4_TX_DP1':
      PIN_NUMBER='(0,0,0,0,0,0,0,0,0,0,0,0,0,0,0,0,0,0,0,0,N86,0,0,0,0,0,0,0,0,0,0,0,0,0,0,0,0,0,0,0,0,0)';
      OUTPUT_LOAD='(1.0,-1.0)';
    'PE4_TX_DP0':
      PIN_NUMBER='(0,0,0,0,0,0,0,0,0,0,0,0,0,0,0,0,0,0,0,0,M87,0,0,0,0,0,0,0,0,0,0,0,0,0,0,0,0,0,0,0,0,0)';
      OUTPUT_LOAD='(1.0,-1.0)';
    'UPI0_RX_DN23':
      PIN_NUMBER='(0,0,0,0,0,0,0,0,0,0,0,0,0,0,0,0,0,0,0,0,0,BU5,0,0,0,0,0,0,0,0,0,0,0,0,0,0,0,0,0,0,0,0)';
      INPUT_LOAD='(-0.01,0.01)';
    'UPI0_RX_DN22':
      PIN_NUMBER='(0,0,0,0,0,0,0,0,0,0,0,0,0,0,0,0,0,0,0,0,0,BR7,0,0,0,0,0,0,0,0,0,0,0,0,0,0,0,0,0,0,0,0)';
      INPUT_LOAD='(-0.01,0.01)';
    'UPI0_RX_DN21':
      PIN_NUMBER='(0,0,0,0,0,0,0,0,0,0,0,0,0,0,0,0,0,0,0,0,0,BN5,0,0,0,0,0,0,0,0,0,0,0,0,0,0,0,0,0,0,0,0)';
      INPUT_LOAD='(-0.01,0.01)';
    'UPI0_RX_DN20':
      PIN_NUMBER='(0,0,0,0,0,0,0,0,0,0,0,0,0,0,0,0,0,0,0,0,0,BK6,0,0,0,0,0,0,0,0,0,0,0,0,0,0,0,0,0,0,0,0)';
      INPUT_LOAD='(-0.01,0.01)';
    'UPI0_RX_DN19':
      PIN_NUMBER='(0,0,0,0,0,0,0,0,0,0,0,0,0,0,0,0,0,0,0,0,0,BJ5,0,0,0,0,0,0,0,0,0,0,0,0,0,0,0,0,0,0,0,0)';
      INPUT_LOAD='(-0.01,0.01)';
    'UPI0_RX_DN18':
      PIN_NUMBER='(0,0,0,0,0,0,0,0,0,0,0,0,0,0,0,0,0,0,0,0,0,BF6,0,0,0,0,0,0,0,0,0,0,0,0,0,0,0,0,0,0,0,0)';
      INPUT_LOAD='(-0.01,0.01)';
    'UPI0_RX_DN17':
      PIN_NUMBER='(0,0,0,0,0,0,0,0,0,0,0,0,0,0,0,0,0,0,0,0,0,BE5,0,0,0,0,0,0,0,0,0,0,0,0,0,0,0,0,0,0,0,0)';
      INPUT_LOAD='(-0.01,0.01)';
    'UPI0_RX_DN16':
      PIN_NUMBER='(0,0,0,0,0,0,0,0,0,0,0,0,0,0,0,0,0,0,0,0,0,BB6,0,0,0,0,0,0,0,0,0,0,0,0,0,0,0,0,0,0,0,0)';
      INPUT_LOAD='(-0.01,0.01)';
    'UPI0_RX_DN15':
      PIN_NUMBER='(0,0,0,0,0,0,0,0,0,0,0,0,0,0,0,0,0,0,0,0,0,BA5,0,0,0,0,0,0,0,0,0,0,0,0,0,0,0,0,0,0,0,0)';
      INPUT_LOAD='(-0.01,0.01)';
    'UPI0_RX_DN14':
      PIN_NUMBER='(0,0,0,0,0,0,0,0,0,0,0,0,0,0,0,0,0,0,0,0,0,AV6,0,0,0,0,0,0,0,0,0,0,0,0,0,0,0,0,0,0,0,0)';
      INPUT_LOAD='(-0.01,0.01)';
    'UPI0_RX_DN13':
      PIN_NUMBER='(0,0,0,0,0,0,0,0,0,0,0,0,0,0,0,0,0,0,0,0,0,AU5,0,0,0,0,0,0,0,0,0,0,0,0,0,0,0,0,0,0,0,0)';
      INPUT_LOAD='(-0.01,0.01)';
    'UPI0_RX_DN12':
      PIN_NUMBER='(0,0,0,0,0,0,0,0,0,0,0,0,0,0,0,0,0,0,0,0,0,AP6,0,0,0,0,0,0,0,0,0,0,0,0,0,0,0,0,0,0,0,0)';
      INPUT_LOAD='(-0.01,0.01)';
    'UPI0_RX_DN11':
      PIN_NUMBER='(0,0,0,0,0,0,0,0,0,0,0,0,0,0,0,0,0,0,0,0,0,AN5,0,0,0,0,0,0,0,0,0,0,0,0,0,0,0,0,0,0,0,0)';
      INPUT_LOAD='(-0.01,0.01)';
    'UPI0_RX_DN10':
      PIN_NUMBER='(0,0,0,0,0,0,0,0,0,0,0,0,0,0,0,0,0,0,0,0,0,AK6,0,0,0,0,0,0,0,0,0,0,0,0,0,0,0,0,0,0,0,0)';
      INPUT_LOAD='(-0.01,0.01)';
    'UPI0_RX_DN9':
      PIN_NUMBER='(0,0,0,0,0,0,0,0,0,0,0,0,0,0,0,0,0,0,0,0,0,AH6,0,0,0,0,0,0,0,0,0,0,0,0,0,0,0,0,0,0,0,0)';
      INPUT_LOAD='(-0.01,0.01)';
    'UPI0_RX_DN8':
      PIN_NUMBER='(0,0,0,0,0,0,0,0,0,0,0,0,0,0,0,0,0,0,0,0,0,AF6,0,0,0,0,0,0,0,0,0,0,0,0,0,0,0,0,0,0,0,0)';
      INPUT_LOAD='(-0.01,0.01)';
    'UPI0_RX_DN7':
      PIN_NUMBER='(0,0,0,0,0,0,0,0,0,0,0,0,0,0,0,0,0,0,0,0,0,AE5,0,0,0,0,0,0,0,0,0,0,0,0,0,0,0,0,0,0,0,0)';
      INPUT_LOAD='(-0.01,0.01)';
    'UPI0_RX_DN6':
      PIN_NUMBER='(0,0,0,0,0,0,0,0,0,0,0,0,0,0,0,0,0,0,0,0,0,AB6,0,0,0,0,0,0,0,0,0,0,0,0,0,0,0,0,0,0,0,0)';
      INPUT_LOAD='(-0.01,0.01)';
    'UPI0_RX_DN5':
      PIN_NUMBER='(0,0,0,0,0,0,0,0,0,0,0,0,0,0,0,0,0,0,0,0,0,AA5,0,0,0,0,0,0,0,0,0,0,0,0,0,0,0,0,0,0,0,0)';
      INPUT_LOAD='(-0.01,0.01)';
    'UPI0_RX_DN4':
      PIN_NUMBER='(0,0,0,0,0,0,0,0,0,0,0,0,0,0,0,0,0,0,0,0,0,V6,0,0,0,0,0,0,0,0,0,0,0,0,0,0,0,0,0,0,0,0)';
      INPUT_LOAD='(-0.01,0.01)';
    'UPI0_RX_DN3':
      PIN_NUMBER='(0,0,0,0,0,0,0,0,0,0,0,0,0,0,0,0,0,0,0,0,0,U5,0,0,0,0,0,0,0,0,0,0,0,0,0,0,0,0,0,0,0,0)';
      INPUT_LOAD='(-0.01,0.01)';
    'UPI0_RX_DN2':
      PIN_NUMBER='(0,0,0,0,0,0,0,0,0,0,0,0,0,0,0,0,0,0,0,0,0,P6,0,0,0,0,0,0,0,0,0,0,0,0,0,0,0,0,0,0,0,0)';
      INPUT_LOAD='(-0.01,0.01)';
    'UPI0_RX_DN1':
      PIN_NUMBER='(0,0,0,0,0,0,0,0,0,0,0,0,0,0,0,0,0,0,0,0,0,N5,0,0,0,0,0,0,0,0,0,0,0,0,0,0,0,0,0,0,0,0)';
      INPUT_LOAD='(-0.01,0.01)';
    'UPI0_RX_DN0':
      PIN_NUMBER='(0,0,0,0,0,0,0,0,0,0,0,0,0,0,0,0,0,0,0,0,0,K6,0,0,0,0,0,0,0,0,0,0,0,0,0,0,0,0,0,0,0,0)';
      INPUT_LOAD='(-0.01,0.01)';
    'UPI0_RX_DP23':
      PIN_NUMBER='(0,0,0,0,0,0,0,0,0,0,0,0,0,0,0,0,0,0,0,0,0,BT6,0,0,0,0,0,0,0,0,0,0,0,0,0,0,0,0,0,0,0,0)';
      INPUT_LOAD='(-0.01,0.01)';
    'UPI0_RX_DP22':
      PIN_NUMBER='(0,0,0,0,0,0,0,0,0,0,0,0,0,0,0,0,0,0,0,0,0,BP6,0,0,0,0,0,0,0,0,0,0,0,0,0,0,0,0,0,0,0,0)';
      INPUT_LOAD='(-0.01,0.01)';
    'UPI0_RX_DP21':
      PIN_NUMBER='(0,0,0,0,0,0,0,0,0,0,0,0,0,0,0,0,0,0,0,0,0,BM6,0,0,0,0,0,0,0,0,0,0,0,0,0,0,0,0,0,0,0,0)';
      INPUT_LOAD='(-0.01,0.01)';
    'UPI0_RX_DP20':
      PIN_NUMBER='(0,0,0,0,0,0,0,0,0,0,0,0,0,0,0,0,0,0,0,0,0,BL7,0,0,0,0,0,0,0,0,0,0,0,0,0,0,0,0,0,0,0,0)';
      INPUT_LOAD='(-0.01,0.01)';
    'UPI0_RX_DP19':
      PIN_NUMBER='(0,0,0,0,0,0,0,0,0,0,0,0,0,0,0,0,0,0,0,0,0,BH6,0,0,0,0,0,0,0,0,0,0,0,0,0,0,0,0,0,0,0,0)';
      INPUT_LOAD='(-0.01,0.01)';
    'UPI0_RX_DP18':
      PIN_NUMBER='(0,0,0,0,0,0,0,0,0,0,0,0,0,0,0,0,0,0,0,0,0,BG7,0,0,0,0,0,0,0,0,0,0,0,0,0,0,0,0,0,0,0,0)';
      INPUT_LOAD='(-0.01,0.01)';
    'UPI0_RX_DP17':
      PIN_NUMBER='(0,0,0,0,0,0,0,0,0,0,0,0,0,0,0,0,0,0,0,0,0,BD6,0,0,0,0,0,0,0,0,0,0,0,0,0,0,0,0,0,0,0,0)';
      INPUT_LOAD='(-0.01,0.01)';
    'UPI0_RX_DP16':
      PIN_NUMBER='(0,0,0,0,0,0,0,0,0,0,0,0,0,0,0,0,0,0,0,0,0,BC7,0,0,0,0,0,0,0,0,0,0,0,0,0,0,0,0,0,0,0,0)';
      INPUT_LOAD='(-0.01,0.01)';
    'UPI0_RX_DP15':
      PIN_NUMBER='(0,0,0,0,0,0,0,0,0,0,0,0,0,0,0,0,0,0,0,0,0,AY6,0,0,0,0,0,0,0,0,0,0,0,0,0,0,0,0,0,0,0,0)';
      INPUT_LOAD='(-0.01,0.01)';
    'UPI0_RX_DP14':
      PIN_NUMBER='(0,0,0,0,0,0,0,0,0,0,0,0,0,0,0,0,0,0,0,0,0,AW7,0,0,0,0,0,0,0,0,0,0,0,0,0,0,0,0,0,0,0,0)';
      INPUT_LOAD='(-0.01,0.01)';
    'UPI0_RX_DP13':
      PIN_NUMBER='(0,0,0,0,0,0,0,0,0,0,0,0,0,0,0,0,0,0,0,0,0,AT6,0,0,0,0,0,0,0,0,0,0,0,0,0,0,0,0,0,0,0,0)';
      INPUT_LOAD='(-0.01,0.01)';
    'UPI0_RX_DP12':
      PIN_NUMBER='(0,0,0,0,0,0,0,0,0,0,0,0,0,0,0,0,0,0,0,0,0,AR7,0,0,0,0,0,0,0,0,0,0,0,0,0,0,0,0,0,0,0,0)';
      INPUT_LOAD='(-0.01,0.01)';
    'UPI0_RX_DP11':
      PIN_NUMBER='(0,0,0,0,0,0,0,0,0,0,0,0,0,0,0,0,0,0,0,0,0,AM6,0,0,0,0,0,0,0,0,0,0,0,0,0,0,0,0,0,0,0,0)';
      INPUT_LOAD='(-0.01,0.01)';
    'UPI0_RX_DP10':
      PIN_NUMBER='(0,0,0,0,0,0,0,0,0,0,0,0,0,0,0,0,0,0,0,0,0,AL7,0,0,0,0,0,0,0,0,0,0,0,0,0,0,0,0,0,0,0,0)';
      INPUT_LOAD='(-0.01,0.01)';
    'UPI0_RX_DP9':
      PIN_NUMBER='(0,0,0,0,0,0,0,0,0,0,0,0,0,0,0,0,0,0,0,0,0,AJ5,0,0,0,0,0,0,0,0,0,0,0,0,0,0,0,0,0,0,0,0)';
      INPUT_LOAD='(-0.01,0.01)';
    'UPI0_RX_DP8':
      PIN_NUMBER='(0,0,0,0,0,0,0,0,0,0,0,0,0,0,0,0,0,0,0,0,0,AG7,0,0,0,0,0,0,0,0,0,0,0,0,0,0,0,0,0,0,0,0)';
      INPUT_LOAD='(-0.01,0.01)';
    'UPI0_RX_DP7':
      PIN_NUMBER='(0,0,0,0,0,0,0,0,0,0,0,0,0,0,0,0,0,0,0,0,0,AD6,0,0,0,0,0,0,0,0,0,0,0,0,0,0,0,0,0,0,0,0)';
      INPUT_LOAD='(-0.01,0.01)';
    'UPI0_RX_DP6':
      PIN_NUMBER='(0,0,0,0,0,0,0,0,0,0,0,0,0,0,0,0,0,0,0,0,0,AC7,0,0,0,0,0,0,0,0,0,0,0,0,0,0,0,0,0,0,0,0)';
      INPUT_LOAD='(-0.01,0.01)';
    'UPI0_RX_DP5':
      PIN_NUMBER='(0,0,0,0,0,0,0,0,0,0,0,0,0,0,0,0,0,0,0,0,0,Y6,0,0,0,0,0,0,0,0,0,0,0,0,0,0,0,0,0,0,0,0)';
      INPUT_LOAD='(-0.01,0.01)';
    'UPI0_RX_DP4':
      PIN_NUMBER='(0,0,0,0,0,0,0,0,0,0,0,0,0,0,0,0,0,0,0,0,0,W7,0,0,0,0,0,0,0,0,0,0,0,0,0,0,0,0,0,0,0,0)';
      INPUT_LOAD='(-0.01,0.01)';
    'UPI0_RX_DP3':
      PIN_NUMBER='(0,0,0,0,0,0,0,0,0,0,0,0,0,0,0,0,0,0,0,0,0,T6,0,0,0,0,0,0,0,0,0,0,0,0,0,0,0,0,0,0,0,0)';
      INPUT_LOAD='(-0.01,0.01)';
    'UPI0_RX_DP2':
      PIN_NUMBER='(0,0,0,0,0,0,0,0,0,0,0,0,0,0,0,0,0,0,0,0,0,R7,0,0,0,0,0,0,0,0,0,0,0,0,0,0,0,0,0,0,0,0)';
      INPUT_LOAD='(-0.01,0.01)';
    'UPI0_RX_DP1':
      PIN_NUMBER='(0,0,0,0,0,0,0,0,0,0,0,0,0,0,0,0,0,0,0,0,0,M6,0,0,0,0,0,0,0,0,0,0,0,0,0,0,0,0,0,0,0,0)';
      INPUT_LOAD='(-0.01,0.01)';
    'UPI0_RX_DP0':
      PIN_NUMBER='(0,0,0,0,0,0,0,0,0,0,0,0,0,0,0,0,0,0,0,0,0,L7,0,0,0,0,0,0,0,0,0,0,0,0,0,0,0,0,0,0,0,0)';
      INPUT_LOAD='(-0.01,0.01)';
    'UPI0_TX_DN23':
      PIN_NUMBER='(0,0,0,0,0,0,0,0,0,0,0,0,0,0,0,0,0,0,0,0,0,BT2,0,0,0,0,0,0,0,0,0,0,0,0,0,0,0,0,0,0,0,0)';
      OUTPUT_LOAD='(1.0,-1.0)';
    'UPI0_TX_DN22':
      PIN_NUMBER='(0,0,0,0,0,0,0,0,0,0,0,0,0,0,0,0,0,0,0,0,0,BR3,0,0,0,0,0,0,0,0,0,0,0,0,0,0,0,0,0,0,0,0)';
      OUTPUT_LOAD='(1.0,-1.0)';
    'UPI0_TX_DN21':
      PIN_NUMBER='(0,0,0,0,0,0,0,0,0,0,0,0,0,0,0,0,0,0,0,0,0,BM2,0,0,0,0,0,0,0,0,0,0,0,0,0,0,0,0,0,0,0,0)';
      OUTPUT_LOAD='(1.0,-1.0)';
    'UPI0_TX_DN20':
      PIN_NUMBER='(0,0,0,0,0,0,0,0,0,0,0,0,0,0,0,0,0,0,0,0,0,BK2,0,0,0,0,0,0,0,0,0,0,0,0,0,0,0,0,0,0,0,0)';
      OUTPUT_LOAD='(1.0,-1.0)';
    'UPI0_TX_DN19':
      PIN_NUMBER='(0,0,0,0,0,0,0,0,0,0,0,0,0,0,0,0,0,0,0,0,0,BH2,0,0,0,0,0,0,0,0,0,0,0,0,0,0,0,0,0,0,0,0)';
      OUTPUT_LOAD='(1.0,-1.0)';
    'UPI0_TX_DN18':
      PIN_NUMBER='(0,0,0,0,0,0,0,0,0,0,0,0,0,0,0,0,0,0,0,0,0,BF2,0,0,0,0,0,0,0,0,0,0,0,0,0,0,0,0,0,0,0,0)';
      OUTPUT_LOAD='(1.0,-1.0)';
    'UPI0_TX_DN17':
      PIN_NUMBER='(0,0,0,0,0,0,0,0,0,0,0,0,0,0,0,0,0,0,0,0,0,BD2,0,0,0,0,0,0,0,0,0,0,0,0,0,0,0,0,0,0,0,0)';
      OUTPUT_LOAD='(1.0,-1.0)';
    'UPI0_TX_DN16':
      PIN_NUMBER='(0,0,0,0,0,0,0,0,0,0,0,0,0,0,0,0,0,0,0,0,0,BB2,0,0,0,0,0,0,0,0,0,0,0,0,0,0,0,0,0,0,0,0)';
      OUTPUT_LOAD='(1.0,-1.0)';
    'UPI0_TX_DN15':
      PIN_NUMBER='(0,0,0,0,0,0,0,0,0,0,0,0,0,0,0,0,0,0,0,0,0,AY2,0,0,0,0,0,0,0,0,0,0,0,0,0,0,0,0,0,0,0,0)';
      OUTPUT_LOAD='(1.0,-1.0)';
    'UPI0_TX_DN14':
      PIN_NUMBER='(0,0,0,0,0,0,0,0,0,0,0,0,0,0,0,0,0,0,0,0,0,AU1,0,0,0,0,0,0,0,0,0,0,0,0,0,0,0,0,0,0,0,0)';
      OUTPUT_LOAD='(1.0,-1.0)';
    'UPI0_TX_DN13':
      PIN_NUMBER='(0,0,0,0,0,0,0,0,0,0,0,0,0,0,0,0,0,0,0,0,0,AT2,0,0,0,0,0,0,0,0,0,0,0,0,0,0,0,0,0,0,0,0)';
      OUTPUT_LOAD='(1.0,-1.0)';
    'UPI0_TX_DN12':
      PIN_NUMBER='(0,0,0,0,0,0,0,0,0,0,0,0,0,0,0,0,0,0,0,0,0,AP2,0,0,0,0,0,0,0,0,0,0,0,0,0,0,0,0,0,0,0,0)';
      OUTPUT_LOAD='(1.0,-1.0)';
    'UPI0_TX_DN11':
      PIN_NUMBER='(0,0,0,0,0,0,0,0,0,0,0,0,0,0,0,0,0,0,0,0,0,AM2,0,0,0,0,0,0,0,0,0,0,0,0,0,0,0,0,0,0,0,0)';
      OUTPUT_LOAD='(1.0,-1.0)';
    'UPI0_TX_DN10':
      PIN_NUMBER='(0,0,0,0,0,0,0,0,0,0,0,0,0,0,0,0,0,0,0,0,0,AK2,0,0,0,0,0,0,0,0,0,0,0,0,0,0,0,0,0,0,0,0)';
      OUTPUT_LOAD='(1.0,-1.0)';
    'UPI0_TX_DN9':
      PIN_NUMBER='(0,0,0,0,0,0,0,0,0,0,0,0,0,0,0,0,0,0,0,0,0,AH2,0,0,0,0,0,0,0,0,0,0,0,0,0,0,0,0,0,0,0,0)';
      OUTPUT_LOAD='(1.0,-1.0)';
    'UPI0_TX_DN8':
      PIN_NUMBER='(0,0,0,0,0,0,0,0,0,0,0,0,0,0,0,0,0,0,0,0,0,AF2,0,0,0,0,0,0,0,0,0,0,0,0,0,0,0,0,0,0,0,0)';
      OUTPUT_LOAD='(1.0,-1.0)';
    'UPI0_TX_DN7':
      PIN_NUMBER='(0,0,0,0,0,0,0,0,0,0,0,0,0,0,0,0,0,0,0,0,0,AD2,0,0,0,0,0,0,0,0,0,0,0,0,0,0,0,0,0,0,0,0)';
      OUTPUT_LOAD='(1.0,-1.0)';
    'UPI0_TX_DN6':
      PIN_NUMBER='(0,0,0,0,0,0,0,0,0,0,0,0,0,0,0,0,0,0,0,0,0,AA1,0,0,0,0,0,0,0,0,0,0,0,0,0,0,0,0,0,0,0,0)';
      OUTPUT_LOAD='(1.0,-1.0)';
    'UPI0_TX_DN5':
      PIN_NUMBER='(0,0,0,0,0,0,0,0,0,0,0,0,0,0,0,0,0,0,0,0,0,Y2,0,0,0,0,0,0,0,0,0,0,0,0,0,0,0,0,0,0,0,0)';
      OUTPUT_LOAD='(1.0,-1.0)';
    'UPI0_TX_DN4':
      PIN_NUMBER='(0,0,0,0,0,0,0,0,0,0,0,0,0,0,0,0,0,0,0,0,0,U1,0,0,0,0,0,0,0,0,0,0,0,0,0,0,0,0,0,0,0,0)';
      OUTPUT_LOAD='(1.0,-1.0)';
    'UPI0_TX_DN3':
      PIN_NUMBER='(0,0,0,0,0,0,0,0,0,0,0,0,0,0,0,0,0,0,0,0,0,T2,0,0,0,0,0,0,0,0,0,0,0,0,0,0,0,0,0,0,0,0)';
      OUTPUT_LOAD='(1.0,-1.0)';
    'UPI0_TX_DN2':
      PIN_NUMBER='(0,0,0,0,0,0,0,0,0,0,0,0,0,0,0,0,0,0,0,0,0,N1,0,0,0,0,0,0,0,0,0,0,0,0,0,0,0,0,0,0,0,0)';
      OUTPUT_LOAD='(1.0,-1.0)';
    'UPI0_TX_DN1':
      PIN_NUMBER='(0,0,0,0,0,0,0,0,0,0,0,0,0,0,0,0,0,0,0,0,0,M2,0,0,0,0,0,0,0,0,0,0,0,0,0,0,0,0,0,0,0,0)';
      OUTPUT_LOAD='(1.0,-1.0)';
    'UPI0_TX_DN0':
      PIN_NUMBER='(0,0,0,0,0,0,0,0,0,0,0,0,0,0,0,0,0,0,0,0,0,K4,0,0,0,0,0,0,0,0,0,0,0,0,0,0,0,0,0,0,0,0)';
      OUTPUT_LOAD='(1.0,-1.0)';
    'UPI0_TX_DP23':
      PIN_NUMBER='(0,0,0,0,0,0,0,0,0,0,0,0,0,0,0,0,0,0,0,0,0,BU3,0,0,0,0,0,0,0,0,0,0,0,0,0,0,0,0,0,0,0,0)';
      OUTPUT_LOAD='(1.0,-1.0)';
    'UPI0_TX_DP22':
      PIN_NUMBER='(0,0,0,0,0,0,0,0,0,0,0,0,0,0,0,0,0,0,0,0,0,BN3,0,0,0,0,0,0,0,0,0,0,0,0,0,0,0,0,0,0,0,0)';
      OUTPUT_LOAD='(1.0,-1.0)';
    'UPI0_TX_DP21':
      PIN_NUMBER='(0,0,0,0,0,0,0,0,0,0,0,0,0,0,0,0,0,0,0,0,0,BL3,0,0,0,0,0,0,0,0,0,0,0,0,0,0,0,0,0,0,0,0)';
      OUTPUT_LOAD='(1.0,-1.0)';
    'UPI0_TX_DP20':
      PIN_NUMBER='(0,0,0,0,0,0,0,0,0,0,0,0,0,0,0,0,0,0,0,0,0,BJ1,0,0,0,0,0,0,0,0,0,0,0,0,0,0,0,0,0,0,0,0)';
      OUTPUT_LOAD='(1.0,-1.0)';
    'UPI0_TX_DP19':
      PIN_NUMBER='(0,0,0,0,0,0,0,0,0,0,0,0,0,0,0,0,0,0,0,0,0,BG3,0,0,0,0,0,0,0,0,0,0,0,0,0,0,0,0,0,0,0,0)';
      OUTPUT_LOAD='(1.0,-1.0)';
    'UPI0_TX_DP18':
      PIN_NUMBER='(0,0,0,0,0,0,0,0,0,0,0,0,0,0,0,0,0,0,0,0,0,BE1,0,0,0,0,0,0,0,0,0,0,0,0,0,0,0,0,0,0,0,0)';
      OUTPUT_LOAD='(1.0,-1.0)';
    'UPI0_TX_DP17':
      PIN_NUMBER='(0,0,0,0,0,0,0,0,0,0,0,0,0,0,0,0,0,0,0,0,0,BC3,0,0,0,0,0,0,0,0,0,0,0,0,0,0,0,0,0,0,0,0)';
      OUTPUT_LOAD='(1.0,-1.0)';
    'UPI0_TX_DP16':
      PIN_NUMBER='(0,0,0,0,0,0,0,0,0,0,0,0,0,0,0,0,0,0,0,0,0,BA1,0,0,0,0,0,0,0,0,0,0,0,0,0,0,0,0,0,0,0,0)';
      OUTPUT_LOAD='(1.0,-1.0)';
    'UPI0_TX_DP15':
      PIN_NUMBER='(0,0,0,0,0,0,0,0,0,0,0,0,0,0,0,0,0,0,0,0,0,AW3,0,0,0,0,0,0,0,0,0,0,0,0,0,0,0,0,0,0,0,0)';
      OUTPUT_LOAD='(1.0,-1.0)';
    'UPI0_TX_DP14':
      PIN_NUMBER='(0,0,0,0,0,0,0,0,0,0,0,0,0,0,0,0,0,0,0,0,0,AV2,0,0,0,0,0,0,0,0,0,0,0,0,0,0,0,0,0,0,0,0)';
      OUTPUT_LOAD='(1.0,-1.0)';
    'UPI0_TX_DP13':
      PIN_NUMBER='(0,0,0,0,0,0,0,0,0,0,0,0,0,0,0,0,0,0,0,0,0,AR3,0,0,0,0,0,0,0,0,0,0,0,0,0,0,0,0,0,0,0,0)';
      OUTPUT_LOAD='(1.0,-1.0)';
    'UPI0_TX_DP12':
      PIN_NUMBER='(0,0,0,0,0,0,0,0,0,0,0,0,0,0,0,0,0,0,0,0,0,AN1,0,0,0,0,0,0,0,0,0,0,0,0,0,0,0,0,0,0,0,0)';
      OUTPUT_LOAD='(1.0,-1.0)';
    'UPI0_TX_DP11':
      PIN_NUMBER='(0,0,0,0,0,0,0,0,0,0,0,0,0,0,0,0,0,0,0,0,0,AL3,0,0,0,0,0,0,0,0,0,0,0,0,0,0,0,0,0,0,0,0)';
      OUTPUT_LOAD='(1.0,-1.0)';
    'UPI0_TX_DP10':
      PIN_NUMBER='(0,0,0,0,0,0,0,0,0,0,0,0,0,0,0,0,0,0,0,0,0,AJ1,0,0,0,0,0,0,0,0,0,0,0,0,0,0,0,0,0,0,0,0)';
      OUTPUT_LOAD='(1.0,-1.0)';
    'UPI0_TX_DP9':
      PIN_NUMBER='(0,0,0,0,0,0,0,0,0,0,0,0,0,0,0,0,0,0,0,0,0,AG3,0,0,0,0,0,0,0,0,0,0,0,0,0,0,0,0,0,0,0,0)';
      OUTPUT_LOAD='(1.0,-1.0)';
    'UPI0_TX_DP8':
      PIN_NUMBER='(0,0,0,0,0,0,0,0,0,0,0,0,0,0,0,0,0,0,0,0,0,AE1,0,0,0,0,0,0,0,0,0,0,0,0,0,0,0,0,0,0,0,0)';
      OUTPUT_LOAD='(1.0,-1.0)';
    'UPI0_TX_DP7':
      PIN_NUMBER='(0,0,0,0,0,0,0,0,0,0,0,0,0,0,0,0,0,0,0,0,0,AC3,0,0,0,0,0,0,0,0,0,0,0,0,0,0,0,0,0,0,0,0)';
      OUTPUT_LOAD='(1.0,-1.0)';
    'UPI0_TX_DP6':
      PIN_NUMBER='(0,0,0,0,0,0,0,0,0,0,0,0,0,0,0,0,0,0,0,0,0,AB2,0,0,0,0,0,0,0,0,0,0,0,0,0,0,0,0,0,0,0,0)';
      OUTPUT_LOAD='(1.0,-1.0)';
    'UPI0_TX_DP5':
      PIN_NUMBER='(0,0,0,0,0,0,0,0,0,0,0,0,0,0,0,0,0,0,0,0,0,W3,0,0,0,0,0,0,0,0,0,0,0,0,0,0,0,0,0,0,0,0)';
      OUTPUT_LOAD='(1.0,-1.0)';
    'UPI0_TX_DP4':
      PIN_NUMBER='(0,0,0,0,0,0,0,0,0,0,0,0,0,0,0,0,0,0,0,0,0,V2,0,0,0,0,0,0,0,0,0,0,0,0,0,0,0,0,0,0,0,0)';
      OUTPUT_LOAD='(1.0,-1.0)';
    'UPI0_TX_DP3':
      PIN_NUMBER='(0,0,0,0,0,0,0,0,0,0,0,0,0,0,0,0,0,0,0,0,0,R3,0,0,0,0,0,0,0,0,0,0,0,0,0,0,0,0,0,0,0,0)';
      OUTPUT_LOAD='(1.0,-1.0)';
    'UPI0_TX_DP2':
      PIN_NUMBER='(0,0,0,0,0,0,0,0,0,0,0,0,0,0,0,0,0,0,0,0,0,P2,0,0,0,0,0,0,0,0,0,0,0,0,0,0,0,0,0,0,0,0)';
      OUTPUT_LOAD='(1.0,-1.0)';
    'UPI0_TX_DP1':
      PIN_NUMBER='(0,0,0,0,0,0,0,0,0,0,0,0,0,0,0,0,0,0,0,0,0,L3,0,0,0,0,0,0,0,0,0,0,0,0,0,0,0,0,0,0,0,0)';
      OUTPUT_LOAD='(1.0,-1.0)';
    'UPI0_TX_DP0':
      PIN_NUMBER='(0,0,0,0,0,0,0,0,0,0,0,0,0,0,0,0,0,0,0,0,0,J3,0,0,0,0,0,0,0,0,0,0,0,0,0,0,0,0,0,0,0,0)';
      OUTPUT_LOAD='(1.0,-1.0)';
    'UPI1_RX_DN23':
      PIN_NUMBER='(0,0,0,0,0,0,0,0,0,0,0,0,0,0,0,0,0,0,0,0,0,0,CB2,0,0,0,0,0,0,0,0,0,0,0,0,0,0,0,0,0,0,0)';
      INPUT_LOAD='(-0.01,0.01)';
    'UPI1_RX_DN22':
      PIN_NUMBER='(0,0,0,0,0,0,0,0,0,0,0,0,0,0,0,0,0,0,0,0,0,0,CD2,0,0,0,0,0,0,0,0,0,0,0,0,0,0,0,0,0,0,0)';
      INPUT_LOAD='(-0.01,0.01)';
    'UPI1_RX_DN21':
      PIN_NUMBER='(0,0,0,0,0,0,0,0,0,0,0,0,0,0,0,0,0,0,0,0,0,0,CF2,0,0,0,0,0,0,0,0,0,0,0,0,0,0,0,0,0,0,0)';
      INPUT_LOAD='(-0.01,0.01)';
    'UPI1_RX_DN20':
      PIN_NUMBER='(0,0,0,0,0,0,0,0,0,0,0,0,0,0,0,0,0,0,0,0,0,0,CH2,0,0,0,0,0,0,0,0,0,0,0,0,0,0,0,0,0,0,0)';
      INPUT_LOAD='(-0.01,0.01)';
    'UPI1_RX_DN19':
      PIN_NUMBER='(0,0,0,0,0,0,0,0,0,0,0,0,0,0,0,0,0,0,0,0,0,0,CJ1,0,0,0,0,0,0,0,0,0,0,0,0,0,0,0,0,0,0,0)';
      INPUT_LOAD='(-0.01,0.01)';
    'UPI1_RX_DN18':
      PIN_NUMBER='(0,0,0,0,0,0,0,0,0,0,0,0,0,0,0,0,0,0,0,0,0,0,CL3,0,0,0,0,0,0,0,0,0,0,0,0,0,0,0,0,0,0,0)';
      INPUT_LOAD='(-0.01,0.01)';
    'UPI1_RX_DN17':
      PIN_NUMBER='(0,0,0,0,0,0,0,0,0,0,0,0,0,0,0,0,0,0,0,0,0,0,CN1,0,0,0,0,0,0,0,0,0,0,0,0,0,0,0,0,0,0,0)';
      INPUT_LOAD='(-0.01,0.01)';
    'UPI1_RX_DN16':
      PIN_NUMBER='(0,0,0,0,0,0,0,0,0,0,0,0,0,0,0,0,0,0,0,0,0,0,CR3,0,0,0,0,0,0,0,0,0,0,0,0,0,0,0,0,0,0,0)';
      INPUT_LOAD='(-0.01,0.01)';
    'UPI1_RX_DN15':
      PIN_NUMBER='(0,0,0,0,0,0,0,0,0,0,0,0,0,0,0,0,0,0,0,0,0,0,CV2,0,0,0,0,0,0,0,0,0,0,0,0,0,0,0,0,0,0,0)';
      INPUT_LOAD='(-0.01,0.01)';
    'UPI1_RX_DN14':
      PIN_NUMBER='(0,0,0,0,0,0,0,0,0,0,0,0,0,0,0,0,0,0,0,0,0,0,CY2,0,0,0,0,0,0,0,0,0,0,0,0,0,0,0,0,0,0,0)';
      INPUT_LOAD='(-0.01,0.01)';
    'UPI1_RX_DN13':
      PIN_NUMBER='(0,0,0,0,0,0,0,0,0,0,0,0,0,0,0,0,0,0,0,0,0,0,DB2,0,0,0,0,0,0,0,0,0,0,0,0,0,0,0,0,0,0,0)';
      INPUT_LOAD='(-0.01,0.01)';
    'UPI1_RX_DN12':
      PIN_NUMBER='(0,0,0,0,0,0,0,0,0,0,0,0,0,0,0,0,0,0,0,0,0,0,DD2,0,0,0,0,0,0,0,0,0,0,0,0,0,0,0,0,0,0,0)';
      INPUT_LOAD='(-0.01,0.01)';
    'UPI1_RX_DN11':
      PIN_NUMBER='(0,0,0,0,0,0,0,0,0,0,0,0,0,0,0,0,0,0,0,0,0,0,DE1,0,0,0,0,0,0,0,0,0,0,0,0,0,0,0,0,0,0,0)';
      INPUT_LOAD='(-0.01,0.01)';
    'UPI1_RX_DN10':
      PIN_NUMBER='(0,0,0,0,0,0,0,0,0,0,0,0,0,0,0,0,0,0,0,0,0,0,DG3,0,0,0,0,0,0,0,0,0,0,0,0,0,0,0,0,0,0,0)';
      INPUT_LOAD='(-0.01,0.01)';
    'UPI1_RX_DN9':
      PIN_NUMBER='(0,0,0,0,0,0,0,0,0,0,0,0,0,0,0,0,0,0,0,0,0,0,DJ1,0,0,0,0,0,0,0,0,0,0,0,0,0,0,0,0,0,0,0)';
      INPUT_LOAD='(-0.01,0.01)';
    'UPI1_RX_DN8':
      PIN_NUMBER='(0,0,0,0,0,0,0,0,0,0,0,0,0,0,0,0,0,0,0,0,0,0,DL3,0,0,0,0,0,0,0,0,0,0,0,0,0,0,0,0,0,0,0)';
      INPUT_LOAD='(-0.01,0.01)';
    'UPI1_RX_DN7':
      PIN_NUMBER='(0,0,0,0,0,0,0,0,0,0,0,0,0,0,0,0,0,0,0,0,0,0,DN1,0,0,0,0,0,0,0,0,0,0,0,0,0,0,0,0,0,0,0)';
      INPUT_LOAD='(-0.01,0.01)';
    'UPI1_RX_DN6':
      PIN_NUMBER='(0,0,0,0,0,0,0,0,0,0,0,0,0,0,0,0,0,0,0,0,0,0,DT2,0,0,0,0,0,0,0,0,0,0,0,0,0,0,0,0,0,0,0)';
      INPUT_LOAD='(-0.01,0.01)';
    'UPI1_RX_DN5':
      PIN_NUMBER='(0,0,0,0,0,0,0,0,0,0,0,0,0,0,0,0,0,0,0,0,0,0,DU1,0,0,0,0,0,0,0,0,0,0,0,0,0,0,0,0,0,0,0)';
      INPUT_LOAD='(-0.01,0.01)';
    'UPI1_RX_DN4':
      PIN_NUMBER='(0,0,0,0,0,0,0,0,0,0,0,0,0,0,0,0,0,0,0,0,0,0,DY2,0,0,0,0,0,0,0,0,0,0,0,0,0,0,0,0,0,0,0)';
      INPUT_LOAD='(-0.01,0.01)';
    'UPI1_RX_DN3':
      PIN_NUMBER='(0,0,0,0,0,0,0,0,0,0,0,0,0,0,0,0,0,0,0,0,0,0,EA1,0,0,0,0,0,0,0,0,0,0,0,0,0,0,0,0,0,0,0)';
      INPUT_LOAD='(-0.01,0.01)';
    'UPI1_RX_DN2':
      PIN_NUMBER='(0,0,0,0,0,0,0,0,0,0,0,0,0,0,0,0,0,0,0,0,0,0,ED2,0,0,0,0,0,0,0,0,0,0,0,0,0,0,0,0,0,0,0)';
      INPUT_LOAD='(-0.01,0.01)';
    'UPI1_RX_DN1':
      PIN_NUMBER='(0,0,0,0,0,0,0,0,0,0,0,0,0,0,0,0,0,0,0,0,0,0,EE3,0,0,0,0,0,0,0,0,0,0,0,0,0,0,0,0,0,0,0)';
      INPUT_LOAD='(-0.01,0.01)';
    'UPI1_RX_DN0':
      PIN_NUMBER='(0,0,0,0,0,0,0,0,0,0,0,0,0,0,0,0,0,0,0,0,0,0,EH2,0,0,0,0,0,0,0,0,0,0,0,0,0,0,0,0,0,0,0)';
      INPUT_LOAD='(-0.01,0.01)';
    'UPI1_RX_DP23':
      PIN_NUMBER='(0,0,0,0,0,0,0,0,0,0,0,0,0,0,0,0,0,0,0,0,0,0,BY2,0,0,0,0,0,0,0,0,0,0,0,0,0,0,0,0,0,0,0)';
      INPUT_LOAD='(-0.01,0.01)';
    'UPI1_RX_DP22':
      PIN_NUMBER='(0,0,0,0,0,0,0,0,0,0,0,0,0,0,0,0,0,0,0,0,0,0,CC3,0,0,0,0,0,0,0,0,0,0,0,0,0,0,0,0,0,0,0)';
      INPUT_LOAD='(-0.01,0.01)';
    'UPI1_RX_DP21':
      PIN_NUMBER='(0,0,0,0,0,0,0,0,0,0,0,0,0,0,0,0,0,0,0,0,0,0,CE1,0,0,0,0,0,0,0,0,0,0,0,0,0,0,0,0,0,0,0)';
      INPUT_LOAD='(-0.01,0.01)';
    'UPI1_RX_DP20':
      PIN_NUMBER='(0,0,0,0,0,0,0,0,0,0,0,0,0,0,0,0,0,0,0,0,0,0,CG3,0,0,0,0,0,0,0,0,0,0,0,0,0,0,0,0,0,0,0)';
      INPUT_LOAD='(-0.01,0.01)';
    'UPI1_RX_DP19':
      PIN_NUMBER='(0,0,0,0,0,0,0,0,0,0,0,0,0,0,0,0,0,0,0,0,0,0,CK2,0,0,0,0,0,0,0,0,0,0,0,0,0,0,0,0,0,0,0)';
      INPUT_LOAD='(-0.01,0.01)';
    'UPI1_RX_DP18':
      PIN_NUMBER='(0,0,0,0,0,0,0,0,0,0,0,0,0,0,0,0,0,0,0,0,0,0,CM2,0,0,0,0,0,0,0,0,0,0,0,0,0,0,0,0,0,0,0)';
      INPUT_LOAD='(-0.01,0.01)';
    'UPI1_RX_DP17':
      PIN_NUMBER='(0,0,0,0,0,0,0,0,0,0,0,0,0,0,0,0,0,0,0,0,0,0,CP2,0,0,0,0,0,0,0,0,0,0,0,0,0,0,0,0,0,0,0)';
      INPUT_LOAD='(-0.01,0.01)';
    'UPI1_RX_DP16':
      PIN_NUMBER='(0,0,0,0,0,0,0,0,0,0,0,0,0,0,0,0,0,0,0,0,0,0,CT2,0,0,0,0,0,0,0,0,0,0,0,0,0,0,0,0,0,0,0)';
      INPUT_LOAD='(-0.01,0.01)';
    'UPI1_RX_DP15':
      PIN_NUMBER='(0,0,0,0,0,0,0,0,0,0,0,0,0,0,0,0,0,0,0,0,0,0,CU1,0,0,0,0,0,0,0,0,0,0,0,0,0,0,0,0,0,0,0)';
      INPUT_LOAD='(-0.01,0.01)';
    'UPI1_RX_DP14':
      PIN_NUMBER='(0,0,0,0,0,0,0,0,0,0,0,0,0,0,0,0,0,0,0,0,0,0,CW3,0,0,0,0,0,0,0,0,0,0,0,0,0,0,0,0,0,0,0)';
      INPUT_LOAD='(-0.01,0.01)';
    'UPI1_RX_DP13':
      PIN_NUMBER='(0,0,0,0,0,0,0,0,0,0,0,0,0,0,0,0,0,0,0,0,0,0,DA1,0,0,0,0,0,0,0,0,0,0,0,0,0,0,0,0,0,0,0)';
      INPUT_LOAD='(-0.01,0.01)';
    'UPI1_RX_DP12':
      PIN_NUMBER='(0,0,0,0,0,0,0,0,0,0,0,0,0,0,0,0,0,0,0,0,0,0,DC3,0,0,0,0,0,0,0,0,0,0,0,0,0,0,0,0,0,0,0)';
      INPUT_LOAD='(-0.01,0.01)';
    'UPI1_RX_DP11':
      PIN_NUMBER='(0,0,0,0,0,0,0,0,0,0,0,0,0,0,0,0,0,0,0,0,0,0,DF2,0,0,0,0,0,0,0,0,0,0,0,0,0,0,0,0,0,0,0)';
      INPUT_LOAD='(-0.01,0.01)';
    'UPI1_RX_DP10':
      PIN_NUMBER='(0,0,0,0,0,0,0,0,0,0,0,0,0,0,0,0,0,0,0,0,0,0,DH2,0,0,0,0,0,0,0,0,0,0,0,0,0,0,0,0,0,0,0)';
      INPUT_LOAD='(-0.01,0.01)';
    'UPI1_RX_DP9':
      PIN_NUMBER='(0,0,0,0,0,0,0,0,0,0,0,0,0,0,0,0,0,0,0,0,0,0,DK2,0,0,0,0,0,0,0,0,0,0,0,0,0,0,0,0,0,0,0)';
      INPUT_LOAD='(-0.01,0.01)';
    'UPI1_RX_DP8':
      PIN_NUMBER='(0,0,0,0,0,0,0,0,0,0,0,0,0,0,0,0,0,0,0,0,0,0,DM2,0,0,0,0,0,0,0,0,0,0,0,0,0,0,0,0,0,0,0)';
      INPUT_LOAD='(-0.01,0.01)';
    'UPI1_RX_DP7':
      PIN_NUMBER='(0,0,0,0,0,0,0,0,0,0,0,0,0,0,0,0,0,0,0,0,0,0,DP2,0,0,0,0,0,0,0,0,0,0,0,0,0,0,0,0,0,0,0)';
      INPUT_LOAD='(-0.01,0.01)';
    'UPI1_RX_DP6':
      PIN_NUMBER='(0,0,0,0,0,0,0,0,0,0,0,0,0,0,0,0,0,0,0,0,0,0,DR3,0,0,0,0,0,0,0,0,0,0,0,0,0,0,0,0,0,0,0)';
      INPUT_LOAD='(-0.01,0.01)';
    'UPI1_RX_DP5':
      PIN_NUMBER='(0,0,0,0,0,0,0,0,0,0,0,0,0,0,0,0,0,0,0,0,0,0,DV2,0,0,0,0,0,0,0,0,0,0,0,0,0,0,0,0,0,0,0)';
      INPUT_LOAD='(-0.01,0.01)';
    'UPI1_RX_DP4':
      PIN_NUMBER='(0,0,0,0,0,0,0,0,0,0,0,0,0,0,0,0,0,0,0,0,0,0,DW3,0,0,0,0,0,0,0,0,0,0,0,0,0,0,0,0,0,0,0)';
      INPUT_LOAD='(-0.01,0.01)';
    'UPI1_RX_DP3':
      PIN_NUMBER='(0,0,0,0,0,0,0,0,0,0,0,0,0,0,0,0,0,0,0,0,0,0,EB2,0,0,0,0,0,0,0,0,0,0,0,0,0,0,0,0,0,0,0)';
      INPUT_LOAD='(-0.01,0.01)';
    'UPI1_RX_DP2':
      PIN_NUMBER='(0,0,0,0,0,0,0,0,0,0,0,0,0,0,0,0,0,0,0,0,0,0,EC3,0,0,0,0,0,0,0,0,0,0,0,0,0,0,0,0,0,0,0)';
      INPUT_LOAD='(-0.01,0.01)';
    'UPI1_RX_DP1':
      PIN_NUMBER='(0,0,0,0,0,0,0,0,0,0,0,0,0,0,0,0,0,0,0,0,0,0,EG3,0,0,0,0,0,0,0,0,0,0,0,0,0,0,0,0,0,0,0)';
      INPUT_LOAD='(-0.01,0.01)';
    'UPI1_RX_DP0':
      PIN_NUMBER='(0,0,0,0,0,0,0,0,0,0,0,0,0,0,0,0,0,0,0,0,0,0,EJ3,0,0,0,0,0,0,0,0,0,0,0,0,0,0,0,0,0,0,0)';
      INPUT_LOAD='(-0.01,0.01)';
    'UPI1_TX_DN23':
      PIN_NUMBER='(0,0,0,0,0,0,0,0,0,0,0,0,0,0,0,0,0,0,0,0,0,0,BY6,0,0,0,0,0,0,0,0,0,0,0,0,0,0,0,0,0,0,0)';
      OUTPUT_LOAD='(1.0,-1.0)';
    'UPI1_TX_DN22':
      PIN_NUMBER='(0,0,0,0,0,0,0,0,0,0,0,0,0,0,0,0,0,0,0,0,0,0,CA5,0,0,0,0,0,0,0,0,0,0,0,0,0,0,0,0,0,0,0)';
      OUTPUT_LOAD='(1.0,-1.0)';
    'UPI1_TX_DN21':
      PIN_NUMBER='(0,0,0,0,0,0,0,0,0,0,0,0,0,0,0,0,0,0,0,0,0,0,CD6,0,0,0,0,0,0,0,0,0,0,0,0,0,0,0,0,0,0,0)';
      OUTPUT_LOAD='(1.0,-1.0)';
    'UPI1_TX_DN20':
      PIN_NUMBER='(0,0,0,0,0,0,0,0,0,0,0,0,0,0,0,0,0,0,0,0,0,0,CE5,0,0,0,0,0,0,0,0,0,0,0,0,0,0,0,0,0,0,0)';
      OUTPUT_LOAD='(1.0,-1.0)';
    'UPI1_TX_DN19':
      PIN_NUMBER='(0,0,0,0,0,0,0,0,0,0,0,0,0,0,0,0,0,0,0,0,0,0,CH6,0,0,0,0,0,0,0,0,0,0,0,0,0,0,0,0,0,0,0)';
      OUTPUT_LOAD='(1.0,-1.0)';
    'UPI1_TX_DN18':
      PIN_NUMBER='(0,0,0,0,0,0,0,0,0,0,0,0,0,0,0,0,0,0,0,0,0,0,CJ5,0,0,0,0,0,0,0,0,0,0,0,0,0,0,0,0,0,0,0)';
      OUTPUT_LOAD='(1.0,-1.0)';
    'UPI1_TX_DN17':
      PIN_NUMBER='(0,0,0,0,0,0,0,0,0,0,0,0,0,0,0,0,0,0,0,0,0,0,CM6,0,0,0,0,0,0,0,0,0,0,0,0,0,0,0,0,0,0,0)';
      OUTPUT_LOAD='(1.0,-1.0)';
    'UPI1_TX_DN16':
      PIN_NUMBER='(0,0,0,0,0,0,0,0,0,0,0,0,0,0,0,0,0,0,0,0,0,0,CN5,0,0,0,0,0,0,0,0,0,0,0,0,0,0,0,0,0,0,0)';
      OUTPUT_LOAD='(1.0,-1.0)';
    'UPI1_TX_DN15':
      PIN_NUMBER='(0,0,0,0,0,0,0,0,0,0,0,0,0,0,0,0,0,0,0,0,0,0,CT6,0,0,0,0,0,0,0,0,0,0,0,0,0,0,0,0,0,0,0)';
      OUTPUT_LOAD='(1.0,-1.0)';
    'UPI1_TX_DN14':
      PIN_NUMBER='(0,0,0,0,0,0,0,0,0,0,0,0,0,0,0,0,0,0,0,0,0,0,CU5,0,0,0,0,0,0,0,0,0,0,0,0,0,0,0,0,0,0,0)';
      OUTPUT_LOAD='(1.0,-1.0)';
    'UPI1_TX_DN13':
      PIN_NUMBER='(0,0,0,0,0,0,0,0,0,0,0,0,0,0,0,0,0,0,0,0,0,0,CY6,0,0,0,0,0,0,0,0,0,0,0,0,0,0,0,0,0,0,0)';
      OUTPUT_LOAD='(1.0,-1.0)';
    'UPI1_TX_DN12':
      PIN_NUMBER='(0,0,0,0,0,0,0,0,0,0,0,0,0,0,0,0,0,0,0,0,0,0,DA5,0,0,0,0,0,0,0,0,0,0,0,0,0,0,0,0,0,0,0)';
      OUTPUT_LOAD='(1.0,-1.0)';
    'UPI1_TX_DN11':
      PIN_NUMBER='(0,0,0,0,0,0,0,0,0,0,0,0,0,0,0,0,0,0,0,0,0,0,DD6,0,0,0,0,0,0,0,0,0,0,0,0,0,0,0,0,0,0,0)';
      OUTPUT_LOAD='(1.0,-1.0)';
    'UPI1_TX_DN10':
      PIN_NUMBER='(0,0,0,0,0,0,0,0,0,0,0,0,0,0,0,0,0,0,0,0,0,0,DE5,0,0,0,0,0,0,0,0,0,0,0,0,0,0,0,0,0,0,0)';
      OUTPUT_LOAD='(1.0,-1.0)';
    'UPI1_TX_DN9':
      PIN_NUMBER='(0,0,0,0,0,0,0,0,0,0,0,0,0,0,0,0,0,0,0,0,0,0,DH6,0,0,0,0,0,0,0,0,0,0,0,0,0,0,0,0,0,0,0)';
      OUTPUT_LOAD='(1.0,-1.0)';
    'UPI1_TX_DN8':
      PIN_NUMBER='(0,0,0,0,0,0,0,0,0,0,0,0,0,0,0,0,0,0,0,0,0,0,DK6,0,0,0,0,0,0,0,0,0,0,0,0,0,0,0,0,0,0,0)';
      OUTPUT_LOAD='(1.0,-1.0)';
    'UPI1_TX_DN7':
      PIN_NUMBER='(0,0,0,0,0,0,0,0,0,0,0,0,0,0,0,0,0,0,0,0,0,0,DL7,0,0,0,0,0,0,0,0,0,0,0,0,0,0,0,0,0,0,0)';
      OUTPUT_LOAD='(1.0,-1.0)';
    'UPI1_TX_DN6':
      PIN_NUMBER='(0,0,0,0,0,0,0,0,0,0,0,0,0,0,0,0,0,0,0,0,0,0,DP6,0,0,0,0,0,0,0,0,0,0,0,0,0,0,0,0,0,0,0)';
      OUTPUT_LOAD='(1.0,-1.0)';
    'UPI1_TX_DN5':
      PIN_NUMBER='(0,0,0,0,0,0,0,0,0,0,0,0,0,0,0,0,0,0,0,0,0,0,DT6,0,0,0,0,0,0,0,0,0,0,0,0,0,0,0,0,0,0,0)';
      OUTPUT_LOAD='(1.0,-1.0)';
    'UPI1_TX_DN4':
      PIN_NUMBER='(0,0,0,0,0,0,0,0,0,0,0,0,0,0,0,0,0,0,0,0,0,0,DV6,0,0,0,0,0,0,0,0,0,0,0,0,0,0,0,0,0,0,0)';
      OUTPUT_LOAD='(1.0,-1.0)';
    'UPI1_TX_DN3':
      PIN_NUMBER='(0,0,0,0,0,0,0,0,0,0,0,0,0,0,0,0,0,0,0,0,0,0,DY6,0,0,0,0,0,0,0,0,0,0,0,0,0,0,0,0,0,0,0)';
      OUTPUT_LOAD='(1.0,-1.0)';
    'UPI1_TX_DN2':
      PIN_NUMBER='(0,0,0,0,0,0,0,0,0,0,0,0,0,0,0,0,0,0,0,0,0,0,EB6,0,0,0,0,0,0,0,0,0,0,0,0,0,0,0,0,0,0,0)';
      OUTPUT_LOAD='(1.0,-1.0)';
    'UPI1_TX_DN1':
      PIN_NUMBER='(0,0,0,0,0,0,0,0,0,0,0,0,0,0,0,0,0,0,0,0,0,0,EC7,0,0,0,0,0,0,0,0,0,0,0,0,0,0,0,0,0,0,0)';
      OUTPUT_LOAD='(1.0,-1.0)';
    'UPI1_TX_DN0':
      PIN_NUMBER='(0,0,0,0,0,0,0,0,0,0,0,0,0,0,0,0,0,0,0,0,0,0,EF6,0,0,0,0,0,0,0,0,0,0,0,0,0,0,0,0,0,0,0)';
      OUTPUT_LOAD='(1.0,-1.0)';
    'UPI1_TX_DP23':
      PIN_NUMBER='(0,0,0,0,0,0,0,0,0,0,0,0,0,0,0,0,0,0,0,0,0,0,BW7,0,0,0,0,0,0,0,0,0,0,0,0,0,0,0,0,0,0,0)';
      OUTPUT_LOAD='(1.0,-1.0)';
    'UPI1_TX_DP22':
      PIN_NUMBER='(0,0,0,0,0,0,0,0,0,0,0,0,0,0,0,0,0,0,0,0,0,0,CB6,0,0,0,0,0,0,0,0,0,0,0,0,0,0,0,0,0,0,0)';
      OUTPUT_LOAD='(1.0,-1.0)';
    'UPI1_TX_DP21':
      PIN_NUMBER='(0,0,0,0,0,0,0,0,0,0,0,0,0,0,0,0,0,0,0,0,0,0,CC7,0,0,0,0,0,0,0,0,0,0,0,0,0,0,0,0,0,0,0)';
      OUTPUT_LOAD='(1.0,-1.0)';
    'UPI1_TX_DP20':
      PIN_NUMBER='(0,0,0,0,0,0,0,0,0,0,0,0,0,0,0,0,0,0,0,0,0,0,CF6,0,0,0,0,0,0,0,0,0,0,0,0,0,0,0,0,0,0,0)';
      OUTPUT_LOAD='(1.0,-1.0)';
    'UPI1_TX_DP19':
      PIN_NUMBER='(0,0,0,0,0,0,0,0,0,0,0,0,0,0,0,0,0,0,0,0,0,0,CG7,0,0,0,0,0,0,0,0,0,0,0,0,0,0,0,0,0,0,0)';
      OUTPUT_LOAD='(1.0,-1.0)';
    'UPI1_TX_DP18':
      PIN_NUMBER='(0,0,0,0,0,0,0,0,0,0,0,0,0,0,0,0,0,0,0,0,0,0,CK6,0,0,0,0,0,0,0,0,0,0,0,0,0,0,0,0,0,0,0)';
      OUTPUT_LOAD='(1.0,-1.0)';
    'UPI1_TX_DP17':
      PIN_NUMBER='(0,0,0,0,0,0,0,0,0,0,0,0,0,0,0,0,0,0,0,0,0,0,CL7,0,0,0,0,0,0,0,0,0,0,0,0,0,0,0,0,0,0,0)';
      OUTPUT_LOAD='(1.0,-1.0)';
    'UPI1_TX_DP16':
      PIN_NUMBER='(0,0,0,0,0,0,0,0,0,0,0,0,0,0,0,0,0,0,0,0,0,0,CP6,0,0,0,0,0,0,0,0,0,0,0,0,0,0,0,0,0,0,0)';
      OUTPUT_LOAD='(1.0,-1.0)';
    'UPI1_TX_DP15':
      PIN_NUMBER='(0,0,0,0,0,0,0,0,0,0,0,0,0,0,0,0,0,0,0,0,0,0,CR7,0,0,0,0,0,0,0,0,0,0,0,0,0,0,0,0,0,0,0)';
      OUTPUT_LOAD='(1.0,-1.0)';
    'UPI1_TX_DP14':
      PIN_NUMBER='(0,0,0,0,0,0,0,0,0,0,0,0,0,0,0,0,0,0,0,0,0,0,CV6,0,0,0,0,0,0,0,0,0,0,0,0,0,0,0,0,0,0,0)';
      OUTPUT_LOAD='(1.0,-1.0)';
    'UPI1_TX_DP13':
      PIN_NUMBER='(0,0,0,0,0,0,0,0,0,0,0,0,0,0,0,0,0,0,0,0,0,0,CW7,0,0,0,0,0,0,0,0,0,0,0,0,0,0,0,0,0,0,0)';
      OUTPUT_LOAD='(1.0,-1.0)';
    'UPI1_TX_DP12':
      PIN_NUMBER='(0,0,0,0,0,0,0,0,0,0,0,0,0,0,0,0,0,0,0,0,0,0,DB6,0,0,0,0,0,0,0,0,0,0,0,0,0,0,0,0,0,0,0)';
      OUTPUT_LOAD='(1.0,-1.0)';
    'UPI1_TX_DP11':
      PIN_NUMBER='(0,0,0,0,0,0,0,0,0,0,0,0,0,0,0,0,0,0,0,0,0,0,DC7,0,0,0,0,0,0,0,0,0,0,0,0,0,0,0,0,0,0,0)';
      OUTPUT_LOAD='(1.0,-1.0)';
    'UPI1_TX_DP10':
      PIN_NUMBER='(0,0,0,0,0,0,0,0,0,0,0,0,0,0,0,0,0,0,0,0,0,0,DF6,0,0,0,0,0,0,0,0,0,0,0,0,0,0,0,0,0,0,0)';
      OUTPUT_LOAD='(1.0,-1.0)';
    'UPI1_TX_DP9':
      PIN_NUMBER='(0,0,0,0,0,0,0,0,0,0,0,0,0,0,0,0,0,0,0,0,0,0,DG7,0,0,0,0,0,0,0,0,0,0,0,0,0,0,0,0,0,0,0)';
      OUTPUT_LOAD='(1.0,-1.0)';
    'UPI1_TX_DP8':
      PIN_NUMBER='(0,0,0,0,0,0,0,0,0,0,0,0,0,0,0,0,0,0,0,0,0,0,DJ5,0,0,0,0,0,0,0,0,0,0,0,0,0,0,0,0,0,0,0)';
      OUTPUT_LOAD='(1.0,-1.0)';
    'UPI1_TX_DP7':
      PIN_NUMBER='(0,0,0,0,0,0,0,0,0,0,0,0,0,0,0,0,0,0,0,0,0,0,DM6,0,0,0,0,0,0,0,0,0,0,0,0,0,0,0,0,0,0,0)';
      OUTPUT_LOAD='(1.0,-1.0)';
    'UPI1_TX_DP6':
      PIN_NUMBER='(0,0,0,0,0,0,0,0,0,0,0,0,0,0,0,0,0,0,0,0,0,0,DN5,0,0,0,0,0,0,0,0,0,0,0,0,0,0,0,0,0,0,0)';
      OUTPUT_LOAD='(1.0,-1.0)';
    'UPI1_TX_DP5':
      PIN_NUMBER='(0,0,0,0,0,0,0,0,0,0,0,0,0,0,0,0,0,0,0,0,0,0,DR7,0,0,0,0,0,0,0,0,0,0,0,0,0,0,0,0,0,0,0)';
      OUTPUT_LOAD='(1.0,-1.0)';
    'UPI1_TX_DP4':
      PIN_NUMBER='(0,0,0,0,0,0,0,0,0,0,0,0,0,0,0,0,0,0,0,0,0,0,DU5,0,0,0,0,0,0,0,0,0,0,0,0,0,0,0,0,0,0,0)';
      OUTPUT_LOAD='(1.0,-1.0)';
    'UPI1_TX_DP3':
      PIN_NUMBER='(0,0,0,0,0,0,0,0,0,0,0,0,0,0,0,0,0,0,0,0,0,0,DW7,0,0,0,0,0,0,0,0,0,0,0,0,0,0,0,0,0,0,0)';
      OUTPUT_LOAD='(1.0,-1.0)';
    'UPI1_TX_DP2':
      PIN_NUMBER='(0,0,0,0,0,0,0,0,0,0,0,0,0,0,0,0,0,0,0,0,0,0,EA5,0,0,0,0,0,0,0,0,0,0,0,0,0,0,0,0,0,0,0)';
      OUTPUT_LOAD='(1.0,-1.0)';
    'UPI1_TX_DP1':
      PIN_NUMBER='(0,0,0,0,0,0,0,0,0,0,0,0,0,0,0,0,0,0,0,0,0,0,ED6,0,0,0,0,0,0,0,0,0,0,0,0,0,0,0,0,0,0,0)';
      OUTPUT_LOAD='(1.0,-1.0)';
    'UPI1_TX_DP0':
      PIN_NUMBER='(0,0,0,0,0,0,0,0,0,0,0,0,0,0,0,0,0,0,0,0,0,0,EE5,0,0,0,0,0,0,0,0,0,0,0,0,0,0,0,0,0,0,0)';
      OUTPUT_LOAD='(1.0,-1.0)';
    'UPI2_RX_DN23':
      PIN_NUMBER='(0,0,0,0,0,0,0,0,0,0,0,0,0,0,0,0,0,0,0,0,0,0,0,BD73,0,0,0,0,0,0,0,0,0,0,0,0,0,0,0,0,0,0)';
      INPUT_LOAD='(-0.01,0.01)';
    'UPI2_RX_DN22':
      PIN_NUMBER='(0,0,0,0,0,0,0,0,0,0,0,0,0,0,0,0,0,0,0,0,0,0,0,BK73,0,0,0,0,0,0,0,0,0,0,0,0,0,0,0,0,0,0)';
      INPUT_LOAD='(-0.01,0.01)';
    'UPI2_RX_DN21':
      PIN_NUMBER='(0,0,0,0,0,0,0,0,0,0,0,0,0,0,0,0,0,0,0,0,0,0,0,BN74,0,0,0,0,0,0,0,0,0,0,0,0,0,0,0,0,0,0)';
      INPUT_LOAD='(-0.01,0.01)';
    'UPI2_RX_DN20':
      PIN_NUMBER='(0,0,0,0,0,0,0,0,0,0,0,0,0,0,0,0,0,0,0,0,0,0,0,BG74,0,0,0,0,0,0,0,0,0,0,0,0,0,0,0,0,0,0)';
      INPUT_LOAD='(-0.01,0.01)';
    'UPI2_RX_DN19':
      PIN_NUMBER='(0,0,0,0,0,0,0,0,0,0,0,0,0,0,0,0,0,0,0,0,0,0,0,BL76,0,0,0,0,0,0,0,0,0,0,0,0,0,0,0,0,0,0)';
      INPUT_LOAD='(-0.01,0.01)';
    'UPI2_RX_DN18':
      PIN_NUMBER='(0,0,0,0,0,0,0,0,0,0,0,0,0,0,0,0,0,0,0,0,0,0,0,BJ76,0,0,0,0,0,0,0,0,0,0,0,0,0,0,0,0,0,0)';
      INPUT_LOAD='(-0.01,0.01)';
    'UPI2_RX_DN17':
      PIN_NUMBER='(0,0,0,0,0,0,0,0,0,0,0,0,0,0,0,0,0,0,0,0,0,0,0,BH75,0,0,0,0,0,0,0,0,0,0,0,0,0,0,0,0,0,0)';
      INPUT_LOAD='(-0.01,0.01)';
    'UPI2_RX_DN16':
      PIN_NUMBER='(0,0,0,0,0,0,0,0,0,0,0,0,0,0,0,0,0,0,0,0,0,0,0,AW74,0,0,0,0,0,0,0,0,0,0,0,0,0,0,0,0,0,0)';
      INPUT_LOAD='(-0.01,0.01)';
    'UPI2_RX_DN15':
      PIN_NUMBER='(0,0,0,0,0,0,0,0,0,0,0,0,0,0,0,0,0,0,0,0,0,0,0,BB75,0,0,0,0,0,0,0,0,0,0,0,0,0,0,0,0,0,0)';
      INPUT_LOAD='(-0.01,0.01)';
    'UPI2_RX_DN14':
      PIN_NUMBER='(0,0,0,0,0,0,0,0,0,0,0,0,0,0,0,0,0,0,0,0,0,0,0,AY75,0,0,0,0,0,0,0,0,0,0,0,0,0,0,0,0,0,0)';
      INPUT_LOAD='(-0.01,0.01)';
    'UPI2_RX_DN13':
      PIN_NUMBER='(0,0,0,0,0,0,0,0,0,0,0,0,0,0,0,0,0,0,0,0,0,0,0,AV73,0,0,0,0,0,0,0,0,0,0,0,0,0,0,0,0,0,0)';
      INPUT_LOAD='(-0.01,0.01)';
    'UPI2_RX_DN12':
      PIN_NUMBER='(0,0,0,0,0,0,0,0,0,0,0,0,0,0,0,0,0,0,0,0,0,0,0,BA72,0,0,0,0,0,0,0,0,0,0,0,0,0,0,0,0,0,0)';
      INPUT_LOAD='(-0.01,0.01)';
    'UPI2_RX_DN11':
      PIN_NUMBER='(0,0,0,0,0,0,0,0,0,0,0,0,0,0,0,0,0,0,0,0,0,0,0,AG82,0,0,0,0,0,0,0,0,0,0,0,0,0,0,0,0,0,0)';
      INPUT_LOAD='(-0.01,0.01)';
    'UPI2_RX_DN10':
      PIN_NUMBER='(0,0,0,0,0,0,0,0,0,0,0,0,0,0,0,0,0,0,0,0,0,0,0,AJ80,0,0,0,0,0,0,0,0,0,0,0,0,0,0,0,0,0,0)';
      INPUT_LOAD='(-0.01,0.01)';
    'UPI2_RX_DN9':
      PIN_NUMBER='(0,0,0,0,0,0,0,0,0,0,0,0,0,0,0,0,0,0,0,0,0,0,0,AE82,0,0,0,0,0,0,0,0,0,0,0,0,0,0,0,0,0,0)';
      INPUT_LOAD='(-0.01,0.01)';
    'UPI2_RX_DN8':
      PIN_NUMBER='(0,0,0,0,0,0,0,0,0,0,0,0,0,0,0,0,0,0,0,0,0,0,0,AF79,0,0,0,0,0,0,0,0,0,0,0,0,0,0,0,0,0,0)';
      INPUT_LOAD='(-0.01,0.01)';
    'UPI2_RX_DN7':
      PIN_NUMBER='(0,0,0,0,0,0,0,0,0,0,0,0,0,0,0,0,0,0,0,0,0,0,0,AD81,0,0,0,0,0,0,0,0,0,0,0,0,0,0,0,0,0,0)';
      INPUT_LOAD='(-0.01,0.01)';
    'UPI2_RX_DN6':
      PIN_NUMBER='(0,0,0,0,0,0,0,0,0,0,0,0,0,0,0,0,0,0,0,0,0,0,0,AC80,0,0,0,0,0,0,0,0,0,0,0,0,0,0,0,0,0,0)';
      INPUT_LOAD='(-0.01,0.01)';
    'UPI2_RX_DN5':
      PIN_NUMBER='(0,0,0,0,0,0,0,0,0,0,0,0,0,0,0,0,0,0,0,0,0,0,0,L80,0,0,0,0,0,0,0,0,0,0,0,0,0,0,0,0,0,0)';
      INPUT_LOAD='(-0.01,0.01)';
    'UPI2_RX_DN4':
      PIN_NUMBER='(0,0,0,0,0,0,0,0,0,0,0,0,0,0,0,0,0,0,0,0,0,0,0,J82,0,0,0,0,0,0,0,0,0,0,0,0,0,0,0,0,0,0)';
      INPUT_LOAD='(-0.01,0.01)';
    'UPI2_RX_DN3':
      PIN_NUMBER='(0,0,0,0,0,0,0,0,0,0,0,0,0,0,0,0,0,0,0,0,0,0,0,K79,0,0,0,0,0,0,0,0,0,0,0,0,0,0,0,0,0,0)';
      INPUT_LOAD='(-0.01,0.01)';
    'UPI2_RX_DN2':
      PIN_NUMBER='(0,0,0,0,0,0,0,0,0,0,0,0,0,0,0,0,0,0,0,0,0,0,0,G82,0,0,0,0,0,0,0,0,0,0,0,0,0,0,0,0,0,0)';
      INPUT_LOAD='(-0.01,0.01)';
    'UPI2_RX_DN1':
      PIN_NUMBER='(0,0,0,0,0,0,0,0,0,0,0,0,0,0,0,0,0,0,0,0,0,0,0,F81,0,0,0,0,0,0,0,0,0,0,0,0,0,0,0,0,0,0)';
      INPUT_LOAD='(-0.01,0.01)';
    'UPI2_RX_DN0':
      PIN_NUMBER='(0,0,0,0,0,0,0,0,0,0,0,0,0,0,0,0,0,0,0,0,0,0,0,E80,0,0,0,0,0,0,0,0,0,0,0,0,0,0,0,0,0,0)';
      INPUT_LOAD='(-0.01,0.01)';
    'UPI2_RX_DP23':
      PIN_NUMBER='(0,0,0,0,0,0,0,0,0,0,0,0,0,0,0,0,0,0,0,0,0,0,0,BC74,0,0,0,0,0,0,0,0,0,0,0,0,0,0,0,0,0,0)';
      INPUT_LOAD='(-0.01,0.01)';
    'UPI2_RX_DP22':
      PIN_NUMBER='(0,0,0,0,0,0,0,0,0,0,0,0,0,0,0,0,0,0,0,0,0,0,0,BL74,0,0,0,0,0,0,0,0,0,0,0,0,0,0,0,0,0,0)';
      INPUT_LOAD='(-0.01,0.01)';
    'UPI2_RX_DP21':
      PIN_NUMBER='(0,0,0,0,0,0,0,0,0,0,0,0,0,0,0,0,0,0,0,0,0,0,0,BM75,0,0,0,0,0,0,0,0,0,0,0,0,0,0,0,0,0,0)';
      INPUT_LOAD='(-0.01,0.01)';
    'UPI2_RX_DP20':
      PIN_NUMBER='(0,0,0,0,0,0,0,0,0,0,0,0,0,0,0,0,0,0,0,0,0,0,0,BJ74,0,0,0,0,0,0,0,0,0,0,0,0,0,0,0,0,0,0)';
      INPUT_LOAD='(-0.01,0.01)';
    'UPI2_RX_DP19':
      PIN_NUMBER='(0,0,0,0,0,0,0,0,0,0,0,0,0,0,0,0,0,0,0,0,0,0,0,BN76,0,0,0,0,0,0,0,0,0,0,0,0,0,0,0,0,0,0)';
      INPUT_LOAD='(-0.01,0.01)';
    'UPI2_RX_DP18':
      PIN_NUMBER='(0,0,0,0,0,0,0,0,0,0,0,0,0,0,0,0,0,0,0,0,0,0,0,BK77,0,0,0,0,0,0,0,0,0,0,0,0,0,0,0,0,0,0)';
      INPUT_LOAD='(-0.01,0.01)';
    'UPI2_RX_DP17':
      PIN_NUMBER='(0,0,0,0,0,0,0,0,0,0,0,0,0,0,0,0,0,0,0,0,0,0,0,BG76,0,0,0,0,0,0,0,0,0,0,0,0,0,0,0,0,0,0)';
      INPUT_LOAD='(-0.01,0.01)';
    'UPI2_RX_DP16':
      PIN_NUMBER='(0,0,0,0,0,0,0,0,0,0,0,0,0,0,0,0,0,0,0,0,0,0,0,AV75,0,0,0,0,0,0,0,0,0,0,0,0,0,0,0,0,0,0)';
      INPUT_LOAD='(-0.01,0.01)';
    'UPI2_RX_DP15':
      PIN_NUMBER='(0,0,0,0,0,0,0,0,0,0,0,0,0,0,0,0,0,0,0,0,0,0,0,BD75,0,0,0,0,0,0,0,0,0,0,0,0,0,0,0,0,0,0)';
      INPUT_LOAD='(-0.01,0.01)';
    'UPI2_RX_DP14':
      PIN_NUMBER='(0,0,0,0,0,0,0,0,0,0,0,0,0,0,0,0,0,0,0,0,0,0,0,BA76,0,0,0,0,0,0,0,0,0,0,0,0,0,0,0,0,0,0)';
      INPUT_LOAD='(-0.01,0.01)';
    'UPI2_RX_DP13':
      PIN_NUMBER='(0,0,0,0,0,0,0,0,0,0,0,0,0,0,0,0,0,0,0,0,0,0,0,AY73,0,0,0,0,0,0,0,0,0,0,0,0,0,0,0,0,0,0)';
      INPUT_LOAD='(-0.01,0.01)';
    'UPI2_RX_DP12':
      PIN_NUMBER='(0,0,0,0,0,0,0,0,0,0,0,0,0,0,0,0,0,0,0,0,0,0,0,BB73,0,0,0,0,0,0,0,0,0,0,0,0,0,0,0,0,0,0)';
      INPUT_LOAD='(-0.01,0.01)';
    'UPI2_RX_DP11':
      PIN_NUMBER='(0,0,0,0,0,0,0,0,0,0,0,0,0,0,0,0,0,0,0,0,0,0,0,AJ82,0,0,0,0,0,0,0,0,0,0,0,0,0,0,0,0,0,0)';
      INPUT_LOAD='(-0.01,0.01)';
    'UPI2_RX_DP10':
      PIN_NUMBER='(0,0,0,0,0,0,0,0,0,0,0,0,0,0,0,0,0,0,0,0,0,0,0,AH81,0,0,0,0,0,0,0,0,0,0,0,0,0,0,0,0,0,0)';
      INPUT_LOAD='(-0.01,0.01)';
    'UPI2_RX_DP9':
      PIN_NUMBER='(0,0,0,0,0,0,0,0,0,0,0,0,0,0,0,0,0,0,0,0,0,0,0,AF83,0,0,0,0,0,0,0,0,0,0,0,0,0,0,0,0,0,0)';
      INPUT_LOAD='(-0.01,0.01)';
    'UPI2_RX_DP8':
      PIN_NUMBER='(0,0,0,0,0,0,0,0,0,0,0,0,0,0,0,0,0,0,0,0,0,0,0,AG80,0,0,0,0,0,0,0,0,0,0,0,0,0,0,0,0,0,0)';
      INPUT_LOAD='(-0.01,0.01)';
    'UPI2_RX_DP7':
      PIN_NUMBER='(0,0,0,0,0,0,0,0,0,0,0,0,0,0,0,0,0,0,0,0,0,0,0,AC82,0,0,0,0,0,0,0,0,0,0,0,0,0,0,0,0,0,0)';
      INPUT_LOAD='(-0.01,0.01)';
    'UPI2_RX_DP6':
      PIN_NUMBER='(0,0,0,0,0,0,0,0,0,0,0,0,0,0,0,0,0,0,0,0,0,0,0,AE80,0,0,0,0,0,0,0,0,0,0,0,0,0,0,0,0,0,0)';
      INPUT_LOAD='(-0.01,0.01)';
    'UPI2_RX_DP5':
      PIN_NUMBER='(0,0,0,0,0,0,0,0,0,0,0,0,0,0,0,0,0,0,0,0,0,0,0,K81,0,0,0,0,0,0,0,0,0,0,0,0,0,0,0,0,0,0)';
      INPUT_LOAD='(-0.01,0.01)';
    'UPI2_RX_DP4':
      PIN_NUMBER='(0,0,0,0,0,0,0,0,0,0,0,0,0,0,0,0,0,0,0,0,0,0,0,L82,0,0,0,0,0,0,0,0,0,0,0,0,0,0,0,0,0,0)';
      INPUT_LOAD='(-0.01,0.01)';
    'UPI2_RX_DP3':
      PIN_NUMBER='(0,0,0,0,0,0,0,0,0,0,0,0,0,0,0,0,0,0,0,0,0,0,0,M79,0,0,0,0,0,0,0,0,0,0,0,0,0,0,0,0,0,0)';
      INPUT_LOAD='(-0.01,0.01)';
    'UPI2_RX_DP2':
      PIN_NUMBER='(0,0,0,0,0,0,0,0,0,0,0,0,0,0,0,0,0,0,0,0,0,0,0,H83,0,0,0,0,0,0,0,0,0,0,0,0,0,0,0,0,0,0)';
      INPUT_LOAD='(-0.01,0.01)';
    'UPI2_RX_DP1':
      PIN_NUMBER='(0,0,0,0,0,0,0,0,0,0,0,0,0,0,0,0,0,0,0,0,0,0,0,E82,0,0,0,0,0,0,0,0,0,0,0,0,0,0,0,0,0,0)';
      INPUT_LOAD='(-0.01,0.01)';
    'UPI2_RX_DP0':
      PIN_NUMBER='(0,0,0,0,0,0,0,0,0,0,0,0,0,0,0,0,0,0,0,0,0,0,0,G80,0,0,0,0,0,0,0,0,0,0,0,0,0,0,0,0,0,0)';
      INPUT_LOAD='(-0.01,0.01)';
    'UPI2_TX_DN23':
      PIN_NUMBER='(0,0,0,0,0,0,0,0,0,0,0,0,0,0,0,0,0,0,0,0,0,0,0,BM71,0,0,0,0,0,0,0,0,0,0,0,0,0,0,0,0,0,0)';
      OUTPUT_LOAD='(1.0,-1.0)';
    'UPI2_TX_DN22':
      PIN_NUMBER='(0,0,0,0,0,0,0,0,0,0,0,0,0,0,0,0,0,0,0,0,0,0,0,BG80,0,0,0,0,0,0,0,0,0,0,0,0,0,0,0,0,0,0)';
      OUTPUT_LOAD='(1.0,-1.0)';
    'UPI2_TX_DN21':
      PIN_NUMBER='(0,0,0,0,0,0,0,0,0,0,0,0,0,0,0,0,0,0,0,0,0,0,0,BF81,0,0,0,0,0,0,0,0,0,0,0,0,0,0,0,0,0,0)';
      OUTPUT_LOAD='(1.0,-1.0)';
    'UPI2_TX_DN20':
      PIN_NUMBER='(0,0,0,0,0,0,0,0,0,0,0,0,0,0,0,0,0,0,0,0,0,0,0,BD79,0,0,0,0,0,0,0,0,0,0,0,0,0,0,0,0,0,0)';
      OUTPUT_LOAD='(1.0,-1.0)';
    'UPI2_TX_DN19':
      PIN_NUMBER='(0,0,0,0,0,0,0,0,0,0,0,0,0,0,0,0,0,0,0,0,0,0,0,BE82,0,0,0,0,0,0,0,0,0,0,0,0,0,0,0,0,0,0)';
      OUTPUT_LOAD='(1.0,-1.0)';
    'UPI2_TX_DN18':
      PIN_NUMBER='(0,0,0,0,0,0,0,0,0,0,0,0,0,0,0,0,0,0,0,0,0,0,0,BC82,0,0,0,0,0,0,0,0,0,0,0,0,0,0,0,0,0,0)';
      OUTPUT_LOAD='(1.0,-1.0)';
    'UPI2_TX_DN17':
      PIN_NUMBER='(0,0,0,0,0,0,0,0,0,0,0,0,0,0,0,0,0,0,0,0,0,0,0,BA80,0,0,0,0,0,0,0,0,0,0,0,0,0,0,0,0,0,0)';
      OUTPUT_LOAD='(1.0,-1.0)';
    'UPI2_TX_DN16':
      PIN_NUMBER='(0,0,0,0,0,0,0,0,0,0,0,0,0,0,0,0,0,0,0,0,0,0,0,AV81,0,0,0,0,0,0,0,0,0,0,0,0,0,0,0,0,0,0)';
      OUTPUT_LOAD='(1.0,-1.0)';
    'UPI2_TX_DN15':
      PIN_NUMBER='(0,0,0,0,0,0,0,0,0,0,0,0,0,0,0,0,0,0,0,0,0,0,0,AT83,0,0,0,0,0,0,0,0,0,0,0,0,0,0,0,0,0,0)';
      OUTPUT_LOAD='(1.0,-1.0)';
    'UPI2_TX_DN14':
      PIN_NUMBER='(0,0,0,0,0,0,0,0,0,0,0,0,0,0,0,0,0,0,0,0,0,0,0,AR80,0,0,0,0,0,0,0,0,0,0,0,0,0,0,0,0,0,0)';
      OUTPUT_LOAD='(1.0,-1.0)';
    'UPI2_TX_DN13':
      PIN_NUMBER='(0,0,0,0,0,0,0,0,0,0,0,0,0,0,0,0,0,0,0,0,0,0,0,AN82,0,0,0,0,0,0,0,0,0,0,0,0,0,0,0,0,0,0)';
      OUTPUT_LOAD='(1.0,-1.0)';
    'UPI2_TX_DN12':
      PIN_NUMBER='(0,0,0,0,0,0,0,0,0,0,0,0,0,0,0,0,0,0,0,0,0,0,0,AM81,0,0,0,0,0,0,0,0,0,0,0,0,0,0,0,0,0,0)';
      OUTPUT_LOAD='(1.0,-1.0)';
    'UPI2_TX_DN11':
      PIN_NUMBER='(0,0,0,0,0,0,0,0,0,0,0,0,0,0,0,0,0,0,0,0,0,0,0,AU78,0,0,0,0,0,0,0,0,0,0,0,0,0,0,0,0,0,0)';
      OUTPUT_LOAD='(1.0,-1.0)';
    'UPI2_TX_DN10':
      PIN_NUMBER='(0,0,0,0,0,0,0,0,0,0,0,0,0,0,0,0,0,0,0,0,0,0,0,AW78,0,0,0,0,0,0,0,0,0,0,0,0,0,0,0,0,0,0)';
      OUTPUT_LOAD='(1.0,-1.0)';
    'UPI2_TX_DN9':
      PIN_NUMBER='(0,0,0,0,0,0,0,0,0,0,0,0,0,0,0,0,0,0,0,0,0,0,0,Y81,0,0,0,0,0,0,0,0,0,0,0,0,0,0,0,0,0,0)';
      OUTPUT_LOAD='(1.0,-1.0)';
    'UPI2_TX_DN8':
      PIN_NUMBER='(0,0,0,0,0,0,0,0,0,0,0,0,0,0,0,0,0,0,0,0,0,0,0,V83,0,0,0,0,0,0,0,0,0,0,0,0,0,0,0,0,0,0)';
      OUTPUT_LOAD='(1.0,-1.0)';
    'UPI2_TX_DN7':
      PIN_NUMBER='(0,0,0,0,0,0,0,0,0,0,0,0,0,0,0,0,0,0,0,0,0,0,0,U80,0,0,0,0,0,0,0,0,0,0,0,0,0,0,0,0,0,0)';
      OUTPUT_LOAD='(1.0,-1.0)';
    'UPI2_TX_DN6':
      PIN_NUMBER='(0,0,0,0,0,0,0,0,0,0,0,0,0,0,0,0,0,0,0,0,0,0,0,R82,0,0,0,0,0,0,0,0,0,0,0,0,0,0,0,0,0,0)';
      OUTPUT_LOAD='(1.0,-1.0)';
    'UPI2_TX_DN5':
      PIN_NUMBER='(0,0,0,0,0,0,0,0,0,0,0,0,0,0,0,0,0,0,0,0,0,0,0,P81,0,0,0,0,0,0,0,0,0,0,0,0,0,0,0,0,0,0)';
      OUTPUT_LOAD='(1.0,-1.0)';
    'UPI2_TX_DN4':
      PIN_NUMBER='(0,0,0,0,0,0,0,0,0,0,0,0,0,0,0,0,0,0,0,0,0,0,0,H85,0,0,0,0,0,0,0,0,0,0,0,0,0,0,0,0,0,0)';
      OUTPUT_LOAD='(1.0,-1.0)';
    'UPI2_TX_DN3':
      PIN_NUMBER='(0,0,0,0,0,0,0,0,0,0,0,0,0,0,0,0,0,0,0,0,0,0,0,F87,0,0,0,0,0,0,0,0,0,0,0,0,0,0,0,0,0,0)';
      OUTPUT_LOAD='(1.0,-1.0)';
    'UPI2_TX_DN2':
      PIN_NUMBER='(0,0,0,0,0,0,0,0,0,0,0,0,0,0,0,0,0,0,0,0,0,0,0,D87,0,0,0,0,0,0,0,0,0,0,0,0,0,0,0,0,0,0)';
      OUTPUT_LOAD='(1.0,-1.0)';
    'UPI2_TX_DN1':
      PIN_NUMBER='(0,0,0,0,0,0,0,0,0,0,0,0,0,0,0,0,0,0,0,0,0,0,0,E84,0,0,0,0,0,0,0,0,0,0,0,0,0,0,0,0,0,0)';
      OUTPUT_LOAD='(1.0,-1.0)';
    'UPI2_TX_DN0':
      PIN_NUMBER='(0,0,0,0,0,0,0,0,0,0,0,0,0,0,0,0,0,0,0,0,0,0,0,B85,0,0,0,0,0,0,0,0,0,0,0,0,0,0,0,0,0,0)';
      OUTPUT_LOAD='(1.0,-1.0)';
    'UPI2_TX_DP23':
      PIN_NUMBER='(0,0,0,0,0,0,0,0,0,0,0,0,0,0,0,0,0,0,0,0,0,0,0,BN72,0,0,0,0,0,0,0,0,0,0,0,0,0,0,0,0,0,0)';
      OUTPUT_LOAD='(1.0,-1.0)';
    'UPI2_TX_DP22':
      PIN_NUMBER='(0,0,0,0,0,0,0,0,0,0,0,0,0,0,0,0,0,0,0,0,0,0,0,BE80,0,0,0,0,0,0,0,0,0,0,0,0,0,0,0,0,0,0)';
      OUTPUT_LOAD='(1.0,-1.0)';
    'UPI2_TX_DP21':
      PIN_NUMBER='(0,0,0,0,0,0,0,0,0,0,0,0,0,0,0,0,0,0,0,0,0,0,0,BG82,0,0,0,0,0,0,0,0,0,0,0,0,0,0,0,0,0,0)';
      OUTPUT_LOAD='(1.0,-1.0)';
    'UPI2_TX_DP20':
      PIN_NUMBER='(0,0,0,0,0,0,0,0,0,0,0,0,0,0,0,0,0,0,0,0,0,0,0,BC80,0,0,0,0,0,0,0,0,0,0,0,0,0,0,0,0,0,0)';
      OUTPUT_LOAD='(1.0,-1.0)';
    'UPI2_TX_DP19':
      PIN_NUMBER='(0,0,0,0,0,0,0,0,0,0,0,0,0,0,0,0,0,0,0,0,0,0,0,BD83,0,0,0,0,0,0,0,0,0,0,0,0,0,0,0,0,0,0)';
      OUTPUT_LOAD='(1.0,-1.0)';
    'UPI2_TX_DP18':
      PIN_NUMBER='(0,0,0,0,0,0,0,0,0,0,0,0,0,0,0,0,0,0,0,0,0,0,0,BA82,0,0,0,0,0,0,0,0,0,0,0,0,0,0,0,0,0,0)';
      OUTPUT_LOAD='(1.0,-1.0)';
    'UPI2_TX_DP17':
      PIN_NUMBER='(0,0,0,0,0,0,0,0,0,0,0,0,0,0,0,0,0,0,0,0,0,0,0,BB81,0,0,0,0,0,0,0,0,0,0,0,0,0,0,0,0,0,0)';
      OUTPUT_LOAD='(1.0,-1.0)';
    'UPI2_TX_DP16':
      PIN_NUMBER='(0,0,0,0,0,0,0,0,0,0,0,0,0,0,0,0,0,0,0,0,0,0,0,AU82,0,0,0,0,0,0,0,0,0,0,0,0,0,0,0,0,0,0)';
      OUTPUT_LOAD='(1.0,-1.0)';
    'UPI2_TX_DP15':
      PIN_NUMBER='(0,0,0,0,0,0,0,0,0,0,0,0,0,0,0,0,0,0,0,0,0,0,0,AV83,0,0,0,0,0,0,0,0,0,0,0,0,0,0,0,0,0,0)';
      OUTPUT_LOAD='(1.0,-1.0)';
    'UPI2_TX_DP14':
      PIN_NUMBER='(0,0,0,0,0,0,0,0,0,0,0,0,0,0,0,0,0,0,0,0,0,0,0,AT81,0,0,0,0,0,0,0,0,0,0,0,0,0,0,0,0,0,0)';
      OUTPUT_LOAD='(1.0,-1.0)';
    'UPI2_TX_DP13':
      PIN_NUMBER='(0,0,0,0,0,0,0,0,0,0,0,0,0,0,0,0,0,0,0,0,0,0,0,AM83,0,0,0,0,0,0,0,0,0,0,0,0,0,0,0,0,0,0)';
      OUTPUT_LOAD='(1.0,-1.0)';
    'UPI2_TX_DP12':
      PIN_NUMBER='(0,0,0,0,0,0,0,0,0,0,0,0,0,0,0,0,0,0,0,0,0,0,0,AP81,0,0,0,0,0,0,0,0,0,0,0,0,0,0,0,0,0,0)';
      OUTPUT_LOAD='(1.0,-1.0)';
    'UPI2_TX_DP11':
      PIN_NUMBER='(0,0,0,0,0,0,0,0,0,0,0,0,0,0,0,0,0,0,0,0,0,0,0,AV79,0,0,0,0,0,0,0,0,0,0,0,0,0,0,0,0,0,0)';
      OUTPUT_LOAD='(1.0,-1.0)';
    'UPI2_TX_DP10':
      PIN_NUMBER='(0,0,0,0,0,0,0,0,0,0,0,0,0,0,0,0,0,0,0,0,0,0,0,BA78,0,0,0,0,0,0,0,0,0,0,0,0,0,0,0,0,0,0)';
      OUTPUT_LOAD='(1.0,-1.0)';
    'UPI2_TX_DP9':
      PIN_NUMBER='(0,0,0,0,0,0,0,0,0,0,0,0,0,0,0,0,0,0,0,0,0,0,0,W82,0,0,0,0,0,0,0,0,0,0,0,0,0,0,0,0,0,0)';
      OUTPUT_LOAD='(1.0,-1.0)';
    'UPI2_TX_DP8':
      PIN_NUMBER='(0,0,0,0,0,0,0,0,0,0,0,0,0,0,0,0,0,0,0,0,0,0,0,Y83,0,0,0,0,0,0,0,0,0,0,0,0,0,0,0,0,0,0)';
      OUTPUT_LOAD='(1.0,-1.0)';
    'UPI2_TX_DP7':
      PIN_NUMBER='(0,0,0,0,0,0,0,0,0,0,0,0,0,0,0,0,0,0,0,0,0,0,0,V81,0,0,0,0,0,0,0,0,0,0,0,0,0,0,0,0,0,0)';
      OUTPUT_LOAD='(1.0,-1.0)';
    'UPI2_TX_DP6':
      PIN_NUMBER='(0,0,0,0,0,0,0,0,0,0,0,0,0,0,0,0,0,0,0,0,0,0,0,P83,0,0,0,0,0,0,0,0,0,0,0,0,0,0,0,0,0,0)';
      OUTPUT_LOAD='(1.0,-1.0)';
    'UPI2_TX_DP5':
      PIN_NUMBER='(0,0,0,0,0,0,0,0,0,0,0,0,0,0,0,0,0,0,0,0,0,0,0,T81,0,0,0,0,0,0,0,0,0,0,0,0,0,0,0,0,0,0)';
      OUTPUT_LOAD='(1.0,-1.0)';
    'UPI2_TX_DP4':
      PIN_NUMBER='(0,0,0,0,0,0,0,0,0,0,0,0,0,0,0,0,0,0,0,0,0,0,0,G86,0,0,0,0,0,0,0,0,0,0,0,0,0,0,0,0,0,0)';
      OUTPUT_LOAD='(1.0,-1.0)';
    'UPI2_TX_DP3':
      PIN_NUMBER='(0,0,0,0,0,0,0,0,0,0,0,0,0,0,0,0,0,0,0,0,0,0,0,H87,0,0,0,0,0,0,0,0,0,0,0,0,0,0,0,0,0,0)';
      OUTPUT_LOAD='(1.0,-1.0)';
    'UPI2_TX_DP2':
      PIN_NUMBER='(0,0,0,0,0,0,0,0,0,0,0,0,0,0,0,0,0,0,0,0,0,0,0,E88,0,0,0,0,0,0,0,0,0,0,0,0,0,0,0,0,0,0)';
      OUTPUT_LOAD='(1.0,-1.0)';
    'UPI2_TX_DP1':
      PIN_NUMBER='(0,0,0,0,0,0,0,0,0,0,0,0,0,0,0,0,0,0,0,0,0,0,0,F85,0,0,0,0,0,0,0,0,0,0,0,0,0,0,0,0,0,0)';
      OUTPUT_LOAD='(1.0,-1.0)';
    'UPI2_TX_DP0':
      PIN_NUMBER='(0,0,0,0,0,0,0,0,0,0,0,0,0,0,0,0,0,0,0,0,0,0,0,D85,0,0,0,0,0,0,0,0,0,0,0,0,0,0,0,0,0,0)';
      OUTPUT_LOAD='(1.0,-1.0)';
    'UPI3_RX_DN23':
      PIN_NUMBER='(0,0,0,0,0,0,0,0,0,0,0,0,0,0,0,0,0,0,0,0,0,0,0,0,DA78,0,0,0,0,0,0,0,0,0,0,0,0,0,0,0,0,0)';
      INPUT_LOAD='(-0.01,0.01)';
    'UPI3_RX_DN22':
      PIN_NUMBER='(0,0,0,0,0,0,0,0,0,0,0,0,0,0,0,0,0,0,0,0,0,0,0,0,CT79,0,0,0,0,0,0,0,0,0,0,0,0,0,0,0,0,0)';
      INPUT_LOAD='(-0.01,0.01)';
    'UPI3_RX_DN21':
      PIN_NUMBER='(0,0,0,0,0,0,0,0,0,0,0,0,0,0,0,0,0,0,0,0,0,0,0,0,CN80,0,0,0,0,0,0,0,0,0,0,0,0,0,0,0,0,0)';
      INPUT_LOAD='(-0.01,0.01)';
    'UPI3_RX_DN20':
      PIN_NUMBER='(0,0,0,0,0,0,0,0,0,0,0,0,0,0,0,0,0,0,0,0,0,0,0,0,CP81,0,0,0,0,0,0,0,0,0,0,0,0,0,0,0,0,0)';
      INPUT_LOAD='(-0.01,0.01)';
    'UPI3_RX_DN19':
      PIN_NUMBER='(0,0,0,0,0,0,0,0,0,0,0,0,0,0,0,0,0,0,0,0,0,0,0,0,CW80,0,0,0,0,0,0,0,0,0,0,0,0,0,0,0,0,0)';
      INPUT_LOAD='(-0.01,0.01)';
    'UPI3_RX_DN18':
      PIN_NUMBER='(0,0,0,0,0,0,0,0,0,0,0,0,0,0,0,0,0,0,0,0,0,0,0,0,CR82,0,0,0,0,0,0,0,0,0,0,0,0,0,0,0,0,0)';
      INPUT_LOAD='(-0.01,0.01)';
    'UPI3_RX_DN17':
      PIN_NUMBER='(0,0,0,0,0,0,0,0,0,0,0,0,0,0,0,0,0,0,0,0,0,0,0,0,CU82,0,0,0,0,0,0,0,0,0,0,0,0,0,0,0,0,0)';
      INPUT_LOAD='(-0.01,0.01)';
    'UPI3_RX_DN16':
      PIN_NUMBER='(0,0,0,0,0,0,0,0,0,0,0,0,0,0,0,0,0,0,0,0,0,0,0,0,DF77,0,0,0,0,0,0,0,0,0,0,0,0,0,0,0,0,0)';
      INPUT_LOAD='(-0.01,0.01)';
    'UPI3_RX_DN15':
      PIN_NUMBER='(0,0,0,0,0,0,0,0,0,0,0,0,0,0,0,0,0,0,0,0,0,0,0,0,DB81,0,0,0,0,0,0,0,0,0,0,0,0,0,0,0,0,0)';
      INPUT_LOAD='(-0.01,0.01)';
    'UPI3_RX_DN14':
      PIN_NUMBER='(0,0,0,0,0,0,0,0,0,0,0,0,0,0,0,0,0,0,0,0,0,0,0,0,DC82,0,0,0,0,0,0,0,0,0,0,0,0,0,0,0,0,0)';
      INPUT_LOAD='(-0.01,0.01)';
    'UPI3_RX_DN13':
      PIN_NUMBER='(0,0,0,0,0,0,0,0,0,0,0,0,0,0,0,0,0,0,0,0,0,0,0,0,DE80,0,0,0,0,0,0,0,0,0,0,0,0,0,0,0,0,0)';
      INPUT_LOAD='(-0.01,0.01)';
    'UPI3_RX_DN12':
      PIN_NUMBER='(0,0,0,0,0,0,0,0,0,0,0,0,0,0,0,0,0,0,0,0,0,0,0,0,DF83,0,0,0,0,0,0,0,0,0,0,0,0,0,0,0,0,0)';
      INPUT_LOAD='(-0.01,0.01)';
    'UPI3_RX_DN11':
      PIN_NUMBER='(0,0,0,0,0,0,0,0,0,0,0,0,0,0,0,0,0,0,0,0,0,0,0,0,DH81,0,0,0,0,0,0,0,0,0,0,0,0,0,0,0,0,0)';
      INPUT_LOAD='(-0.01,0.01)';
    'UPI3_RX_DN10':
      PIN_NUMBER='(0,0,0,0,0,0,0,0,0,0,0,0,0,0,0,0,0,0,0,0,0,0,0,0,DG78,0,0,0,0,0,0,0,0,0,0,0,0,0,0,0,0,0)';
      INPUT_LOAD='(-0.01,0.01)';
    'UPI3_RX_DN9':
      PIN_NUMBER='(0,0,0,0,0,0,0,0,0,0,0,0,0,0,0,0,0,0,0,0,0,0,0,0,DJ78,0,0,0,0,0,0,0,0,0,0,0,0,0,0,0,0,0)';
      INPUT_LOAD='(-0.01,0.01)';
    'UPI3_RX_DN8':
      PIN_NUMBER='(0,0,0,0,0,0,0,0,0,0,0,0,0,0,0,0,0,0,0,0,0,0,0,0,DY81,0,0,0,0,0,0,0,0,0,0,0,0,0,0,0,0,0)';
      INPUT_LOAD='(-0.01,0.01)';
    'UPI3_RX_DN7':
      PIN_NUMBER='(0,0,0,0,0,0,0,0,0,0,0,0,0,0,0,0,0,0,0,0,0,0,0,0,EA82,0,0,0,0,0,0,0,0,0,0,0,0,0,0,0,0,0)';
      INPUT_LOAD='(-0.01,0.01)';
    'UPI3_RX_DN6':
      PIN_NUMBER='(0,0,0,0,0,0,0,0,0,0,0,0,0,0,0,0,0,0,0,0,0,0,0,0,EC80,0,0,0,0,0,0,0,0,0,0,0,0,0,0,0,0,0)';
      INPUT_LOAD='(-0.01,0.01)';
    'UPI3_RX_DN5':
      PIN_NUMBER='(0,0,0,0,0,0,0,0,0,0,0,0,0,0,0,0,0,0,0,0,0,0,0,0,ED83,0,0,0,0,0,0,0,0,0,0,0,0,0,0,0,0,0)';
      INPUT_LOAD='(-0.01,0.01)';
    'UPI3_RX_DN4':
      PIN_NUMBER='(0,0,0,0,0,0,0,0,0,0,0,0,0,0,0,0,0,0,0,0,0,0,0,0,EF81,0,0,0,0,0,0,0,0,0,0,0,0,0,0,0,0,0)';
      INPUT_LOAD='(-0.01,0.01)';
    'UPI3_RX_DN3':
      PIN_NUMBER='(0,0,0,0,0,0,0,0,0,0,0,0,0,0,0,0,0,0,0,0,0,0,0,0,EK81,0,0,0,0,0,0,0,0,0,0,0,0,0,0,0,0,0)';
      INPUT_LOAD='(-0.01,0.01)';
    'UPI3_RX_DN2':
      PIN_NUMBER='(0,0,0,0,0,0,0,0,0,0,0,0,0,0,0,0,0,0,0,0,0,0,0,0,EL82,0,0,0,0,0,0,0,0,0,0,0,0,0,0,0,0,0)';
      INPUT_LOAD='(-0.01,0.01)';
    'UPI3_RX_DN1':
      PIN_NUMBER='(0,0,0,0,0,0,0,0,0,0,0,0,0,0,0,0,0,0,0,0,0,0,0,0,EP81,0,0,0,0,0,0,0,0,0,0,0,0,0,0,0,0,0)';
      INPUT_LOAD='(-0.01,0.01)';
    'UPI3_RX_DN0':
      PIN_NUMBER='(0,0,0,0,0,0,0,0,0,0,0,0,0,0,0,0,0,0,0,0,0,0,0,0,EJ80,0,0,0,0,0,0,0,0,0,0,0,0,0,0,0,0,0)';
      INPUT_LOAD='(-0.01,0.01)';
    'UPI3_RX_DP23':
      PIN_NUMBER='(0,0,0,0,0,0,0,0,0,0,0,0,0,0,0,0,0,0,0,0,0,0,0,0,DB79,0,0,0,0,0,0,0,0,0,0,0,0,0,0,0,0,0)';
      INPUT_LOAD='(-0.01,0.01)';
    'UPI3_RX_DP22':
      PIN_NUMBER='(0,0,0,0,0,0,0,0,0,0,0,0,0,0,0,0,0,0,0,0,0,0,0,0,CU80,0,0,0,0,0,0,0,0,0,0,0,0,0,0,0,0,0)';
      INPUT_LOAD='(-0.01,0.01)';
    'UPI3_RX_DP21':
      PIN_NUMBER='(0,0,0,0,0,0,0,0,0,0,0,0,0,0,0,0,0,0,0,0,0,0,0,0,CR80,0,0,0,0,0,0,0,0,0,0,0,0,0,0,0,0,0)';
      INPUT_LOAD='(-0.01,0.01)';
    'UPI3_RX_DP20':
      PIN_NUMBER='(0,0,0,0,0,0,0,0,0,0,0,0,0,0,0,0,0,0,0,0,0,0,0,0,CN82,0,0,0,0,0,0,0,0,0,0,0,0,0,0,0,0,0)';
      INPUT_LOAD='(-0.01,0.01)';
    'UPI3_RX_DP19':
      PIN_NUMBER='(0,0,0,0,0,0,0,0,0,0,0,0,0,0,0,0,0,0,0,0,0,0,0,0,CV81,0,0,0,0,0,0,0,0,0,0,0,0,0,0,0,0,0)';
      INPUT_LOAD='(-0.01,0.01)';
    'UPI3_RX_DP18':
      PIN_NUMBER='(0,0,0,0,0,0,0,0,0,0,0,0,0,0,0,0,0,0,0,0,0,0,0,0,CT83,0,0,0,0,0,0,0,0,0,0,0,0,0,0,0,0,0)';
      INPUT_LOAD='(-0.01,0.01)';
    'UPI3_RX_DP17':
      PIN_NUMBER='(0,0,0,0,0,0,0,0,0,0,0,0,0,0,0,0,0,0,0,0,0,0,0,0,CW82,0,0,0,0,0,0,0,0,0,0,0,0,0,0,0,0,0)';
      INPUT_LOAD='(-0.01,0.01)';
    'UPI3_RX_DP16':
      PIN_NUMBER='(0,0,0,0,0,0,0,0,0,0,0,0,0,0,0,0,0,0,0,0,0,0,0,0,DE78,0,0,0,0,0,0,0,0,0,0,0,0,0,0,0,0,0)';
      INPUT_LOAD='(-0.01,0.01)';
    'UPI3_RX_DP15':
      PIN_NUMBER='(0,0,0,0,0,0,0,0,0,0,0,0,0,0,0,0,0,0,0,0,0,0,0,0,DD81,0,0,0,0,0,0,0,0,0,0,0,0,0,0,0,0,0)';
      INPUT_LOAD='(-0.01,0.01)';
    'UPI3_RX_DP14':
      PIN_NUMBER='(0,0,0,0,0,0,0,0,0,0,0,0,0,0,0,0,0,0,0,0,0,0,0,0,DB83,0,0,0,0,0,0,0,0,0,0,0,0,0,0,0,0,0)';
      INPUT_LOAD='(-0.01,0.01)';
    'UPI3_RX_DP13':
      PIN_NUMBER='(0,0,0,0,0,0,0,0,0,0,0,0,0,0,0,0,0,0,0,0,0,0,0,0,DF81,0,0,0,0,0,0,0,0,0,0,0,0,0,0,0,0,0)';
      INPUT_LOAD='(-0.01,0.01)';
    'UPI3_RX_DP12':
      PIN_NUMBER='(0,0,0,0,0,0,0,0,0,0,0,0,0,0,0,0,0,0,0,0,0,0,0,0,DH83,0,0,0,0,0,0,0,0,0,0,0,0,0,0,0,0,0)';
      INPUT_LOAD='(-0.01,0.01)';
    'UPI3_RX_DP11':
      PIN_NUMBER='(0,0,0,0,0,0,0,0,0,0,0,0,0,0,0,0,0,0,0,0,0,0,0,0,DG82,0,0,0,0,0,0,0,0,0,0,0,0,0,0,0,0,0)';
      INPUT_LOAD='(-0.01,0.01)';
    'UPI3_RX_DP10':
      PIN_NUMBER='(0,0,0,0,0,0,0,0,0,0,0,0,0,0,0,0,0,0,0,0,0,0,0,0,DH79,0,0,0,0,0,0,0,0,0,0,0,0,0,0,0,0,0)';
      INPUT_LOAD='(-0.01,0.01)';
    'UPI3_RX_DP9':
      PIN_NUMBER='(0,0,0,0,0,0,0,0,0,0,0,0,0,0,0,0,0,0,0,0,0,0,0,0,DL78,0,0,0,0,0,0,0,0,0,0,0,0,0,0,0,0,0)';
      INPUT_LOAD='(-0.01,0.01)';
    'UPI3_RX_DP8':
      PIN_NUMBER='(0,0,0,0,0,0,0,0,0,0,0,0,0,0,0,0,0,0,0,0,0,0,0,0,EB81,0,0,0,0,0,0,0,0,0,0,0,0,0,0,0,0,0)';
      INPUT_LOAD='(-0.01,0.01)';
    'UPI3_RX_DP7':
      PIN_NUMBER='(0,0,0,0,0,0,0,0,0,0,0,0,0,0,0,0,0,0,0,0,0,0,0,0,DY83,0,0,0,0,0,0,0,0,0,0,0,0,0,0,0,0,0)';
      INPUT_LOAD='(-0.01,0.01)';
    'UPI3_RX_DP6':
      PIN_NUMBER='(0,0,0,0,0,0,0,0,0,0,0,0,0,0,0,0,0,0,0,0,0,0,0,0,ED81,0,0,0,0,0,0,0,0,0,0,0,0,0,0,0,0,0)';
      INPUT_LOAD='(-0.01,0.01)';
    'UPI3_RX_DP5':
      PIN_NUMBER='(0,0,0,0,0,0,0,0,0,0,0,0,0,0,0,0,0,0,0,0,0,0,0,0,EF83,0,0,0,0,0,0,0,0,0,0,0,0,0,0,0,0,0)';
      INPUT_LOAD='(-0.01,0.01)';
    'UPI3_RX_DP4':
      PIN_NUMBER='(0,0,0,0,0,0,0,0,0,0,0,0,0,0,0,0,0,0,0,0,0,0,0,0,EE82,0,0,0,0,0,0,0,0,0,0,0,0,0,0,0,0,0)';
      INPUT_LOAD='(-0.01,0.01)';
    'UPI3_RX_DP3':
      PIN_NUMBER='(0,0,0,0,0,0,0,0,0,0,0,0,0,0,0,0,0,0,0,0,0,0,0,0,EJ82,0,0,0,0,0,0,0,0,0,0,0,0,0,0,0,0,0)';
      INPUT_LOAD='(-0.01,0.01)';
    'UPI3_RX_DP2':
      PIN_NUMBER='(0,0,0,0,0,0,0,0,0,0,0,0,0,0,0,0,0,0,0,0,0,0,0,0,EN82,0,0,0,0,0,0,0,0,0,0,0,0,0,0,0,0,0)';
      INPUT_LOAD='(-0.01,0.01)';
    'UPI3_RX_DP1':
      PIN_NUMBER='(0,0,0,0,0,0,0,0,0,0,0,0,0,0,0,0,0,0,0,0,0,0,0,0,ER82,0,0,0,0,0,0,0,0,0,0,0,0,0,0,0,0,0)';
      INPUT_LOAD='(-0.01,0.01)';
    'UPI3_RX_DP0':
      PIN_NUMBER='(0,0,0,0,0,0,0,0,0,0,0,0,0,0,0,0,0,0,0,0,0,0,0,0,EL80,0,0,0,0,0,0,0,0,0,0,0,0,0,0,0,0,0)';
      INPUT_LOAD='(-0.01,0.01)';
    'UPI3_TX_DN23':
      PIN_NUMBER='(0,0,0,0,0,0,0,0,0,0,0,0,0,0,0,0,0,0,0,0,0,0,0,0,CF73,0,0,0,0,0,0,0,0,0,0,0,0,0,0,0,0,0)';
      OUTPUT_LOAD='(1.0,-1.0)';
    'UPI3_TX_DN22':
      PIN_NUMBER='(0,0,0,0,0,0,0,0,0,0,0,0,0,0,0,0,0,0,0,0,0,0,0,0,CV73,0,0,0,0,0,0,0,0,0,0,0,0,0,0,0,0,0)';
      OUTPUT_LOAD='(1.0,-1.0)';
    'UPI3_TX_DN21':
      PIN_NUMBER='(0,0,0,0,0,0,0,0,0,0,0,0,0,0,0,0,0,0,0,0,0,0,0,0,CJ74,0,0,0,0,0,0,0,0,0,0,0,0,0,0,0,0,0)';
      OUTPUT_LOAD='(1.0,-1.0)';
    'UPI3_TX_DN20':
      PIN_NUMBER='(0,0,0,0,0,0,0,0,0,0,0,0,0,0,0,0,0,0,0,0,0,0,0,0,CF75,0,0,0,0,0,0,0,0,0,0,0,0,0,0,0,0,0)';
      OUTPUT_LOAD='(1.0,-1.0)';
    'UPI3_TX_DN19':
      PIN_NUMBER='(0,0,0,0,0,0,0,0,0,0,0,0,0,0,0,0,0,0,0,0,0,0,0,0,CG76,0,0,0,0,0,0,0,0,0,0,0,0,0,0,0,0,0)';
      OUTPUT_LOAD='(1.0,-1.0)';
    'UPI3_TX_DN18':
      PIN_NUMBER='(0,0,0,0,0,0,0,0,0,0,0,0,0,0,0,0,0,0,0,0,0,0,0,0,CM75,0,0,0,0,0,0,0,0,0,0,0,0,0,0,0,0,0)';
      OUTPUT_LOAD='(1.0,-1.0)';
    'UPI3_TX_DN17':
      PIN_NUMBER='(0,0,0,0,0,0,0,0,0,0,0,0,0,0,0,0,0,0,0,0,0,0,0,0,CH77,0,0,0,0,0,0,0,0,0,0,0,0,0,0,0,0,0)';
      OUTPUT_LOAD='(1.0,-1.0)';
    'UPI3_TX_DN16':
      PIN_NUMBER='(0,0,0,0,0,0,0,0,0,0,0,0,0,0,0,0,0,0,0,0,0,0,0,0,CK77,0,0,0,0,0,0,0,0,0,0,0,0,0,0,0,0,0)';
      OUTPUT_LOAD='(1.0,-1.0)';
    'UPI3_TX_DN15':
      PIN_NUMBER='(0,0,0,0,0,0,0,0,0,0,0,0,0,0,0,0,0,0,0,0,0,0,0,0,CR74,0,0,0,0,0,0,0,0,0,0,0,0,0,0,0,0,0)';
      OUTPUT_LOAD='(1.0,-1.0)';
    'UPI3_TX_DN14':
      PIN_NUMBER='(0,0,0,0,0,0,0,0,0,0,0,0,0,0,0,0,0,0,0,0,0,0,0,0,CT75,0,0,0,0,0,0,0,0,0,0,0,0,0,0,0,0,0)';
      OUTPUT_LOAD='(1.0,-1.0)';
    'UPI3_TX_DN13':
      PIN_NUMBER='(0,0,0,0,0,0,0,0,0,0,0,0,0,0,0,0,0,0,0,0,0,0,0,0,CU76,0,0,0,0,0,0,0,0,0,0,0,0,0,0,0,0,0)';
      OUTPUT_LOAD='(1.0,-1.0)';
    'UPI3_TX_DN12':
      PIN_NUMBER='(0,0,0,0,0,0,0,0,0,0,0,0,0,0,0,0,0,0,0,0,0,0,0,0,CW76,0,0,0,0,0,0,0,0,0,0,0,0,0,0,0,0,0)';
      OUTPUT_LOAD='(1.0,-1.0)';
    'UPI3_TX_DN11':
      PIN_NUMBER='(0,0,0,0,0,0,0,0,0,0,0,0,0,0,0,0,0,0,0,0,0,0,0,0,DL80,0,0,0,0,0,0,0,0,0,0,0,0,0,0,0,0,0)';
      OUTPUT_LOAD='(1.0,-1.0)';
    'UPI3_TX_DN10':
      PIN_NUMBER='(0,0,0,0,0,0,0,0,0,0,0,0,0,0,0,0,0,0,0,0,0,0,0,0,DM81,0,0,0,0,0,0,0,0,0,0,0,0,0,0,0,0,0)';
      OUTPUT_LOAD='(1.0,-1.0)';
    'UPI3_TX_DN9':
      PIN_NUMBER='(0,0,0,0,0,0,0,0,0,0,0,0,0,0,0,0,0,0,0,0,0,0,0,0,DN82,0,0,0,0,0,0,0,0,0,0,0,0,0,0,0,0,0)';
      OUTPUT_LOAD='(1.0,-1.0)';
    'UPI3_TX_DN8':
      PIN_NUMBER='(0,0,0,0,0,0,0,0,0,0,0,0,0,0,0,0,0,0,0,0,0,0,0,0,DP79,0,0,0,0,0,0,0,0,0,0,0,0,0,0,0,0,0)';
      OUTPUT_LOAD='(1.0,-1.0)';
    'UPI3_TX_DN7':
      PIN_NUMBER='(0,0,0,0,0,0,0,0,0,0,0,0,0,0,0,0,0,0,0,0,0,0,0,0,DR82,0,0,0,0,0,0,0,0,0,0,0,0,0,0,0,0,0)';
      OUTPUT_LOAD='(1.0,-1.0)';
    'UPI3_TX_DN6':
      PIN_NUMBER='(0,0,0,0,0,0,0,0,0,0,0,0,0,0,0,0,0,0,0,0,0,0,0,0,DU80,0,0,0,0,0,0,0,0,0,0,0,0,0,0,0,0,0)';
      OUTPUT_LOAD='(1.0,-1.0)';
    'UPI3_TX_DN5':
      PIN_NUMBER='(0,0,0,0,0,0,0,0,0,0,0,0,0,0,0,0,0,0,0,0,0,0,0,0,EK87,0,0,0,0,0,0,0,0,0,0,0,0,0,0,0,0,0)';
      OUTPUT_LOAD='(1.0,-1.0)';
    'UPI3_TX_DN4':
      PIN_NUMBER='(0,0,0,0,0,0,0,0,0,0,0,0,0,0,0,0,0,0,0,0,0,0,0,0,EJ86,0,0,0,0,0,0,0,0,0,0,0,0,0,0,0,0,0)';
      OUTPUT_LOAD='(1.0,-1.0)';
    'UPI3_TX_DN3':
      PIN_NUMBER='(0,0,0,0,0,0,0,0,0,0,0,0,0,0,0,0,0,0,0,0,0,0,0,0,EM87,0,0,0,0,0,0,0,0,0,0,0,0,0,0,0,0,0)';
      OUTPUT_LOAD='(1.0,-1.0)';
    'UPI3_TX_DN2':
      PIN_NUMBER='(0,0,0,0,0,0,0,0,0,0,0,0,0,0,0,0,0,0,0,0,0,0,0,0,EP85,0,0,0,0,0,0,0,0,0,0,0,0,0,0,0,0,0)';
      OUTPUT_LOAD='(1.0,-1.0)';
    'UPI3_TX_DN1':
      PIN_NUMBER='(0,0,0,0,0,0,0,0,0,0,0,0,0,0,0,0,0,0,0,0,0,0,0,0,EL84,0,0,0,0,0,0,0,0,0,0,0,0,0,0,0,0,0)';
      OUTPUT_LOAD='(1.0,-1.0)';
    'UPI3_TX_DN0':
      PIN_NUMBER='(0,0,0,0,0,0,0,0,0,0,0,0,0,0,0,0,0,0,0,0,0,0,0,0,EH85,0,0,0,0,0,0,0,0,0,0,0,0,0,0,0,0,0)';
      OUTPUT_LOAD='(1.0,-1.0)';
    'UPI3_TX_DP23':
      PIN_NUMBER='(0,0,0,0,0,0,0,0,0,0,0,0,0,0,0,0,0,0,0,0,0,0,0,0,CD73,0,0,0,0,0,0,0,0,0,0,0,0,0,0,0,0,0)';
      OUTPUT_LOAD='(1.0,-1.0)';
    'UPI3_TX_DP22':
      PIN_NUMBER='(0,0,0,0,0,0,0,0,0,0,0,0,0,0,0,0,0,0,0,0,0,0,0,0,CW74,0,0,0,0,0,0,0,0,0,0,0,0,0,0,0,0,0)';
      OUTPUT_LOAD='(1.0,-1.0)';
    'UPI3_TX_DP21':
      PIN_NUMBER='(0,0,0,0,0,0,0,0,0,0,0,0,0,0,0,0,0,0,0,0,0,0,0,0,CK75,0,0,0,0,0,0,0,0,0,0,0,0,0,0,0,0,0)';
      OUTPUT_LOAD='(1.0,-1.0)';
    'UPI3_TX_DP20':
      PIN_NUMBER='(0,0,0,0,0,0,0,0,0,0,0,0,0,0,0,0,0,0,0,0,0,0,0,0,CH75,0,0,0,0,0,0,0,0,0,0,0,0,0,0,0,0,0)';
      OUTPUT_LOAD='(1.0,-1.0)';
    'UPI3_TX_DP19':
      PIN_NUMBER='(0,0,0,0,0,0,0,0,0,0,0,0,0,0,0,0,0,0,0,0,0,0,0,0,CF77,0,0,0,0,0,0,0,0,0,0,0,0,0,0,0,0,0)';
      OUTPUT_LOAD='(1.0,-1.0)';
    'UPI3_TX_DP18':
      PIN_NUMBER='(0,0,0,0,0,0,0,0,0,0,0,0,0,0,0,0,0,0,0,0,0,0,0,0,CL76,0,0,0,0,0,0,0,0,0,0,0,0,0,0,0,0,0)';
      OUTPUT_LOAD='(1.0,-1.0)';
    'UPI3_TX_DP17':
      PIN_NUMBER='(0,0,0,0,0,0,0,0,0,0,0,0,0,0,0,0,0,0,0,0,0,0,0,0,CJ78,0,0,0,0,0,0,0,0,0,0,0,0,0,0,0,0,0)';
      OUTPUT_LOAD='(1.0,-1.0)';
    'UPI3_TX_DP16':
      PIN_NUMBER='(0,0,0,0,0,0,0,0,0,0,0,0,0,0,0,0,0,0,0,0,0,0,0,0,CM77,0,0,0,0,0,0,0,0,0,0,0,0,0,0,0,0,0)';
      OUTPUT_LOAD='(1.0,-1.0)';
    'UPI3_TX_DP15':
      PIN_NUMBER='(0,0,0,0,0,0,0,0,0,0,0,0,0,0,0,0,0,0,0,0,0,0,0,0,CU74,0,0,0,0,0,0,0,0,0,0,0,0,0,0,0,0,0)';
      OUTPUT_LOAD='(1.0,-1.0)';
    'UPI3_TX_DP14':
      PIN_NUMBER='(0,0,0,0,0,0,0,0,0,0,0,0,0,0,0,0,0,0,0,0,0,0,0,0,CR76,0,0,0,0,0,0,0,0,0,0,0,0,0,0,0,0,0)';
      OUTPUT_LOAD='(1.0,-1.0)';
    'UPI3_TX_DP13':
      PIN_NUMBER='(0,0,0,0,0,0,0,0,0,0,0,0,0,0,0,0,0,0,0,0,0,0,0,0,CV77,0,0,0,0,0,0,0,0,0,0,0,0,0,0,0,0,0)';
      OUTPUT_LOAD='(1.0,-1.0)';
    'UPI3_TX_DP12':
      PIN_NUMBER='(0,0,0,0,0,0,0,0,0,0,0,0,0,0,0,0,0,0,0,0,0,0,0,0,DA76,0,0,0,0,0,0,0,0,0,0,0,0,0,0,0,0,0)';
      OUTPUT_LOAD='(1.0,-1.0)';
    'UPI3_TX_DP11':
      PIN_NUMBER='(0,0,0,0,0,0,0,0,0,0,0,0,0,0,0,0,0,0,0,0,0,0,0,0,DN80,0,0,0,0,0,0,0,0,0,0,0,0,0,0,0,0,0)';
      OUTPUT_LOAD='(1.0,-1.0)';
    'UPI3_TX_DP10':
      PIN_NUMBER='(0,0,0,0,0,0,0,0,0,0,0,0,0,0,0,0,0,0,0,0,0,0,0,0,DL82,0,0,0,0,0,0,0,0,0,0,0,0,0,0,0,0,0)';
      OUTPUT_LOAD='(1.0,-1.0)';
    'UPI3_TX_DP9':
      PIN_NUMBER='(0,0,0,0,0,0,0,0,0,0,0,0,0,0,0,0,0,0,0,0,0,0,0,0,DP83,0,0,0,0,0,0,0,0,0,0,0,0,0,0,0,0,0)';
      OUTPUT_LOAD='(1.0,-1.0)';
    'UPI3_TX_DP8':
      PIN_NUMBER='(0,0,0,0,0,0,0,0,0,0,0,0,0,0,0,0,0,0,0,0,0,0,0,0,DR80,0,0,0,0,0,0,0,0,0,0,0,0,0,0,0,0,0)';
      OUTPUT_LOAD='(1.0,-1.0)';
    'UPI3_TX_DP7':
      PIN_NUMBER='(0,0,0,0,0,0,0,0,0,0,0,0,0,0,0,0,0,0,0,0,0,0,0,0,DU82,0,0,0,0,0,0,0,0,0,0,0,0,0,0,0,0,0)';
      OUTPUT_LOAD='(1.0,-1.0)';
    'UPI3_TX_DP6':
      PIN_NUMBER='(0,0,0,0,0,0,0,0,0,0,0,0,0,0,0,0,0,0,0,0,0,0,0,0,DT81,0,0,0,0,0,0,0,0,0,0,0,0,0,0,0,0,0)';
      OUTPUT_LOAD='(1.0,-1.0)';
    'UPI3_TX_DP5':
      PIN_NUMBER='(0,0,0,0,0,0,0,0,0,0,0,0,0,0,0,0,0,0,0,0,0,0,0,0,EL88,0,0,0,0,0,0,0,0,0,0,0,0,0,0,0,0,0)';
      OUTPUT_LOAD='(1.0,-1.0)';
    'UPI3_TX_DP4':
      PIN_NUMBER='(0,0,0,0,0,0,0,0,0,0,0,0,0,0,0,0,0,0,0,0,0,0,0,0,EH87,0,0,0,0,0,0,0,0,0,0,0,0,0,0,0,0,0)';
      OUTPUT_LOAD='(1.0,-1.0)';
    'UPI3_TX_DP3':
      PIN_NUMBER='(0,0,0,0,0,0,0,0,0,0,0,0,0,0,0,0,0,0,0,0,0,0,0,0,EP87,0,0,0,0,0,0,0,0,0,0,0,0,0,0,0,0,0)';
      OUTPUT_LOAD='(1.0,-1.0)';
    'UPI3_TX_DP2':
      PIN_NUMBER='(0,0,0,0,0,0,0,0,0,0,0,0,0,0,0,0,0,0,0,0,0,0,0,0,EN86,0,0,0,0,0,0,0,0,0,0,0,0,0,0,0,0,0)';
      OUTPUT_LOAD='(1.0,-1.0)';
    'UPI3_TX_DP1':
      PIN_NUMBER='(0,0,0,0,0,0,0,0,0,0,0,0,0,0,0,0,0,0,0,0,0,0,0,0,EM85,0,0,0,0,0,0,0,0,0,0,0,0,0,0,0,0,0)';
      OUTPUT_LOAD='(1.0,-1.0)';
    'UPI3_TX_DP0':
      PIN_NUMBER='(0,0,0,0,0,0,0,0,0,0,0,0,0,0,0,0,0,0,0,0,0,0,0,0,EK85,0,0,0,0,0,0,0,0,0,0,0,0,0,0,0,0,0)';
      OUTPUT_LOAD='(1.0,-1.0)';
    'VCCIN339':
      PIN_NUMBER='(0,0,0,0,0,0,0,0,0,0,0,0,0,0,0,0,0,0,0,0,0,0,0,0,0,CM89,0,0,0,0,0,0,0,0,0,0,0,0,0,0,0,0)';
      PINUSE='POWER';
      NO_LOAD_CHECK='Both';
      NO_IO_CHECK='Both';
      NO_ASSERT_CHECK='TRUE';
      NO_DIR_CHECK='TRUE';
      ALLOW_CONNECT='TRUE';
    'VCCIN338':
      PIN_NUMBER='(0,0,0,0,0,0,0,0,0,0,0,0,0,0,0,0,0,0,0,0,0,0,0,0,0,CP89,0,0,0,0,0,0,0,0,0,0,0,0,0,0,0,0)';
      PINUSE='POWER';
      NO_LOAD_CHECK='Both';
      NO_IO_CHECK='Both';
      NO_ASSERT_CHECK='TRUE';
      NO_DIR_CHECK='TRUE';
      ALLOW_CONNECT='TRUE';
    'VCCIN337':
      PIN_NUMBER='(0,0,0,0,0,0,0,0,0,0,0,0,0,0,0,0,0,0,0,0,0,0,0,0,0,CN90,0,0,0,0,0,0,0,0,0,0,0,0,0,0,0,0)';
      PINUSE='POWER';
      NO_LOAD_CHECK='Both';
      NO_IO_CHECK='Both';
      NO_ASSERT_CHECK='TRUE';
      NO_DIR_CHECK='TRUE';
      ALLOW_CONNECT='TRUE';
    'VCCIN336':
      PIN_NUMBER='(0,0,0,0,0,0,0,0,0,0,0,0,0,0,0,0,0,0,0,0,0,0,0,0,0,CN88,0,0,0,0,0,0,0,0,0,0,0,0,0,0,0,0)';
      PINUSE='POWER';
      NO_LOAD_CHECK='Both';
      NO_IO_CHECK='Both';
      NO_ASSERT_CHECK='TRUE';
      NO_DIR_CHECK='TRUE';
      ALLOW_CONNECT='TRUE';
    'VCCIN335':
      PIN_NUMBER='(0,0,0,0,0,0,0,0,0,0,0,0,0,0,0,0,0,0,0,0,0,0,0,0,0,CM91,0,0,0,0,0,0,0,0,0,0,0,0,0,0,0,0)';
      PINUSE='POWER';
      NO_LOAD_CHECK='Both';
      NO_IO_CHECK='Both';
      NO_ASSERT_CHECK='TRUE';
      NO_DIR_CHECK='TRUE';
      ALLOW_CONNECT='TRUE';
    'VCCIN334':
      PIN_NUMBER='(0,0,0,0,0,0,0,0,0,0,0,0,0,0,0,0,0,0,0,0,0,0,0,0,0,CM87,0,0,0,0,0,0,0,0,0,0,0,0,0,0,0,0)';
      PINUSE='POWER';
      NO_LOAD_CHECK='Both';
      NO_IO_CHECK='Both';
      NO_ASSERT_CHECK='TRUE';
      NO_DIR_CHECK='TRUE';
      ALLOW_CONNECT='TRUE';
    'VCCIN333':
      PIN_NUMBER='(0,0,0,0,0,0,0,0,0,0,0,0,0,0,0,0,0,0,0,0,0,0,0,0,0,CL90,0,0,0,0,0,0,0,0,0,0,0,0,0,0,0,0)';
      PINUSE='POWER';
      NO_LOAD_CHECK='Both';
      NO_IO_CHECK='Both';
      NO_ASSERT_CHECK='TRUE';
      NO_DIR_CHECK='TRUE';
      ALLOW_CONNECT='TRUE';
    'VCCIN332':
      PIN_NUMBER='(0,0,0,0,0,0,0,0,0,0,0,0,0,0,0,0,0,0,0,0,0,0,0,0,0,CL88,0,0,0,0,0,0,0,0,0,0,0,0,0,0,0,0)';
      PINUSE='POWER';
      NO_LOAD_CHECK='Both';
      NO_IO_CHECK='Both';
      NO_ASSERT_CHECK='TRUE';
      NO_DIR_CHECK='TRUE';
      ALLOW_CONNECT='TRUE';
    'VCCIN331':
      PIN_NUMBER='(0,0,0,0,0,0,0,0,0,0,0,0,0,0,0,0,0,0,0,0,0,0,0,0,0,CL86,0,0,0,0,0,0,0,0,0,0,0,0,0,0,0,0)';
      PINUSE='POWER';
      NO_LOAD_CHECK='Both';
      NO_IO_CHECK='Both';
      NO_ASSERT_CHECK='TRUE';
      NO_DIR_CHECK='TRUE';
      ALLOW_CONNECT='TRUE';
    'VCCIN330':
      PIN_NUMBER='(0,0,0,0,0,0,0,0,0,0,0,0,0,0,0,0,0,0,0,0,0,0,0,0,0,CL84,0,0,0,0,0,0,0,0,0,0,0,0,0,0,0,0)';
      PINUSE='POWER';
      NO_LOAD_CHECK='Both';
      NO_IO_CHECK='Both';
      NO_ASSERT_CHECK='TRUE';
      NO_DIR_CHECK='TRUE';
      ALLOW_CONNECT='TRUE';
    'VCCIN329':
      PIN_NUMBER='(0,0,0,0,0,0,0,0,0,0,0,0,0,0,0,0,0,0,0,0,0,0,0,0,0,CK91,0,0,0,0,0,0,0,0,0,0,0,0,0,0,0,0)';
      PINUSE='POWER';
      NO_LOAD_CHECK='Both';
      NO_IO_CHECK='Both';
      NO_ASSERT_CHECK='TRUE';
      NO_DIR_CHECK='TRUE';
      ALLOW_CONNECT='TRUE';
    'VCCIN328':
      PIN_NUMBER='(0,0,0,0,0,0,0,0,0,0,0,0,0,0,0,0,0,0,0,0,0,0,0,0,0,CK89,0,0,0,0,0,0,0,0,0,0,0,0,0,0,0,0)';
      PINUSE='POWER';
      NO_LOAD_CHECK='Both';
      NO_IO_CHECK='Both';
      NO_ASSERT_CHECK='TRUE';
      NO_DIR_CHECK='TRUE';
      ALLOW_CONNECT='TRUE';
    'VCCIN327':
      PIN_NUMBER='(0,0,0,0,0,0,0,0,0,0,0,0,0,0,0,0,0,0,0,0,0,0,0,0,0,CK87,0,0,0,0,0,0,0,0,0,0,0,0,0,0,0,0)';
      PINUSE='POWER';
      NO_LOAD_CHECK='Both';
      NO_IO_CHECK='Both';
      NO_ASSERT_CHECK='TRUE';
      NO_DIR_CHECK='TRUE';
      ALLOW_CONNECT='TRUE';
    'VCCIN326':
      PIN_NUMBER='(0,0,0,0,0,0,0,0,0,0,0,0,0,0,0,0,0,0,0,0,0,0,0,0,0,CK85,0,0,0,0,0,0,0,0,0,0,0,0,0,0,0,0)';
      PINUSE='POWER';
      NO_LOAD_CHECK='Both';
      NO_IO_CHECK='Both';
      NO_ASSERT_CHECK='TRUE';
      NO_DIR_CHECK='TRUE';
      ALLOW_CONNECT='TRUE';
    'VCCIN325':
      PIN_NUMBER='(0,0,0,0,0,0,0,0,0,0,0,0,0,0,0,0,0,0,0,0,0,0,0,0,0,CK83,0,0,0,0,0,0,0,0,0,0,0,0,0,0,0,0)';
      PINUSE='POWER';
      NO_LOAD_CHECK='Both';
      NO_IO_CHECK='Both';
      NO_ASSERT_CHECK='TRUE';
      NO_DIR_CHECK='TRUE';
      ALLOW_CONNECT='TRUE';
    'VCCIN324':
      PIN_NUMBER='(0,0,0,0,0,0,0,0,0,0,0,0,0,0,0,0,0,0,0,0,0,0,0,0,0,CJ90,0,0,0,0,0,0,0,0,0,0,0,0,0,0,0,0)';
      PINUSE='POWER';
      NO_LOAD_CHECK='Both';
      NO_IO_CHECK='Both';
      NO_ASSERT_CHECK='TRUE';
      NO_DIR_CHECK='TRUE';
      ALLOW_CONNECT='TRUE';
    'VCCIN323':
      PIN_NUMBER='(0,0,0,0,0,0,0,0,0,0,0,0,0,0,0,0,0,0,0,0,0,0,0,0,0,CJ88,0,0,0,0,0,0,0,0,0,0,0,0,0,0,0,0)';
      PINUSE='POWER';
      NO_LOAD_CHECK='Both';
      NO_IO_CHECK='Both';
      NO_ASSERT_CHECK='TRUE';
      NO_DIR_CHECK='TRUE';
      ALLOW_CONNECT='TRUE';
    'VCCIN322':
      PIN_NUMBER='(0,0,0,0,0,0,0,0,0,0,0,0,0,0,0,0,0,0,0,0,0,0,0,0,0,CJ86,0,0,0,0,0,0,0,0,0,0,0,0,0,0,0,0)';
      PINUSE='POWER';
      NO_LOAD_CHECK='Both';
      NO_IO_CHECK='Both';
      NO_ASSERT_CHECK='TRUE';
      NO_DIR_CHECK='TRUE';
      ALLOW_CONNECT='TRUE';
    'VCCIN321':
      PIN_NUMBER='(0,0,0,0,0,0,0,0,0,0,0,0,0,0,0,0,0,0,0,0,0,0,0,0,0,CJ84,0,0,0,0,0,0,0,0,0,0,0,0,0,0,0,0)';
      PINUSE='POWER';
      NO_LOAD_CHECK='Both';
      NO_IO_CHECK='Both';
      NO_ASSERT_CHECK='TRUE';
      NO_DIR_CHECK='TRUE';
      ALLOW_CONNECT='TRUE';
    'VCCIN320':
      PIN_NUMBER='(0,0,0,0,0,0,0,0,0,0,0,0,0,0,0,0,0,0,0,0,0,0,0,0,0,CJ82,0,0,0,0,0,0,0,0,0,0,0,0,0,0,0,0)';
      PINUSE='POWER';
      NO_LOAD_CHECK='Both';
      NO_IO_CHECK='Both';
      NO_ASSERT_CHECK='TRUE';
      NO_DIR_CHECK='TRUE';
      ALLOW_CONNECT='TRUE';
    'VCCIN319':
      PIN_NUMBER='(0,0,0,0,0,0,0,0,0,0,0,0,0,0,0,0,0,0,0,0,0,0,0,0,0,CH91,0,0,0,0,0,0,0,0,0,0,0,0,0,0,0,0)';
      PINUSE='POWER';
      NO_LOAD_CHECK='Both';
      NO_IO_CHECK='Both';
      NO_ASSERT_CHECK='TRUE';
      NO_DIR_CHECK='TRUE';
      ALLOW_CONNECT='TRUE';
    'VCCIN318':
      PIN_NUMBER='(0,0,0,0,0,0,0,0,0,0,0,0,0,0,0,0,0,0,0,0,0,0,0,0,0,CH81,0,0,0,0,0,0,0,0,0,0,0,0,0,0,0,0)';
      PINUSE='POWER';
      NO_LOAD_CHECK='Both';
      NO_IO_CHECK='Both';
      NO_ASSERT_CHECK='TRUE';
      NO_DIR_CHECK='TRUE';
      ALLOW_CONNECT='TRUE';
    'VCCIN317':
      PIN_NUMBER='(0,0,0,0,0,0,0,0,0,0,0,0,0,0,0,0,0,0,0,0,0,0,0,0,0,CG90,0,0,0,0,0,0,0,0,0,0,0,0,0,0,0,0)';
      PINUSE='POWER';
      NO_LOAD_CHECK='Both';
      NO_IO_CHECK='Both';
      NO_ASSERT_CHECK='TRUE';
      NO_DIR_CHECK='TRUE';
      ALLOW_CONNECT='TRUE';
    'VCCIN316':
      PIN_NUMBER='(0,0,0,0,0,0,0,0,0,0,0,0,0,0,0,0,0,0,0,0,0,0,0,0,0,CG88,0,0,0,0,0,0,0,0,0,0,0,0,0,0,0,0)';
      PINUSE='POWER';
      NO_LOAD_CHECK='Both';
      NO_IO_CHECK='Both';
      NO_ASSERT_CHECK='TRUE';
      NO_DIR_CHECK='TRUE';
      ALLOW_CONNECT='TRUE';
    'VCCIN315':
      PIN_NUMBER='(0,0,0,0,0,0,0,0,0,0,0,0,0,0,0,0,0,0,0,0,0,0,0,0,0,CG86,0,0,0,0,0,0,0,0,0,0,0,0,0,0,0,0)';
      PINUSE='POWER';
      NO_LOAD_CHECK='Both';
      NO_IO_CHECK='Both';
      NO_ASSERT_CHECK='TRUE';
      NO_DIR_CHECK='TRUE';
      ALLOW_CONNECT='TRUE';
    'VCCIN314':
      PIN_NUMBER='(0,0,0,0,0,0,0,0,0,0,0,0,0,0,0,0,0,0,0,0,0,0,0,0,0,CG84,0,0,0,0,0,0,0,0,0,0,0,0,0,0,0,0)';
      PINUSE='POWER';
      NO_LOAD_CHECK='Both';
      NO_IO_CHECK='Both';
      NO_ASSERT_CHECK='TRUE';
      NO_DIR_CHECK='TRUE';
      ALLOW_CONNECT='TRUE';
    'VCCIN313':
      PIN_NUMBER='(0,0,0,0,0,0,0,0,0,0,0,0,0,0,0,0,0,0,0,0,0,0,0,0,0,CG82,0,0,0,0,0,0,0,0,0,0,0,0,0,0,0,0)';
      PINUSE='POWER';
      NO_LOAD_CHECK='Both';
      NO_IO_CHECK='Both';
      NO_ASSERT_CHECK='TRUE';
      NO_DIR_CHECK='TRUE';
      ALLOW_CONNECT='TRUE';
    'VCCIN312':
      PIN_NUMBER='(0,0,0,0,0,0,0,0,0,0,0,0,0,0,0,0,0,0,0,0,0,0,0,0,0,CG80,0,0,0,0,0,0,0,0,0,0,0,0,0,0,0,0)';
      PINUSE='POWER';
      NO_LOAD_CHECK='Both';
      NO_IO_CHECK='Both';
      NO_ASSERT_CHECK='TRUE';
      NO_DIR_CHECK='TRUE';
      ALLOW_CONNECT='TRUE';
    'VCCIN311':
      PIN_NUMBER='(0,0,0,0,0,0,0,0,0,0,0,0,0,0,0,0,0,0,0,0,0,0,0,0,0,CF91,0,0,0,0,0,0,0,0,0,0,0,0,0,0,0,0)';
      PINUSE='POWER';
      NO_LOAD_CHECK='Both';
      NO_IO_CHECK='Both';
      NO_ASSERT_CHECK='TRUE';
      NO_DIR_CHECK='TRUE';
      ALLOW_CONNECT='TRUE';
    'VCCIN310':
      PIN_NUMBER='(0,0,0,0,0,0,0,0,0,0,0,0,0,0,0,0,0,0,0,0,0,0,0,0,0,CF89,0,0,0,0,0,0,0,0,0,0,0,0,0,0,0,0)';
      PINUSE='POWER';
      NO_LOAD_CHECK='Both';
      NO_IO_CHECK='Both';
      NO_ASSERT_CHECK='TRUE';
      NO_DIR_CHECK='TRUE';
      ALLOW_CONNECT='TRUE';
    'VCCIN309':
      PIN_NUMBER='(0,0,0,0,0,0,0,0,0,0,0,0,0,0,0,0,0,0,0,0,0,0,0,0,0,CF87,0,0,0,0,0,0,0,0,0,0,0,0,0,0,0,0)';
      PINUSE='POWER';
      NO_LOAD_CHECK='Both';
      NO_IO_CHECK='Both';
      NO_ASSERT_CHECK='TRUE';
      NO_DIR_CHECK='TRUE';
      ALLOW_CONNECT='TRUE';
    'VCCIN308':
      PIN_NUMBER='(0,0,0,0,0,0,0,0,0,0,0,0,0,0,0,0,0,0,0,0,0,0,0,0,0,CF85,0,0,0,0,0,0,0,0,0,0,0,0,0,0,0,0)';
      PINUSE='POWER';
      NO_LOAD_CHECK='Both';
      NO_IO_CHECK='Both';
      NO_ASSERT_CHECK='TRUE';
      NO_DIR_CHECK='TRUE';
      ALLOW_CONNECT='TRUE';
    'VCCIN307':
      PIN_NUMBER='(0,0,0,0,0,0,0,0,0,0,0,0,0,0,0,0,0,0,0,0,0,0,0,0,0,CF83,0,0,0,0,0,0,0,0,0,0,0,0,0,0,0,0)';
      PINUSE='POWER';
      NO_LOAD_CHECK='Both';
      NO_IO_CHECK='Both';
      NO_ASSERT_CHECK='TRUE';
      NO_DIR_CHECK='TRUE';
      ALLOW_CONNECT='TRUE';
    'VCCIN306':
      PIN_NUMBER='(0,0,0,0,0,0,0,0,0,0,0,0,0,0,0,0,0,0,0,0,0,0,0,0,0,CF81,0,0,0,0,0,0,0,0,0,0,0,0,0,0,0,0)';
      PINUSE='POWER';
      NO_LOAD_CHECK='Both';
      NO_IO_CHECK='Both';
      NO_ASSERT_CHECK='TRUE';
      NO_DIR_CHECK='TRUE';
      ALLOW_CONNECT='TRUE';
    'VCCIN305':
      PIN_NUMBER='(0,0,0,0,0,0,0,0,0,0,0,0,0,0,0,0,0,0,0,0,0,0,0,0,0,CF79,0,0,0,0,0,0,0,0,0,0,0,0,0,0,0,0)';
      PINUSE='POWER';
      NO_LOAD_CHECK='Both';
      NO_IO_CHECK='Both';
      NO_ASSERT_CHECK='TRUE';
      NO_DIR_CHECK='TRUE';
      ALLOW_CONNECT='TRUE';
    'VCCIN304':
      PIN_NUMBER='(0,0,0,0,0,0,0,0,0,0,0,0,0,0,0,0,0,0,0,0,0,0,0,0,0,CE90,0,0,0,0,0,0,0,0,0,0,0,0,0,0,0,0)';
      PINUSE='POWER';
      NO_LOAD_CHECK='Both';
      NO_IO_CHECK='Both';
      NO_ASSERT_CHECK='TRUE';
      NO_DIR_CHECK='TRUE';
      ALLOW_CONNECT='TRUE';
    'VCCIN303':
      PIN_NUMBER='(0,0,0,0,0,0,0,0,0,0,0,0,0,0,0,0,0,0,0,0,0,0,0,0,0,CE88,0,0,0,0,0,0,0,0,0,0,0,0,0,0,0,0)';
      PINUSE='POWER';
      NO_LOAD_CHECK='Both';
      NO_IO_CHECK='Both';
      NO_ASSERT_CHECK='TRUE';
      NO_DIR_CHECK='TRUE';
      ALLOW_CONNECT='TRUE';
    'VCCIN302':
      PIN_NUMBER='(0,0,0,0,0,0,0,0,0,0,0,0,0,0,0,0,0,0,0,0,0,0,0,0,0,CE86,0,0,0,0,0,0,0,0,0,0,0,0,0,0,0,0)';
      PINUSE='POWER';
      NO_LOAD_CHECK='Both';
      NO_IO_CHECK='Both';
      NO_ASSERT_CHECK='TRUE';
      NO_DIR_CHECK='TRUE';
      ALLOW_CONNECT='TRUE';
    'VCCIN301':
      PIN_NUMBER='(0,0,0,0,0,0,0,0,0,0,0,0,0,0,0,0,0,0,0,0,0,0,0,0,0,CE84,0,0,0,0,0,0,0,0,0,0,0,0,0,0,0,0)';
      PINUSE='POWER';
      NO_LOAD_CHECK='Both';
      NO_IO_CHECK='Both';
      NO_ASSERT_CHECK='TRUE';
      NO_DIR_CHECK='TRUE';
      ALLOW_CONNECT='TRUE';
    'VCCIN300':
      PIN_NUMBER='(0,0,0,0,0,0,0,0,0,0,0,0,0,0,0,0,0,0,0,0,0,0,0,0,0,CE82,0,0,0,0,0,0,0,0,0,0,0,0,0,0,0,0)';
      PINUSE='POWER';
      NO_LOAD_CHECK='Both';
      NO_IO_CHECK='Both';
      NO_ASSERT_CHECK='TRUE';
      NO_DIR_CHECK='TRUE';
      ALLOW_CONNECT='TRUE';
    'VCCIN299':
      PIN_NUMBER='(0,0,0,0,0,0,0,0,0,0,0,0,0,0,0,0,0,0,0,0,0,0,0,0,0,CE80,0,0,0,0,0,0,0,0,0,0,0,0,0,0,0,0)';
      PINUSE='POWER';
      NO_LOAD_CHECK='Both';
      NO_IO_CHECK='Both';
      NO_ASSERT_CHECK='TRUE';
      NO_DIR_CHECK='TRUE';
      ALLOW_CONNECT='TRUE';
    'VCCIN298':
      PIN_NUMBER='(0,0,0,0,0,0,0,0,0,0,0,0,0,0,0,0,0,0,0,0,0,0,0,0,0,CD89,0,0,0,0,0,0,0,0,0,0,0,0,0,0,0,0)';
      PINUSE='POWER';
      NO_LOAD_CHECK='Both';
      NO_IO_CHECK='Both';
      NO_ASSERT_CHECK='TRUE';
      NO_DIR_CHECK='TRUE';
      ALLOW_CONNECT='TRUE';
    'VCCIN297':
      PIN_NUMBER='(0,0,0,0,0,0,0,0,0,0,0,0,0,0,0,0,0,0,0,0,0,0,0,0,0,CD87,0,0,0,0,0,0,0,0,0,0,0,0,0,0,0,0)';
      PINUSE='POWER';
      NO_LOAD_CHECK='Both';
      NO_IO_CHECK='Both';
      NO_ASSERT_CHECK='TRUE';
      NO_DIR_CHECK='TRUE';
      ALLOW_CONNECT='TRUE';
    'VCCIN296':
      PIN_NUMBER='(0,0,0,0,0,0,0,0,0,0,0,0,0,0,0,0,0,0,0,0,0,0,0,0,0,CD85,0,0,0,0,0,0,0,0,0,0,0,0,0,0,0,0)';
      PINUSE='POWER';
      NO_LOAD_CHECK='Both';
      NO_IO_CHECK='Both';
      NO_ASSERT_CHECK='TRUE';
      NO_DIR_CHECK='TRUE';
      ALLOW_CONNECT='TRUE';
    'VCCIN295':
      PIN_NUMBER='(0,0,0,0,0,0,0,0,0,0,0,0,0,0,0,0,0,0,0,0,0,0,0,0,0,CD83,0,0,0,0,0,0,0,0,0,0,0,0,0,0,0,0)';
      PINUSE='POWER';
      NO_LOAD_CHECK='Both';
      NO_IO_CHECK='Both';
      NO_ASSERT_CHECK='TRUE';
      NO_DIR_CHECK='TRUE';
      ALLOW_CONNECT='TRUE';
    'VCCIN294':
      PIN_NUMBER='(0,0,0,0,0,0,0,0,0,0,0,0,0,0,0,0,0,0,0,0,0,0,0,0,0,CD81,0,0,0,0,0,0,0,0,0,0,0,0,0,0,0,0)';
      PINUSE='POWER';
      NO_LOAD_CHECK='Both';
      NO_IO_CHECK='Both';
      NO_ASSERT_CHECK='TRUE';
      NO_DIR_CHECK='TRUE';
      ALLOW_CONNECT='TRUE';
    'VCCIN293':
      PIN_NUMBER='(0,0,0,0,0,0,0,0,0,0,0,0,0,0,0,0,0,0,0,0,0,0,0,0,0,CD79,0,0,0,0,0,0,0,0,0,0,0,0,0,0,0,0)';
      PINUSE='POWER';
      NO_LOAD_CHECK='Both';
      NO_IO_CHECK='Both';
      NO_ASSERT_CHECK='TRUE';
      NO_DIR_CHECK='TRUE';
      ALLOW_CONNECT='TRUE';
    'VCCIN292':
      PIN_NUMBER='(0,0,0,0,0,0,0,0,0,0,0,0,0,0,0,0,0,0,0,0,0,0,0,0,0,CD59,0,0,0,0,0,0,0,0,0,0,0,0,0,0,0,0)';
      PINUSE='POWER';
      NO_LOAD_CHECK='Both';
      NO_IO_CHECK='Both';
      NO_ASSERT_CHECK='TRUE';
      NO_DIR_CHECK='TRUE';
      ALLOW_CONNECT='TRUE';
    'VCCIN291':
      PIN_NUMBER='(0,0,0,0,0,0,0,0,0,0,0,0,0,0,0,0,0,0,0,0,0,0,0,0,0,CD57,0,0,0,0,0,0,0,0,0,0,0,0,0,0,0,0)';
      PINUSE='POWER';
      NO_LOAD_CHECK='Both';
      NO_IO_CHECK='Both';
      NO_ASSERT_CHECK='TRUE';
      NO_DIR_CHECK='TRUE';
      ALLOW_CONNECT='TRUE';
    'VCCIN290':
      PIN_NUMBER='(0,0,0,0,0,0,0,0,0,0,0,0,0,0,0,0,0,0,0,0,0,0,0,0,0,CD55,0,0,0,0,0,0,0,0,0,0,0,0,0,0,0,0)';
      PINUSE='POWER';
      NO_LOAD_CHECK='Both';
      NO_IO_CHECK='Both';
      NO_ASSERT_CHECK='TRUE';
      NO_DIR_CHECK='TRUE';
      ALLOW_CONNECT='TRUE';
    'VCCIN289':
      PIN_NUMBER='(0,0,0,0,0,0,0,0,0,0,0,0,0,0,0,0,0,0,0,0,0,0,0,0,0,CD53,0,0,0,0,0,0,0,0,0,0,0,0,0,0,0,0)';
      PINUSE='POWER';
      NO_LOAD_CHECK='Both';
      NO_IO_CHECK='Both';
      NO_ASSERT_CHECK='TRUE';
      NO_DIR_CHECK='TRUE';
      ALLOW_CONNECT='TRUE';
    'VCCIN288':
      PIN_NUMBER='(0,0,0,0,0,0,0,0,0,0,0,0,0,0,0,0,0,0,0,0,0,0,0,0,0,CD51,0,0,0,0,0,0,0,0,0,0,0,0,0,0,0,0)';
      PINUSE='POWER';
      NO_LOAD_CHECK='Both';
      NO_IO_CHECK='Both';
      NO_ASSERT_CHECK='TRUE';
      NO_DIR_CHECK='TRUE';
      ALLOW_CONNECT='TRUE';
    'VCCIN287':
      PIN_NUMBER='(0,0,0,0,0,0,0,0,0,0,0,0,0,0,0,0,0,0,0,0,0,0,0,0,0,CD49,0,0,0,0,0,0,0,0,0,0,0,0,0,0,0,0)';
      PINUSE='POWER';
      NO_LOAD_CHECK='Both';
      NO_IO_CHECK='Both';
      NO_ASSERT_CHECK='TRUE';
      NO_DIR_CHECK='TRUE';
      ALLOW_CONNECT='TRUE';
    'VCCIN286':
      PIN_NUMBER='(0,0,0,0,0,0,0,0,0,0,0,0,0,0,0,0,0,0,0,0,0,0,0,0,0,CD47,0,0,0,0,0,0,0,0,0,0,0,0,0,0,0,0)';
      PINUSE='POWER';
      NO_LOAD_CHECK='Both';
      NO_IO_CHECK='Both';
      NO_ASSERT_CHECK='TRUE';
      NO_DIR_CHECK='TRUE';
      ALLOW_CONNECT='TRUE';
    'VCCIN285':
      PIN_NUMBER='(0,0,0,0,0,0,0,0,0,0,0,0,0,0,0,0,0,0,0,0,0,0,0,0,0,CD44,0,0,0,0,0,0,0,0,0,0,0,0,0,0,0,0)';
      PINUSE='POWER';
      NO_LOAD_CHECK='Both';
      NO_IO_CHECK='Both';
      NO_ASSERT_CHECK='TRUE';
      NO_DIR_CHECK='TRUE';
      ALLOW_CONNECT='TRUE';
    'VCCIN284':
      PIN_NUMBER='(0,0,0,0,0,0,0,0,0,0,0,0,0,0,0,0,0,0,0,0,0,0,0,0,0,CD42,0,0,0,0,0,0,0,0,0,0,0,0,0,0,0,0)';
      PINUSE='POWER';
      NO_LOAD_CHECK='Both';
      NO_IO_CHECK='Both';
      NO_ASSERT_CHECK='TRUE';
      NO_DIR_CHECK='TRUE';
      ALLOW_CONNECT='TRUE';
    'VCCIN283':
      PIN_NUMBER='(0,0,0,0,0,0,0,0,0,0,0,0,0,0,0,0,0,0,0,0,0,0,0,0,0,CD40,0,0,0,0,0,0,0,0,0,0,0,0,0,0,0,0)';
      PINUSE='POWER';
      NO_LOAD_CHECK='Both';
      NO_IO_CHECK='Both';
      NO_ASSERT_CHECK='TRUE';
      NO_DIR_CHECK='TRUE';
      ALLOW_CONNECT='TRUE';
    'VCCIN282':
      PIN_NUMBER='(0,0,0,0,0,0,0,0,0,0,0,0,0,0,0,0,0,0,0,0,0,0,0,0,0,CD38,0,0,0,0,0,0,0,0,0,0,0,0,0,0,0,0)';
      PINUSE='POWER';
      NO_LOAD_CHECK='Both';
      NO_IO_CHECK='Both';
      NO_ASSERT_CHECK='TRUE';
      NO_DIR_CHECK='TRUE';
      ALLOW_CONNECT='TRUE';
    'VCCIN281':
      PIN_NUMBER='(0,0,0,0,0,0,0,0,0,0,0,0,0,0,0,0,0,0,0,0,0,0,0,0,0,CD36,0,0,0,0,0,0,0,0,0,0,0,0,0,0,0,0)';
      PINUSE='POWER';
      NO_LOAD_CHECK='Both';
      NO_IO_CHECK='Both';
      NO_ASSERT_CHECK='TRUE';
      NO_DIR_CHECK='TRUE';
      ALLOW_CONNECT='TRUE';
    'VCCIN280':
      PIN_NUMBER='(0,0,0,0,0,0,0,0,0,0,0,0,0,0,0,0,0,0,0,0,0,0,0,0,0,CD34,0,0,0,0,0,0,0,0,0,0,0,0,0,0,0,0)';
      PINUSE='POWER';
      NO_LOAD_CHECK='Both';
      NO_IO_CHECK='Both';
      NO_ASSERT_CHECK='TRUE';
      NO_DIR_CHECK='TRUE';
      ALLOW_CONNECT='TRUE';
    'VCCIN279':
      PIN_NUMBER='(0,0,0,0,0,0,0,0,0,0,0,0,0,0,0,0,0,0,0,0,0,0,0,0,0,CD32,0,0,0,0,0,0,0,0,0,0,0,0,0,0,0,0)';
      PINUSE='POWER';
      NO_LOAD_CHECK='Both';
      NO_IO_CHECK='Both';
      NO_ASSERT_CHECK='TRUE';
      NO_DIR_CHECK='TRUE';
      ALLOW_CONNECT='TRUE';
    'VCCIN278':
      PIN_NUMBER='(0,0,0,0,0,0,0,0,0,0,0,0,0,0,0,0,0,0,0,0,0,0,0,0,0,CC90,0,0,0,0,0,0,0,0,0,0,0,0,0,0,0,0)';
      PINUSE='POWER';
      NO_LOAD_CHECK='Both';
      NO_IO_CHECK='Both';
      NO_ASSERT_CHECK='TRUE';
      NO_DIR_CHECK='TRUE';
      ALLOW_CONNECT='TRUE';
    'VCCIN277':
      PIN_NUMBER='(0,0,0,0,0,0,0,0,0,0,0,0,0,0,0,0,0,0,0,0,0,0,0,0,0,CC88,0,0,0,0,0,0,0,0,0,0,0,0,0,0,0,0)';
      PINUSE='POWER';
      NO_LOAD_CHECK='Both';
      NO_IO_CHECK='Both';
      NO_ASSERT_CHECK='TRUE';
      NO_DIR_CHECK='TRUE';
      ALLOW_CONNECT='TRUE';
    'VCCIN276':
      PIN_NUMBER='(0,0,0,0,0,0,0,0,0,0,0,0,0,0,0,0,0,0,0,0,0,0,0,0,0,CC86,0,0,0,0,0,0,0,0,0,0,0,0,0,0,0,0)';
      PINUSE='POWER';
      NO_LOAD_CHECK='Both';
      NO_IO_CHECK='Both';
      NO_ASSERT_CHECK='TRUE';
      NO_DIR_CHECK='TRUE';
      ALLOW_CONNECT='TRUE';
    'VCCIN275':
      PIN_NUMBER='(0,0,0,0,0,0,0,0,0,0,0,0,0,0,0,0,0,0,0,0,0,0,0,0,0,CC84,0,0,0,0,0,0,0,0,0,0,0,0,0,0,0,0)';
      PINUSE='POWER';
      NO_LOAD_CHECK='Both';
      NO_IO_CHECK='Both';
      NO_ASSERT_CHECK='TRUE';
      NO_DIR_CHECK='TRUE';
      ALLOW_CONNECT='TRUE';
    'VCCIN274':
      PIN_NUMBER='(0,0,0,0,0,0,0,0,0,0,0,0,0,0,0,0,0,0,0,0,0,0,0,0,0,CC82,0,0,0,0,0,0,0,0,0,0,0,0,0,0,0,0)';
      PINUSE='POWER';
      NO_LOAD_CHECK='Both';
      NO_IO_CHECK='Both';
      NO_ASSERT_CHECK='TRUE';
      NO_DIR_CHECK='TRUE';
      ALLOW_CONNECT='TRUE';
    'VCCIN273':
      PIN_NUMBER='(0,0,0,0,0,0,0,0,0,0,0,0,0,0,0,0,0,0,0,0,0,0,0,0,0,CC80,0,0,0,0,0,0,0,0,0,0,0,0,0,0,0,0)';
      PINUSE='POWER';
      NO_LOAD_CHECK='Both';
      NO_IO_CHECK='Both';
      NO_ASSERT_CHECK='TRUE';
      NO_DIR_CHECK='TRUE';
      ALLOW_CONNECT='TRUE';
    'VCCIN272':
      PIN_NUMBER='(0,0,0,0,0,0,0,0,0,0,0,0,0,0,0,0,0,0,0,0,0,0,0,0,0,CC78,0,0,0,0,0,0,0,0,0,0,0,0,0,0,0,0)';
      PINUSE='POWER';
      NO_LOAD_CHECK='Both';
      NO_IO_CHECK='Both';
      NO_ASSERT_CHECK='TRUE';
      NO_DIR_CHECK='TRUE';
      ALLOW_CONNECT='TRUE';
    'VCCIN271':
      PIN_NUMBER='(0,0,0,0,0,0,0,0,0,0,0,0,0,0,0,0,0,0,0,0,0,0,0,0,0,CC76,0,0,0,0,0,0,0,0,0,0,0,0,0,0,0,0)';
      PINUSE='POWER';
      NO_LOAD_CHECK='Both';
      NO_IO_CHECK='Both';
      NO_ASSERT_CHECK='TRUE';
      NO_DIR_CHECK='TRUE';
      ALLOW_CONNECT='TRUE';
    'VCCIN270':
      PIN_NUMBER='(0,0,0,0,0,0,0,0,0,0,0,0,0,0,0,0,0,0,0,0,0,0,0,0,0,CC60,0,0,0,0,0,0,0,0,0,0,0,0,0,0,0,0)';
      PINUSE='POWER';
      NO_LOAD_CHECK='Both';
      NO_IO_CHECK='Both';
      NO_ASSERT_CHECK='TRUE';
      NO_DIR_CHECK='TRUE';
      ALLOW_CONNECT='TRUE';
    'VCCIN269':
      PIN_NUMBER='(0,0,0,0,0,0,0,0,0,0,0,0,0,0,0,0,0,0,0,0,0,0,0,0,0,CC58,0,0,0,0,0,0,0,0,0,0,0,0,0,0,0,0)';
      PINUSE='POWER';
      NO_LOAD_CHECK='Both';
      NO_IO_CHECK='Both';
      NO_ASSERT_CHECK='TRUE';
      NO_DIR_CHECK='TRUE';
      ALLOW_CONNECT='TRUE';
    'VCCIN268':
      PIN_NUMBER='(0,0,0,0,0,0,0,0,0,0,0,0,0,0,0,0,0,0,0,0,0,0,0,0,0,CC56,0,0,0,0,0,0,0,0,0,0,0,0,0,0,0,0)';
      PINUSE='POWER';
      NO_LOAD_CHECK='Both';
      NO_IO_CHECK='Both';
      NO_ASSERT_CHECK='TRUE';
      NO_DIR_CHECK='TRUE';
      ALLOW_CONNECT='TRUE';
    'VCCIN267':
      PIN_NUMBER='(0,0,0,0,0,0,0,0,0,0,0,0,0,0,0,0,0,0,0,0,0,0,0,0,0,CC54,0,0,0,0,0,0,0,0,0,0,0,0,0,0,0,0)';
      PINUSE='POWER';
      NO_LOAD_CHECK='Both';
      NO_IO_CHECK='Both';
      NO_ASSERT_CHECK='TRUE';
      NO_DIR_CHECK='TRUE';
      ALLOW_CONNECT='TRUE';
    'VCCIN266':
      PIN_NUMBER='(0,0,0,0,0,0,0,0,0,0,0,0,0,0,0,0,0,0,0,0,0,0,0,0,0,CC52,0,0,0,0,0,0,0,0,0,0,0,0,0,0,0,0)';
      PINUSE='POWER';
      NO_LOAD_CHECK='Both';
      NO_IO_CHECK='Both';
      NO_ASSERT_CHECK='TRUE';
      NO_DIR_CHECK='TRUE';
      ALLOW_CONNECT='TRUE';
    'VCCIN265':
      PIN_NUMBER='(0,0,0,0,0,0,0,0,0,0,0,0,0,0,0,0,0,0,0,0,0,0,0,0,0,CC50,0,0,0,0,0,0,0,0,0,0,0,0,0,0,0,0)';
      PINUSE='POWER';
      NO_LOAD_CHECK='Both';
      NO_IO_CHECK='Both';
      NO_ASSERT_CHECK='TRUE';
      NO_DIR_CHECK='TRUE';
      ALLOW_CONNECT='TRUE';
    'VCCIN264':
      PIN_NUMBER='(0,0,0,0,0,0,0,0,0,0,0,0,0,0,0,0,0,0,0,0,0,0,0,0,0,CC48,0,0,0,0,0,0,0,0,0,0,0,0,0,0,0,0)';
      PINUSE='POWER';
      NO_LOAD_CHECK='Both';
      NO_IO_CHECK='Both';
      NO_ASSERT_CHECK='TRUE';
      NO_DIR_CHECK='TRUE';
      ALLOW_CONNECT='TRUE';
    'VCCIN263':
      PIN_NUMBER='(0,0,0,0,0,0,0,0,0,0,0,0,0,0,0,0,0,0,0,0,0,0,0,0,0,CC45,0,0,0,0,0,0,0,0,0,0,0,0,0,0,0,0)';
      PINUSE='POWER';
      NO_LOAD_CHECK='Both';
      NO_IO_CHECK='Both';
      NO_ASSERT_CHECK='TRUE';
      NO_DIR_CHECK='TRUE';
      ALLOW_CONNECT='TRUE';
    'VCCIN262':
      PIN_NUMBER='(0,0,0,0,0,0,0,0,0,0,0,0,0,0,0,0,0,0,0,0,0,0,0,0,0,CC43,0,0,0,0,0,0,0,0,0,0,0,0,0,0,0,0)';
      PINUSE='POWER';
      NO_LOAD_CHECK='Both';
      NO_IO_CHECK='Both';
      NO_ASSERT_CHECK='TRUE';
      NO_DIR_CHECK='TRUE';
      ALLOW_CONNECT='TRUE';
    'VCCIN261':
      PIN_NUMBER='(0,0,0,0,0,0,0,0,0,0,0,0,0,0,0,0,0,0,0,0,0,0,0,0,0,CC41,0,0,0,0,0,0,0,0,0,0,0,0,0,0,0,0)';
      PINUSE='POWER';
      NO_LOAD_CHECK='Both';
      NO_IO_CHECK='Both';
      NO_ASSERT_CHECK='TRUE';
      NO_DIR_CHECK='TRUE';
      ALLOW_CONNECT='TRUE';
    'VCCIN260':
      PIN_NUMBER='(0,0,0,0,0,0,0,0,0,0,0,0,0,0,0,0,0,0,0,0,0,0,0,0,0,CC39,0,0,0,0,0,0,0,0,0,0,0,0,0,0,0,0)';
      PINUSE='POWER';
      NO_LOAD_CHECK='Both';
      NO_IO_CHECK='Both';
      NO_ASSERT_CHECK='TRUE';
      NO_DIR_CHECK='TRUE';
      ALLOW_CONNECT='TRUE';
    'VCCIN259':
      PIN_NUMBER='(0,0,0,0,0,0,0,0,0,0,0,0,0,0,0,0,0,0,0,0,0,0,0,0,0,CC37,0,0,0,0,0,0,0,0,0,0,0,0,0,0,0,0)';
      PINUSE='POWER';
      NO_LOAD_CHECK='Both';
      NO_IO_CHECK='Both';
      NO_ASSERT_CHECK='TRUE';
      NO_DIR_CHECK='TRUE';
      ALLOW_CONNECT='TRUE';
    'VCCIN258':
      PIN_NUMBER='(0,0,0,0,0,0,0,0,0,0,0,0,0,0,0,0,0,0,0,0,0,0,0,0,0,CC35,0,0,0,0,0,0,0,0,0,0,0,0,0,0,0,0)';
      PINUSE='POWER';
      NO_LOAD_CHECK='Both';
      NO_IO_CHECK='Both';
      NO_ASSERT_CHECK='TRUE';
      NO_DIR_CHECK='TRUE';
      ALLOW_CONNECT='TRUE';
    'VCCIN257':
      PIN_NUMBER='(0,0,0,0,0,0,0,0,0,0,0,0,0,0,0,0,0,0,0,0,0,0,0,0,0,CC33,0,0,0,0,0,0,0,0,0,0,0,0,0,0,0,0)';
      PINUSE='POWER';
      NO_LOAD_CHECK='Both';
      NO_IO_CHECK='Both';
      NO_ASSERT_CHECK='TRUE';
      NO_DIR_CHECK='TRUE';
      ALLOW_CONNECT='TRUE';
    'VCCIN256':
      PIN_NUMBER='(0,0,0,0,0,0,0,0,0,0,0,0,0,0,0,0,0,0,0,0,0,0,0,0,0,CB77,0,0,0,0,0,0,0,0,0,0,0,0,0,0,0,0)';
      PINUSE='POWER';
      NO_LOAD_CHECK='Both';
      NO_IO_CHECK='Both';
      NO_ASSERT_CHECK='TRUE';
      NO_DIR_CHECK='TRUE';
      ALLOW_CONNECT='TRUE';
    'VCCIN255':
      PIN_NUMBER='(0,0,0,0,0,0,0,0,0,0,0,0,0,0,0,0,0,0,0,0,0,0,0,0,0,CB75,0,0,0,0,0,0,0,0,0,0,0,0,0,0,0,0)';
      PINUSE='POWER';
      NO_LOAD_CHECK='Both';
      NO_IO_CHECK='Both';
      NO_ASSERT_CHECK='TRUE';
      NO_DIR_CHECK='TRUE';
      ALLOW_CONNECT='TRUE';
    'VCCIN254':
      PIN_NUMBER='(0,0,0,0,0,0,0,0,0,0,0,0,0,0,0,0,0,0,0,0,0,0,0,0,0,CB61,0,0,0,0,0,0,0,0,0,0,0,0,0,0,0,0)';
      PINUSE='POWER';
      NO_LOAD_CHECK='Both';
      NO_IO_CHECK='Both';
      NO_ASSERT_CHECK='TRUE';
      NO_DIR_CHECK='TRUE';
      ALLOW_CONNECT='TRUE';
    'VCCIN253':
      PIN_NUMBER='(0,0,0,0,0,0,0,0,0,0,0,0,0,0,0,0,0,0,0,0,0,0,0,0,0,CA90,0,0,0,0,0,0,0,0,0,0,0,0,0,0,0,0)';
      PINUSE='POWER';
      NO_LOAD_CHECK='Both';
      NO_IO_CHECK='Both';
      NO_ASSERT_CHECK='TRUE';
      NO_DIR_CHECK='TRUE';
      ALLOW_CONNECT='TRUE';
    'VCCIN252':
      PIN_NUMBER='(0,0,0,0,0,0,0,0,0,0,0,0,0,0,0,0,0,0,0,0,0,0,0,0,0,CA88,0,0,0,0,0,0,0,0,0,0,0,0,0,0,0,0)';
      PINUSE='POWER';
      NO_LOAD_CHECK='Both';
      NO_IO_CHECK='Both';
      NO_ASSERT_CHECK='TRUE';
      NO_DIR_CHECK='TRUE';
      ALLOW_CONNECT='TRUE';
    'VCCIN251':
      PIN_NUMBER='(0,0,0,0,0,0,0,0,0,0,0,0,0,0,0,0,0,0,0,0,0,0,0,0,0,CA86,0,0,0,0,0,0,0,0,0,0,0,0,0,0,0,0)';
      PINUSE='POWER';
      NO_LOAD_CHECK='Both';
      NO_IO_CHECK='Both';
      NO_ASSERT_CHECK='TRUE';
      NO_DIR_CHECK='TRUE';
      ALLOW_CONNECT='TRUE';
    'VCCIN250':
      PIN_NUMBER='(0,0,0,0,0,0,0,0,0,0,0,0,0,0,0,0,0,0,0,0,0,0,0,0,0,CA84,0,0,0,0,0,0,0,0,0,0,0,0,0,0,0,0)';
      PINUSE='POWER';
      NO_LOAD_CHECK='Both';
      NO_IO_CHECK='Both';
      NO_ASSERT_CHECK='TRUE';
      NO_DIR_CHECK='TRUE';
      ALLOW_CONNECT='TRUE';
    'VCCIN249':
      PIN_NUMBER='(0,0,0,0,0,0,0,0,0,0,0,0,0,0,0,0,0,0,0,0,0,0,0,0,0,CA82,0,0,0,0,0,0,0,0,0,0,0,0,0,0,0,0)';
      PINUSE='POWER';
      NO_LOAD_CHECK='Both';
      NO_IO_CHECK='Both';
      NO_ASSERT_CHECK='TRUE';
      NO_DIR_CHECK='TRUE';
      ALLOW_CONNECT='TRUE';
    'VCCIN248':
      PIN_NUMBER='(0,0,0,0,0,0,0,0,0,0,0,0,0,0,0,0,0,0,0,0,0,0,0,0,0,CA80,0,0,0,0,0,0,0,0,0,0,0,0,0,0,0,0)';
      PINUSE='POWER';
      NO_LOAD_CHECK='Both';
      NO_IO_CHECK='Both';
      NO_ASSERT_CHECK='TRUE';
      NO_DIR_CHECK='TRUE';
      ALLOW_CONNECT='TRUE';
    'VCCIN247':
      PIN_NUMBER='(0,0,0,0,0,0,0,0,0,0,0,0,0,0,0,0,0,0,0,0,0,0,0,0,0,CA78,0,0,0,0,0,0,0,0,0,0,0,0,0,0,0,0)';
      PINUSE='POWER';
      NO_LOAD_CHECK='Both';
      NO_IO_CHECK='Both';
      NO_ASSERT_CHECK='TRUE';
      NO_DIR_CHECK='TRUE';
      ALLOW_CONNECT='TRUE';
    'VCCIN246':
      PIN_NUMBER='(0,0,0,0,0,0,0,0,0,0,0,0,0,0,0,0,0,0,0,0,0,0,0,0,0,CA76,0,0,0,0,0,0,0,0,0,0,0,0,0,0,0,0)';
      PINUSE='POWER';
      NO_LOAD_CHECK='Both';
      NO_IO_CHECK='Both';
      NO_ASSERT_CHECK='TRUE';
      NO_DIR_CHECK='TRUE';
      ALLOW_CONNECT='TRUE';
    'VCCIN245':
      PIN_NUMBER='(0,0,0,0,0,0,0,0,0,0,0,0,0,0,0,0,0,0,0,0,0,0,0,0,0,CA74,0,0,0,0,0,0,0,0,0,0,0,0,0,0,0,0)';
      PINUSE='POWER';
      NO_LOAD_CHECK='Both';
      NO_IO_CHECK='Both';
      NO_ASSERT_CHECK='TRUE';
      NO_DIR_CHECK='TRUE';
      ALLOW_CONNECT='TRUE';
    'VCCIN244':
      PIN_NUMBER='(0,0,0,0,0,0,0,0,0,0,0,0,0,0,0,0,0,0,0,0,0,0,0,0,0,CA72,0,0,0,0,0,0,0,0,0,0,0,0,0,0,0,0)';
      PINUSE='POWER';
      NO_LOAD_CHECK='Both';
      NO_IO_CHECK='Both';
      NO_ASSERT_CHECK='TRUE';
      NO_DIR_CHECK='TRUE';
      ALLOW_CONNECT='TRUE';
    'VCCIN243':
      PIN_NUMBER='(0,0,0,0,0,0,0,0,0,0,0,0,0,0,0,0,0,0,0,0,0,0,0,0,0,CA70,0,0,0,0,0,0,0,0,0,0,0,0,0,0,0,0)';
      PINUSE='POWER';
      NO_LOAD_CHECK='Both';
      NO_IO_CHECK='Both';
      NO_ASSERT_CHECK='TRUE';
      NO_DIR_CHECK='TRUE';
      ALLOW_CONNECT='TRUE';
    'VCCIN242':
      PIN_NUMBER='(0,0,0,0,0,0,0,0,0,0,0,0,0,0,0,0,0,0,0,0,0,0,0,0,0,CA68,0,0,0,0,0,0,0,0,0,0,0,0,0,0,0,0)';
      PINUSE='POWER';
      NO_LOAD_CHECK='Both';
      NO_IO_CHECK='Both';
      NO_ASSERT_CHECK='TRUE';
      NO_DIR_CHECK='TRUE';
      ALLOW_CONNECT='TRUE';
    'VCCIN241':
      PIN_NUMBER='(0,0,0,0,0,0,0,0,0,0,0,0,0,0,0,0,0,0,0,0,0,0,0,0,0,CA66,0,0,0,0,0,0,0,0,0,0,0,0,0,0,0,0)';
      PINUSE='POWER';
      NO_LOAD_CHECK='Both';
      NO_IO_CHECK='Both';
      NO_ASSERT_CHECK='TRUE';
      NO_DIR_CHECK='TRUE';
      ALLOW_CONNECT='TRUE';
    'VCCIN240':
      PIN_NUMBER='(0,0,0,0,0,0,0,0,0,0,0,0,0,0,0,0,0,0,0,0,0,0,0,0,0,CA64,0,0,0,0,0,0,0,0,0,0,0,0,0,0,0,0)';
      PINUSE='POWER';
      NO_LOAD_CHECK='Both';
      NO_IO_CHECK='Both';
      NO_ASSERT_CHECK='TRUE';
      NO_DIR_CHECK='TRUE';
      ALLOW_CONNECT='TRUE';
    'VCCIN239':
      PIN_NUMBER='(0,0,0,0,0,0,0,0,0,0,0,0,0,0,0,0,0,0,0,0,0,0,0,0,0,CA62,0,0,0,0,0,0,0,0,0,0,0,0,0,0,0,0)';
      PINUSE='POWER';
      NO_LOAD_CHECK='Both';
      NO_IO_CHECK='Both';
      NO_ASSERT_CHECK='TRUE';
      NO_DIR_CHECK='TRUE';
      ALLOW_CONNECT='TRUE';
    'VCCIN238':
      PIN_NUMBER='(0,0,0,0,0,0,0,0,0,0,0,0,0,0,0,0,0,0,0,0,0,0,0,0,0,CA60,0,0,0,0,0,0,0,0,0,0,0,0,0,0,0,0)';
      PINUSE='POWER';
      NO_LOAD_CHECK='Both';
      NO_IO_CHECK='Both';
      NO_ASSERT_CHECK='TRUE';
      NO_DIR_CHECK='TRUE';
      ALLOW_CONNECT='TRUE';
    'VCCIN237':
      PIN_NUMBER='(0,0,0,0,0,0,0,0,0,0,0,0,0,0,0,0,0,0,0,0,0,0,0,0,0,CA58,0,0,0,0,0,0,0,0,0,0,0,0,0,0,0,0)';
      PINUSE='POWER';
      NO_LOAD_CHECK='Both';
      NO_IO_CHECK='Both';
      NO_ASSERT_CHECK='TRUE';
      NO_DIR_CHECK='TRUE';
      ALLOW_CONNECT='TRUE';
    'VCCIN236':
      PIN_NUMBER='(0,0,0,0,0,0,0,0,0,0,0,0,0,0,0,0,0,0,0,0,0,0,0,0,0,CA56,0,0,0,0,0,0,0,0,0,0,0,0,0,0,0,0)';
      PINUSE='POWER';
      NO_LOAD_CHECK='Both';
      NO_IO_CHECK='Both';
      NO_ASSERT_CHECK='TRUE';
      NO_DIR_CHECK='TRUE';
      ALLOW_CONNECT='TRUE';
    'VCCIN235':
      PIN_NUMBER='(0,0,0,0,0,0,0,0,0,0,0,0,0,0,0,0,0,0,0,0,0,0,0,0,0,CA54,0,0,0,0,0,0,0,0,0,0,0,0,0,0,0,0)';
      PINUSE='POWER';
      NO_LOAD_CHECK='Both';
      NO_IO_CHECK='Both';
      NO_ASSERT_CHECK='TRUE';
      NO_DIR_CHECK='TRUE';
      ALLOW_CONNECT='TRUE';
    'VCCIN234':
      PIN_NUMBER='(0,0,0,0,0,0,0,0,0,0,0,0,0,0,0,0,0,0,0,0,0,0,0,0,0,CA52,0,0,0,0,0,0,0,0,0,0,0,0,0,0,0,0)';
      PINUSE='POWER';
      NO_LOAD_CHECK='Both';
      NO_IO_CHECK='Both';
      NO_ASSERT_CHECK='TRUE';
      NO_DIR_CHECK='TRUE';
      ALLOW_CONNECT='TRUE';
    'VCCIN233':
      PIN_NUMBER='(0,0,0,0,0,0,0,0,0,0,0,0,0,0,0,0,0,0,0,0,0,0,0,0,0,CA50,0,0,0,0,0,0,0,0,0,0,0,0,0,0,0,0)';
      PINUSE='POWER';
      NO_LOAD_CHECK='Both';
      NO_IO_CHECK='Both';
      NO_ASSERT_CHECK='TRUE';
      NO_DIR_CHECK='TRUE';
      ALLOW_CONNECT='TRUE';
    'VCCIN232':
      PIN_NUMBER='(0,0,0,0,0,0,0,0,0,0,0,0,0,0,0,0,0,0,0,0,0,0,0,0,0,CA48,0,0,0,0,0,0,0,0,0,0,0,0,0,0,0,0)';
      PINUSE='POWER';
      NO_LOAD_CHECK='Both';
      NO_IO_CHECK='Both';
      NO_ASSERT_CHECK='TRUE';
      NO_DIR_CHECK='TRUE';
      ALLOW_CONNECT='TRUE';
    'VCCIN231':
      PIN_NUMBER='(0,0,0,0,0,0,0,0,0,0,0,0,0,0,0,0,0,0,0,0,0,0,0,0,0,CA45,0,0,0,0,0,0,0,0,0,0,0,0,0,0,0,0)';
      PINUSE='POWER';
      NO_LOAD_CHECK='Both';
      NO_IO_CHECK='Both';
      NO_ASSERT_CHECK='TRUE';
      NO_DIR_CHECK='TRUE';
      ALLOW_CONNECT='TRUE';
    'VCCIN230':
      PIN_NUMBER='(0,0,0,0,0,0,0,0,0,0,0,0,0,0,0,0,0,0,0,0,0,0,0,0,0,CA43,0,0,0,0,0,0,0,0,0,0,0,0,0,0,0,0)';
      PINUSE='POWER';
      NO_LOAD_CHECK='Both';
      NO_IO_CHECK='Both';
      NO_ASSERT_CHECK='TRUE';
      NO_DIR_CHECK='TRUE';
      ALLOW_CONNECT='TRUE';
    'VCCIN229':
      PIN_NUMBER='(0,0,0,0,0,0,0,0,0,0,0,0,0,0,0,0,0,0,0,0,0,0,0,0,0,CA41,0,0,0,0,0,0,0,0,0,0,0,0,0,0,0,0)';
      PINUSE='POWER';
      NO_LOAD_CHECK='Both';
      NO_IO_CHECK='Both';
      NO_ASSERT_CHECK='TRUE';
      NO_DIR_CHECK='TRUE';
      ALLOW_CONNECT='TRUE';
    'VCCIN228':
      PIN_NUMBER='(0,0,0,0,0,0,0,0,0,0,0,0,0,0,0,0,0,0,0,0,0,0,0,0,0,CA39,0,0,0,0,0,0,0,0,0,0,0,0,0,0,0,0)';
      PINUSE='POWER';
      NO_LOAD_CHECK='Both';
      NO_IO_CHECK='Both';
      NO_ASSERT_CHECK='TRUE';
      NO_DIR_CHECK='TRUE';
      ALLOW_CONNECT='TRUE';
    'VCCIN227':
      PIN_NUMBER='(0,0,0,0,0,0,0,0,0,0,0,0,0,0,0,0,0,0,0,0,0,0,0,0,0,CA37,0,0,0,0,0,0,0,0,0,0,0,0,0,0,0,0)';
      PINUSE='POWER';
      NO_LOAD_CHECK='Both';
      NO_IO_CHECK='Both';
      NO_ASSERT_CHECK='TRUE';
      NO_DIR_CHECK='TRUE';
      ALLOW_CONNECT='TRUE';
    'VCCIN226':
      PIN_NUMBER='(0,0,0,0,0,0,0,0,0,0,0,0,0,0,0,0,0,0,0,0,0,0,0,0,0,CA35,0,0,0,0,0,0,0,0,0,0,0,0,0,0,0,0)';
      PINUSE='POWER';
      NO_LOAD_CHECK='Both';
      NO_IO_CHECK='Both';
      NO_ASSERT_CHECK='TRUE';
      NO_DIR_CHECK='TRUE';
      ALLOW_CONNECT='TRUE';
    'VCCIN225':
      PIN_NUMBER='(0,0,0,0,0,0,0,0,0,0,0,0,0,0,0,0,0,0,0,0,0,0,0,0,0,CA33,0,0,0,0,0,0,0,0,0,0,0,0,0,0,0,0)';
      PINUSE='POWER';
      NO_LOAD_CHECK='Both';
      NO_IO_CHECK='Both';
      NO_ASSERT_CHECK='TRUE';
      NO_DIR_CHECK='TRUE';
      ALLOW_CONNECT='TRUE';
    'VCCIN224':
      PIN_NUMBER='(0,0,0,0,0,0,0,0,0,0,0,0,0,0,0,0,0,0,0,0,0,0,0,0,0,BY89,0,0,0,0,0,0,0,0,0,0,0,0,0,0,0,0)';
      PINUSE='POWER';
      NO_LOAD_CHECK='Both';
      NO_IO_CHECK='Both';
      NO_ASSERT_CHECK='TRUE';
      NO_DIR_CHECK='TRUE';
      ALLOW_CONNECT='TRUE';
    'VCCIN223':
      PIN_NUMBER='(0,0,0,0,0,0,0,0,0,0,0,0,0,0,0,0,0,0,0,0,0,0,0,0,0,BY87,0,0,0,0,0,0,0,0,0,0,0,0,0,0,0,0)';
      PINUSE='POWER';
      NO_LOAD_CHECK='Both';
      NO_IO_CHECK='Both';
      NO_ASSERT_CHECK='TRUE';
      NO_DIR_CHECK='TRUE';
      ALLOW_CONNECT='TRUE';
    'VCCIN222':
      PIN_NUMBER='(0,0,0,0,0,0,0,0,0,0,0,0,0,0,0,0,0,0,0,0,0,0,0,0,0,BY85,0,0,0,0,0,0,0,0,0,0,0,0,0,0,0,0)';
      PINUSE='POWER';
      NO_LOAD_CHECK='Both';
      NO_IO_CHECK='Both';
      NO_ASSERT_CHECK='TRUE';
      NO_DIR_CHECK='TRUE';
      ALLOW_CONNECT='TRUE';
    'VCCIN221':
      PIN_NUMBER='(0,0,0,0,0,0,0,0,0,0,0,0,0,0,0,0,0,0,0,0,0,0,0,0,0,BY83,0,0,0,0,0,0,0,0,0,0,0,0,0,0,0,0)';
      PINUSE='POWER';
      NO_LOAD_CHECK='Both';
      NO_IO_CHECK='Both';
      NO_ASSERT_CHECK='TRUE';
      NO_DIR_CHECK='TRUE';
      ALLOW_CONNECT='TRUE';
    'VCCIN220':
      PIN_NUMBER='(0,0,0,0,0,0,0,0,0,0,0,0,0,0,0,0,0,0,0,0,0,0,0,0,0,BY81,0,0,0,0,0,0,0,0,0,0,0,0,0,0,0,0)';
      PINUSE='POWER';
      NO_LOAD_CHECK='Both';
      NO_IO_CHECK='Both';
      NO_ASSERT_CHECK='TRUE';
      NO_DIR_CHECK='TRUE';
      ALLOW_CONNECT='TRUE';
    'VCCIN219':
      PIN_NUMBER='(0,0,0,0,0,0,0,0,0,0,0,0,0,0,0,0,0,0,0,0,0,0,0,0,0,BY79,0,0,0,0,0,0,0,0,0,0,0,0,0,0,0,0)';
      PINUSE='POWER';
      NO_LOAD_CHECK='Both';
      NO_IO_CHECK='Both';
      NO_ASSERT_CHECK='TRUE';
      NO_DIR_CHECK='TRUE';
      ALLOW_CONNECT='TRUE';
    'VCCIN218':
      PIN_NUMBER='(0,0,0,0,0,0,0,0,0,0,0,0,0,0,0,0,0,0,0,0,0,0,0,0,0,BY77,0,0,0,0,0,0,0,0,0,0,0,0,0,0,0,0)';
      PINUSE='POWER';
      NO_LOAD_CHECK='Both';
      NO_IO_CHECK='Both';
      NO_ASSERT_CHECK='TRUE';
      NO_DIR_CHECK='TRUE';
      ALLOW_CONNECT='TRUE';
    'VCCIN217':
      PIN_NUMBER='(0,0,0,0,0,0,0,0,0,0,0,0,0,0,0,0,0,0,0,0,0,0,0,0,0,BY75,0,0,0,0,0,0,0,0,0,0,0,0,0,0,0,0)';
      PINUSE='POWER';
      NO_LOAD_CHECK='Both';
      NO_IO_CHECK='Both';
      NO_ASSERT_CHECK='TRUE';
      NO_DIR_CHECK='TRUE';
      ALLOW_CONNECT='TRUE';
    'VCCIN216':
      PIN_NUMBER='(0,0,0,0,0,0,0,0,0,0,0,0,0,0,0,0,0,0,0,0,0,0,0,0,0,BY73,0,0,0,0,0,0,0,0,0,0,0,0,0,0,0,0)';
      PINUSE='POWER';
      NO_LOAD_CHECK='Both';
      NO_IO_CHECK='Both';
      NO_ASSERT_CHECK='TRUE';
      NO_DIR_CHECK='TRUE';
      ALLOW_CONNECT='TRUE';
    'VCCIN215':
      PIN_NUMBER='(0,0,0,0,0,0,0,0,0,0,0,0,0,0,0,0,0,0,0,0,0,0,0,0,0,BY71,0,0,0,0,0,0,0,0,0,0,0,0,0,0,0,0)';
      PINUSE='POWER';
      NO_LOAD_CHECK='Both';
      NO_IO_CHECK='Both';
      NO_ASSERT_CHECK='TRUE';
      NO_DIR_CHECK='TRUE';
      ALLOW_CONNECT='TRUE';
    'VCCIN214':
      PIN_NUMBER='(0,0,0,0,0,0,0,0,0,0,0,0,0,0,0,0,0,0,0,0,0,0,0,0,0,BY69,0,0,0,0,0,0,0,0,0,0,0,0,0,0,0,0)';
      PINUSE='POWER';
      NO_LOAD_CHECK='Both';
      NO_IO_CHECK='Both';
      NO_ASSERT_CHECK='TRUE';
      NO_DIR_CHECK='TRUE';
      ALLOW_CONNECT='TRUE';
    'VCCIN213':
      PIN_NUMBER='(0,0,0,0,0,0,0,0,0,0,0,0,0,0,0,0,0,0,0,0,0,0,0,0,0,BY67,0,0,0,0,0,0,0,0,0,0,0,0,0,0,0,0)';
      PINUSE='POWER';
      NO_LOAD_CHECK='Both';
      NO_IO_CHECK='Both';
      NO_ASSERT_CHECK='TRUE';
      NO_DIR_CHECK='TRUE';
      ALLOW_CONNECT='TRUE';
    'VCCIN212':
      PIN_NUMBER='(0,0,0,0,0,0,0,0,0,0,0,0,0,0,0,0,0,0,0,0,0,0,0,0,0,BY65,0,0,0,0,0,0,0,0,0,0,0,0,0,0,0,0)';
      PINUSE='POWER';
      NO_LOAD_CHECK='Both';
      NO_IO_CHECK='Both';
      NO_ASSERT_CHECK='TRUE';
      NO_DIR_CHECK='TRUE';
      ALLOW_CONNECT='TRUE';
    'VCCIN211':
      PIN_NUMBER='(0,0,0,0,0,0,0,0,0,0,0,0,0,0,0,0,0,0,0,0,0,0,0,0,0,BY63,0,0,0,0,0,0,0,0,0,0,0,0,0,0,0,0)';
      PINUSE='POWER';
      NO_LOAD_CHECK='Both';
      NO_IO_CHECK='Both';
      NO_ASSERT_CHECK='TRUE';
      NO_DIR_CHECK='TRUE';
      ALLOW_CONNECT='TRUE';
    'VCCIN210':
      PIN_NUMBER='(0,0,0,0,0,0,0,0,0,0,0,0,0,0,0,0,0,0,0,0,0,0,0,0,0,BY61,0,0,0,0,0,0,0,0,0,0,0,0,0,0,0,0)';
      PINUSE='POWER';
      NO_LOAD_CHECK='Both';
      NO_IO_CHECK='Both';
      NO_ASSERT_CHECK='TRUE';
      NO_DIR_CHECK='TRUE';
      ALLOW_CONNECT='TRUE';
    'VCCIN209':
      PIN_NUMBER='(0,0,0,0,0,0,0,0,0,0,0,0,0,0,0,0,0,0,0,0,0,0,0,0,0,BY59,0,0,0,0,0,0,0,0,0,0,0,0,0,0,0,0)';
      PINUSE='POWER';
      NO_LOAD_CHECK='Both';
      NO_IO_CHECK='Both';
      NO_ASSERT_CHECK='TRUE';
      NO_DIR_CHECK='TRUE';
      ALLOW_CONNECT='TRUE';
    'VCCIN208':
      PIN_NUMBER='(0,0,0,0,0,0,0,0,0,0,0,0,0,0,0,0,0,0,0,0,0,0,0,0,0,BY57,0,0,0,0,0,0,0,0,0,0,0,0,0,0,0,0)';
      PINUSE='POWER';
      NO_LOAD_CHECK='Both';
      NO_IO_CHECK='Both';
      NO_ASSERT_CHECK='TRUE';
      NO_DIR_CHECK='TRUE';
      ALLOW_CONNECT='TRUE';
    'VCCIN207':
      PIN_NUMBER='(0,0,0,0,0,0,0,0,0,0,0,0,0,0,0,0,0,0,0,0,0,0,0,0,0,BY55,0,0,0,0,0,0,0,0,0,0,0,0,0,0,0,0)';
      PINUSE='POWER';
      NO_LOAD_CHECK='Both';
      NO_IO_CHECK='Both';
      NO_ASSERT_CHECK='TRUE';
      NO_DIR_CHECK='TRUE';
      ALLOW_CONNECT='TRUE';
    'VCCIN206':
      PIN_NUMBER='(0,0,0,0,0,0,0,0,0,0,0,0,0,0,0,0,0,0,0,0,0,0,0,0,0,BY53,0,0,0,0,0,0,0,0,0,0,0,0,0,0,0,0)';
      PINUSE='POWER';
      NO_LOAD_CHECK='Both';
      NO_IO_CHECK='Both';
      NO_ASSERT_CHECK='TRUE';
      NO_DIR_CHECK='TRUE';
      ALLOW_CONNECT='TRUE';
    'VCCIN205':
      PIN_NUMBER='(0,0,0,0,0,0,0,0,0,0,0,0,0,0,0,0,0,0,0,0,0,0,0,0,0,BY51,0,0,0,0,0,0,0,0,0,0,0,0,0,0,0,0)';
      PINUSE='POWER';
      NO_LOAD_CHECK='Both';
      NO_IO_CHECK='Both';
      NO_ASSERT_CHECK='TRUE';
      NO_DIR_CHECK='TRUE';
      ALLOW_CONNECT='TRUE';
    'VCCIN204':
      PIN_NUMBER='(0,0,0,0,0,0,0,0,0,0,0,0,0,0,0,0,0,0,0,0,0,0,0,0,0,BY49,0,0,0,0,0,0,0,0,0,0,0,0,0,0,0,0)';
      PINUSE='POWER';
      NO_LOAD_CHECK='Both';
      NO_IO_CHECK='Both';
      NO_ASSERT_CHECK='TRUE';
      NO_DIR_CHECK='TRUE';
      ALLOW_CONNECT='TRUE';
    'VCCIN203':
      PIN_NUMBER='(0,0,0,0,0,0,0,0,0,0,0,0,0,0,0,0,0,0,0,0,0,0,0,0,0,BY47,0,0,0,0,0,0,0,0,0,0,0,0,0,0,0,0)';
      PINUSE='POWER';
      NO_LOAD_CHECK='Both';
      NO_IO_CHECK='Both';
      NO_ASSERT_CHECK='TRUE';
      NO_DIR_CHECK='TRUE';
      ALLOW_CONNECT='TRUE';
    'VCCIN202':
      PIN_NUMBER='(0,0,0,0,0,0,0,0,0,0,0,0,0,0,0,0,0,0,0,0,0,0,0,0,0,BY44,0,0,0,0,0,0,0,0,0,0,0,0,0,0,0,0)';
      PINUSE='POWER';
      NO_LOAD_CHECK='Both';
      NO_IO_CHECK='Both';
      NO_ASSERT_CHECK='TRUE';
      NO_DIR_CHECK='TRUE';
      ALLOW_CONNECT='TRUE';
    'VCCIN201':
      PIN_NUMBER='(0,0,0,0,0,0,0,0,0,0,0,0,0,0,0,0,0,0,0,0,0,0,0,0,0,BY42,0,0,0,0,0,0,0,0,0,0,0,0,0,0,0,0)';
      PINUSE='POWER';
      NO_LOAD_CHECK='Both';
      NO_IO_CHECK='Both';
      NO_ASSERT_CHECK='TRUE';
      NO_DIR_CHECK='TRUE';
      ALLOW_CONNECT='TRUE';
    'VCCIN200':
      PIN_NUMBER='(0,0,0,0,0,0,0,0,0,0,0,0,0,0,0,0,0,0,0,0,0,0,0,0,0,BY40,0,0,0,0,0,0,0,0,0,0,0,0,0,0,0,0)';
      PINUSE='POWER';
      NO_LOAD_CHECK='Both';
      NO_IO_CHECK='Both';
      NO_ASSERT_CHECK='TRUE';
      NO_DIR_CHECK='TRUE';
      ALLOW_CONNECT='TRUE';
    'VCCIN199':
      PIN_NUMBER='(0,0,0,0,0,0,0,0,0,0,0,0,0,0,0,0,0,0,0,0,0,0,0,0,0,BY38,0,0,0,0,0,0,0,0,0,0,0,0,0,0,0,0)';
      PINUSE='POWER';
      NO_LOAD_CHECK='Both';
      NO_IO_CHECK='Both';
      NO_ASSERT_CHECK='TRUE';
      NO_DIR_CHECK='TRUE';
      ALLOW_CONNECT='TRUE';
    'VCCIN198':
      PIN_NUMBER='(0,0,0,0,0,0,0,0,0,0,0,0,0,0,0,0,0,0,0,0,0,0,0,0,0,BY36,0,0,0,0,0,0,0,0,0,0,0,0,0,0,0,0)';
      PINUSE='POWER';
      NO_LOAD_CHECK='Both';
      NO_IO_CHECK='Both';
      NO_ASSERT_CHECK='TRUE';
      NO_DIR_CHECK='TRUE';
      ALLOW_CONNECT='TRUE';
    'VCCIN197':
      PIN_NUMBER='(0,0,0,0,0,0,0,0,0,0,0,0,0,0,0,0,0,0,0,0,0,0,0,0,0,BY34,0,0,0,0,0,0,0,0,0,0,0,0,0,0,0,0)';
      PINUSE='POWER';
      NO_LOAD_CHECK='Both';
      NO_IO_CHECK='Both';
      NO_ASSERT_CHECK='TRUE';
      NO_DIR_CHECK='TRUE';
      ALLOW_CONNECT='TRUE';
    'VCCIN196':
      PIN_NUMBER='(0,0,0,0,0,0,0,0,0,0,0,0,0,0,0,0,0,0,0,0,0,0,0,0,0,BY32,0,0,0,0,0,0,0,0,0,0,0,0,0,0,0,0)';
      PINUSE='POWER';
      NO_LOAD_CHECK='Both';
      NO_IO_CHECK='Both';
      NO_ASSERT_CHECK='TRUE';
      NO_DIR_CHECK='TRUE';
      ALLOW_CONNECT='TRUE';
    'VCCIN195':
      PIN_NUMBER='(0,0,0,0,0,0,0,0,0,0,0,0,0,0,0,0,0,0,0,0,0,0,0,0,0,BW90,0,0,0,0,0,0,0,0,0,0,0,0,0,0,0,0)';
      PINUSE='POWER';
      NO_LOAD_CHECK='Both';
      NO_IO_CHECK='Both';
      NO_ASSERT_CHECK='TRUE';
      NO_DIR_CHECK='TRUE';
      ALLOW_CONNECT='TRUE';
    'VCCIN194':
      PIN_NUMBER='(0,0,0,0,0,0,0,0,0,0,0,0,0,0,0,0,0,0,0,0,0,0,0,0,0,BW88,0,0,0,0,0,0,0,0,0,0,0,0,0,0,0,0)';
      PINUSE='POWER';
      NO_LOAD_CHECK='Both';
      NO_IO_CHECK='Both';
      NO_ASSERT_CHECK='TRUE';
      NO_DIR_CHECK='TRUE';
      ALLOW_CONNECT='TRUE';
    'VCCIN193':
      PIN_NUMBER='(0,0,0,0,0,0,0,0,0,0,0,0,0,0,0,0,0,0,0,0,0,0,0,0,0,BW86,0,0,0,0,0,0,0,0,0,0,0,0,0,0,0,0)';
      PINUSE='POWER';
      NO_LOAD_CHECK='Both';
      NO_IO_CHECK='Both';
      NO_ASSERT_CHECK='TRUE';
      NO_DIR_CHECK='TRUE';
      ALLOW_CONNECT='TRUE';
    'VCCIN192':
      PIN_NUMBER='(0,0,0,0,0,0,0,0,0,0,0,0,0,0,0,0,0,0,0,0,0,0,0,0,0,BW84,0,0,0,0,0,0,0,0,0,0,0,0,0,0,0,0)';
      PINUSE='POWER';
      NO_LOAD_CHECK='Both';
      NO_IO_CHECK='Both';
      NO_ASSERT_CHECK='TRUE';
      NO_DIR_CHECK='TRUE';
      ALLOW_CONNECT='TRUE';
    'VCCIN191':
      PIN_NUMBER='(0,0,0,0,0,0,0,0,0,0,0,0,0,0,0,0,0,0,0,0,0,0,0,0,0,BW82,0,0,0,0,0,0,0,0,0,0,0,0,0,0,0,0)';
      PINUSE='POWER';
      NO_LOAD_CHECK='Both';
      NO_IO_CHECK='Both';
      NO_ASSERT_CHECK='TRUE';
      NO_DIR_CHECK='TRUE';
      ALLOW_CONNECT='TRUE';
    'VCCIN190':
      PIN_NUMBER='(0,0,0,0,0,0,0,0,0,0,0,0,0,0,0,0,0,0,0,0,0,0,0,0,0,BW80,0,0,0,0,0,0,0,0,0,0,0,0,0,0,0,0)';
      PINUSE='POWER';
      NO_LOAD_CHECK='Both';
      NO_IO_CHECK='Both';
      NO_ASSERT_CHECK='TRUE';
      NO_DIR_CHECK='TRUE';
      ALLOW_CONNECT='TRUE';
    'VCCIN189':
      PIN_NUMBER='(0,0,0,0,0,0,0,0,0,0,0,0,0,0,0,0,0,0,0,0,0,0,0,0,0,0,BW78,0,0,0,0,0,0,0,0,0,0,0,0,0,0,0)';
      PINUSE='POWER';
      NO_LOAD_CHECK='Both';
      NO_IO_CHECK='Both';
      NO_ASSERT_CHECK='TRUE';
      NO_DIR_CHECK='TRUE';
      ALLOW_CONNECT='TRUE';
    'VCCIN188':
      PIN_NUMBER='(0,0,0,0,0,0,0,0,0,0,0,0,0,0,0,0,0,0,0,0,0,0,0,0,0,0,BW76,0,0,0,0,0,0,0,0,0,0,0,0,0,0,0)';
      PINUSE='POWER';
      NO_LOAD_CHECK='Both';
      NO_IO_CHECK='Both';
      NO_ASSERT_CHECK='TRUE';
      NO_DIR_CHECK='TRUE';
      ALLOW_CONNECT='TRUE';
    'VCCIN187':
      PIN_NUMBER='(0,0,0,0,0,0,0,0,0,0,0,0,0,0,0,0,0,0,0,0,0,0,0,0,0,0,BW74,0,0,0,0,0,0,0,0,0,0,0,0,0,0,0)';
      PINUSE='POWER';
      NO_LOAD_CHECK='Both';
      NO_IO_CHECK='Both';
      NO_ASSERT_CHECK='TRUE';
      NO_DIR_CHECK='TRUE';
      ALLOW_CONNECT='TRUE';
    'VCCIN186':
      PIN_NUMBER='(0,0,0,0,0,0,0,0,0,0,0,0,0,0,0,0,0,0,0,0,0,0,0,0,0,0,BW72,0,0,0,0,0,0,0,0,0,0,0,0,0,0,0)';
      PINUSE='POWER';
      NO_LOAD_CHECK='Both';
      NO_IO_CHECK='Both';
      NO_ASSERT_CHECK='TRUE';
      NO_DIR_CHECK='TRUE';
      ALLOW_CONNECT='TRUE';
    'VCCIN185':
      PIN_NUMBER='(0,0,0,0,0,0,0,0,0,0,0,0,0,0,0,0,0,0,0,0,0,0,0,0,0,0,BW70,0,0,0,0,0,0,0,0,0,0,0,0,0,0,0)';
      PINUSE='POWER';
      NO_LOAD_CHECK='Both';
      NO_IO_CHECK='Both';
      NO_ASSERT_CHECK='TRUE';
      NO_DIR_CHECK='TRUE';
      ALLOW_CONNECT='TRUE';
    'VCCIN184':
      PIN_NUMBER='(0,0,0,0,0,0,0,0,0,0,0,0,0,0,0,0,0,0,0,0,0,0,0,0,0,0,BW68,0,0,0,0,0,0,0,0,0,0,0,0,0,0,0)';
      PINUSE='POWER';
      NO_LOAD_CHECK='Both';
      NO_IO_CHECK='Both';
      NO_ASSERT_CHECK='TRUE';
      NO_DIR_CHECK='TRUE';
      ALLOW_CONNECT='TRUE';
    'VCCIN183':
      PIN_NUMBER='(0,0,0,0,0,0,0,0,0,0,0,0,0,0,0,0,0,0,0,0,0,0,0,0,0,0,BW66,0,0,0,0,0,0,0,0,0,0,0,0,0,0,0)';
      PINUSE='POWER';
      NO_LOAD_CHECK='Both';
      NO_IO_CHECK='Both';
      NO_ASSERT_CHECK='TRUE';
      NO_DIR_CHECK='TRUE';
      ALLOW_CONNECT='TRUE';
    'VCCIN182':
      PIN_NUMBER='(0,0,0,0,0,0,0,0,0,0,0,0,0,0,0,0,0,0,0,0,0,0,0,0,0,0,BW64,0,0,0,0,0,0,0,0,0,0,0,0,0,0,0)';
      PINUSE='POWER';
      NO_LOAD_CHECK='Both';
      NO_IO_CHECK='Both';
      NO_ASSERT_CHECK='TRUE';
      NO_DIR_CHECK='TRUE';
      ALLOW_CONNECT='TRUE';
    'VCCIN181':
      PIN_NUMBER='(0,0,0,0,0,0,0,0,0,0,0,0,0,0,0,0,0,0,0,0,0,0,0,0,0,0,BW62,0,0,0,0,0,0,0,0,0,0,0,0,0,0,0)';
      PINUSE='POWER';
      NO_LOAD_CHECK='Both';
      NO_IO_CHECK='Both';
      NO_ASSERT_CHECK='TRUE';
      NO_DIR_CHECK='TRUE';
      ALLOW_CONNECT='TRUE';
    'VCCIN180':
      PIN_NUMBER='(0,0,0,0,0,0,0,0,0,0,0,0,0,0,0,0,0,0,0,0,0,0,0,0,0,0,BW60,0,0,0,0,0,0,0,0,0,0,0,0,0,0,0)';
      PINUSE='POWER';
      NO_LOAD_CHECK='Both';
      NO_IO_CHECK='Both';
      NO_ASSERT_CHECK='TRUE';
      NO_DIR_CHECK='TRUE';
      ALLOW_CONNECT='TRUE';
    'VCCIN179':
      PIN_NUMBER='(0,0,0,0,0,0,0,0,0,0,0,0,0,0,0,0,0,0,0,0,0,0,0,0,0,0,BW58,0,0,0,0,0,0,0,0,0,0,0,0,0,0,0)';
      PINUSE='POWER';
      NO_LOAD_CHECK='Both';
      NO_IO_CHECK='Both';
      NO_ASSERT_CHECK='TRUE';
      NO_DIR_CHECK='TRUE';
      ALLOW_CONNECT='TRUE';
    'VCCIN178':
      PIN_NUMBER='(0,0,0,0,0,0,0,0,0,0,0,0,0,0,0,0,0,0,0,0,0,0,0,0,0,0,BW56,0,0,0,0,0,0,0,0,0,0,0,0,0,0,0)';
      PINUSE='POWER';
      NO_LOAD_CHECK='Both';
      NO_IO_CHECK='Both';
      NO_ASSERT_CHECK='TRUE';
      NO_DIR_CHECK='TRUE';
      ALLOW_CONNECT='TRUE';
    'VCCIN177':
      PIN_NUMBER='(0,0,0,0,0,0,0,0,0,0,0,0,0,0,0,0,0,0,0,0,0,0,0,0,0,0,BW54,0,0,0,0,0,0,0,0,0,0,0,0,0,0,0)';
      PINUSE='POWER';
      NO_LOAD_CHECK='Both';
      NO_IO_CHECK='Both';
      NO_ASSERT_CHECK='TRUE';
      NO_DIR_CHECK='TRUE';
      ALLOW_CONNECT='TRUE';
    'VCCIN176':
      PIN_NUMBER='(0,0,0,0,0,0,0,0,0,0,0,0,0,0,0,0,0,0,0,0,0,0,0,0,0,0,BW52,0,0,0,0,0,0,0,0,0,0,0,0,0,0,0)';
      PINUSE='POWER';
      NO_LOAD_CHECK='Both';
      NO_IO_CHECK='Both';
      NO_ASSERT_CHECK='TRUE';
      NO_DIR_CHECK='TRUE';
      ALLOW_CONNECT='TRUE';
    'VCCIN175':
      PIN_NUMBER='(0,0,0,0,0,0,0,0,0,0,0,0,0,0,0,0,0,0,0,0,0,0,0,0,0,0,BW50,0,0,0,0,0,0,0,0,0,0,0,0,0,0,0)';
      PINUSE='POWER';
      NO_LOAD_CHECK='Both';
      NO_IO_CHECK='Both';
      NO_ASSERT_CHECK='TRUE';
      NO_DIR_CHECK='TRUE';
      ALLOW_CONNECT='TRUE';
    'VCCIN174':
      PIN_NUMBER='(0,0,0,0,0,0,0,0,0,0,0,0,0,0,0,0,0,0,0,0,0,0,0,0,0,0,BW48,0,0,0,0,0,0,0,0,0,0,0,0,0,0,0)';
      PINUSE='POWER';
      NO_LOAD_CHECK='Both';
      NO_IO_CHECK='Both';
      NO_ASSERT_CHECK='TRUE';
      NO_DIR_CHECK='TRUE';
      ALLOW_CONNECT='TRUE';
    'VCCIN173':
      PIN_NUMBER='(0,0,0,0,0,0,0,0,0,0,0,0,0,0,0,0,0,0,0,0,0,0,0,0,0,0,BW45,0,0,0,0,0,0,0,0,0,0,0,0,0,0,0)';
      PINUSE='POWER';
      NO_LOAD_CHECK='Both';
      NO_IO_CHECK='Both';
      NO_ASSERT_CHECK='TRUE';
      NO_DIR_CHECK='TRUE';
      ALLOW_CONNECT='TRUE';
    'VCCIN172':
      PIN_NUMBER='(0,0,0,0,0,0,0,0,0,0,0,0,0,0,0,0,0,0,0,0,0,0,0,0,0,0,BW43,0,0,0,0,0,0,0,0,0,0,0,0,0,0,0)';
      PINUSE='POWER';
      NO_LOAD_CHECK='Both';
      NO_IO_CHECK='Both';
      NO_ASSERT_CHECK='TRUE';
      NO_DIR_CHECK='TRUE';
      ALLOW_CONNECT='TRUE';
    'VCCIN171':
      PIN_NUMBER='(0,0,0,0,0,0,0,0,0,0,0,0,0,0,0,0,0,0,0,0,0,0,0,0,0,0,BW41,0,0,0,0,0,0,0,0,0,0,0,0,0,0,0)';
      PINUSE='POWER';
      NO_LOAD_CHECK='Both';
      NO_IO_CHECK='Both';
      NO_ASSERT_CHECK='TRUE';
      NO_DIR_CHECK='TRUE';
      ALLOW_CONNECT='TRUE';
    'VCCIN170':
      PIN_NUMBER='(0,0,0,0,0,0,0,0,0,0,0,0,0,0,0,0,0,0,0,0,0,0,0,0,0,0,BW39,0,0,0,0,0,0,0,0,0,0,0,0,0,0,0)';
      PINUSE='POWER';
      NO_LOAD_CHECK='Both';
      NO_IO_CHECK='Both';
      NO_ASSERT_CHECK='TRUE';
      NO_DIR_CHECK='TRUE';
      ALLOW_CONNECT='TRUE';
    'VCCIN169':
      PIN_NUMBER='(0,0,0,0,0,0,0,0,0,0,0,0,0,0,0,0,0,0,0,0,0,0,0,0,0,0,BW37,0,0,0,0,0,0,0,0,0,0,0,0,0,0,0)';
      PINUSE='POWER';
      NO_LOAD_CHECK='Both';
      NO_IO_CHECK='Both';
      NO_ASSERT_CHECK='TRUE';
      NO_DIR_CHECK='TRUE';
      ALLOW_CONNECT='TRUE';
    'VCCIN168':
      PIN_NUMBER='(0,0,0,0,0,0,0,0,0,0,0,0,0,0,0,0,0,0,0,0,0,0,0,0,0,0,BW35,0,0,0,0,0,0,0,0,0,0,0,0,0,0,0)';
      PINUSE='POWER';
      NO_LOAD_CHECK='Both';
      NO_IO_CHECK='Both';
      NO_ASSERT_CHECK='TRUE';
      NO_DIR_CHECK='TRUE';
      ALLOW_CONNECT='TRUE';
    'VCCIN167':
      PIN_NUMBER='(0,0,0,0,0,0,0,0,0,0,0,0,0,0,0,0,0,0,0,0,0,0,0,0,0,0,BW33,0,0,0,0,0,0,0,0,0,0,0,0,0,0,0)';
      PINUSE='POWER';
      NO_LOAD_CHECK='Both';
      NO_IO_CHECK='Both';
      NO_ASSERT_CHECK='TRUE';
      NO_DIR_CHECK='TRUE';
      ALLOW_CONNECT='TRUE';
    'VCCIN166':
      PIN_NUMBER='(0,0,0,0,0,0,0,0,0,0,0,0,0,0,0,0,0,0,0,0,0,0,0,0,0,0,BV89,0,0,0,0,0,0,0,0,0,0,0,0,0,0,0)';
      PINUSE='POWER';
      NO_LOAD_CHECK='Both';
      NO_IO_CHECK='Both';
      NO_ASSERT_CHECK='TRUE';
      NO_DIR_CHECK='TRUE';
      ALLOW_CONNECT='TRUE';
    'VCCIN165':
      PIN_NUMBER='(0,0,0,0,0,0,0,0,0,0,0,0,0,0,0,0,0,0,0,0,0,0,0,0,0,0,BV87,0,0,0,0,0,0,0,0,0,0,0,0,0,0,0)';
      PINUSE='POWER';
      NO_LOAD_CHECK='Both';
      NO_IO_CHECK='Both';
      NO_ASSERT_CHECK='TRUE';
      NO_DIR_CHECK='TRUE';
      ALLOW_CONNECT='TRUE';
    'VCCIN164':
      PIN_NUMBER='(0,0,0,0,0,0,0,0,0,0,0,0,0,0,0,0,0,0,0,0,0,0,0,0,0,0,BV85,0,0,0,0,0,0,0,0,0,0,0,0,0,0,0)';
      PINUSE='POWER';
      NO_LOAD_CHECK='Both';
      NO_IO_CHECK='Both';
      NO_ASSERT_CHECK='TRUE';
      NO_DIR_CHECK='TRUE';
      ALLOW_CONNECT='TRUE';
    'VCCIN163':
      PIN_NUMBER='(0,0,0,0,0,0,0,0,0,0,0,0,0,0,0,0,0,0,0,0,0,0,0,0,0,0,BV83,0,0,0,0,0,0,0,0,0,0,0,0,0,0,0)';
      PINUSE='POWER';
      NO_LOAD_CHECK='Both';
      NO_IO_CHECK='Both';
      NO_ASSERT_CHECK='TRUE';
      NO_DIR_CHECK='TRUE';
      ALLOW_CONNECT='TRUE';
    'VCCIN162':
      PIN_NUMBER='(0,0,0,0,0,0,0,0,0,0,0,0,0,0,0,0,0,0,0,0,0,0,0,0,0,0,BV81,0,0,0,0,0,0,0,0,0,0,0,0,0,0,0)';
      PINUSE='POWER';
      NO_LOAD_CHECK='Both';
      NO_IO_CHECK='Both';
      NO_ASSERT_CHECK='TRUE';
      NO_DIR_CHECK='TRUE';
      ALLOW_CONNECT='TRUE';
    'VCCIN161':
      PIN_NUMBER='(0,0,0,0,0,0,0,0,0,0,0,0,0,0,0,0,0,0,0,0,0,0,0,0,0,0,BV79,0,0,0,0,0,0,0,0,0,0,0,0,0,0,0)';
      PINUSE='POWER';
      NO_LOAD_CHECK='Both';
      NO_IO_CHECK='Both';
      NO_ASSERT_CHECK='TRUE';
      NO_DIR_CHECK='TRUE';
      ALLOW_CONNECT='TRUE';
    'VCCIN160':
      PIN_NUMBER='(0,0,0,0,0,0,0,0,0,0,0,0,0,0,0,0,0,0,0,0,0,0,0,0,0,0,BV77,0,0,0,0,0,0,0,0,0,0,0,0,0,0,0)';
      PINUSE='POWER';
      NO_LOAD_CHECK='Both';
      NO_IO_CHECK='Both';
      NO_ASSERT_CHECK='TRUE';
      NO_DIR_CHECK='TRUE';
      ALLOW_CONNECT='TRUE';
    'VCCIN159':
      PIN_NUMBER='(0,0,0,0,0,0,0,0,0,0,0,0,0,0,0,0,0,0,0,0,0,0,0,0,0,0,BV75,0,0,0,0,0,0,0,0,0,0,0,0,0,0,0)';
      PINUSE='POWER';
      NO_LOAD_CHECK='Both';
      NO_IO_CHECK='Both';
      NO_ASSERT_CHECK='TRUE';
      NO_DIR_CHECK='TRUE';
      ALLOW_CONNECT='TRUE';
    'VCCIN158':
      PIN_NUMBER='(0,0,0,0,0,0,0,0,0,0,0,0,0,0,0,0,0,0,0,0,0,0,0,0,0,0,BV73,0,0,0,0,0,0,0,0,0,0,0,0,0,0,0)';
      PINUSE='POWER';
      NO_LOAD_CHECK='Both';
      NO_IO_CHECK='Both';
      NO_ASSERT_CHECK='TRUE';
      NO_DIR_CHECK='TRUE';
      ALLOW_CONNECT='TRUE';
    'VCCIN157':
      PIN_NUMBER='(0,0,0,0,0,0,0,0,0,0,0,0,0,0,0,0,0,0,0,0,0,0,0,0,0,0,BV71,0,0,0,0,0,0,0,0,0,0,0,0,0,0,0)';
      PINUSE='POWER';
      NO_LOAD_CHECK='Both';
      NO_IO_CHECK='Both';
      NO_ASSERT_CHECK='TRUE';
      NO_DIR_CHECK='TRUE';
      ALLOW_CONNECT='TRUE';
    'VCCIN156':
      PIN_NUMBER='(0,0,0,0,0,0,0,0,0,0,0,0,0,0,0,0,0,0,0,0,0,0,0,0,0,0,BV69,0,0,0,0,0,0,0,0,0,0,0,0,0,0,0)';
      PINUSE='POWER';
      NO_LOAD_CHECK='Both';
      NO_IO_CHECK='Both';
      NO_ASSERT_CHECK='TRUE';
      NO_DIR_CHECK='TRUE';
      ALLOW_CONNECT='TRUE';
    'VCCIN155':
      PIN_NUMBER='(0,0,0,0,0,0,0,0,0,0,0,0,0,0,0,0,0,0,0,0,0,0,0,0,0,0,BV67,0,0,0,0,0,0,0,0,0,0,0,0,0,0,0)';
      PINUSE='POWER';
      NO_LOAD_CHECK='Both';
      NO_IO_CHECK='Both';
      NO_ASSERT_CHECK='TRUE';
      NO_DIR_CHECK='TRUE';
      ALLOW_CONNECT='TRUE';
    'VCCIN154':
      PIN_NUMBER='(0,0,0,0,0,0,0,0,0,0,0,0,0,0,0,0,0,0,0,0,0,0,0,0,0,0,BV65,0,0,0,0,0,0,0,0,0,0,0,0,0,0,0)';
      PINUSE='POWER';
      NO_LOAD_CHECK='Both';
      NO_IO_CHECK='Both';
      NO_ASSERT_CHECK='TRUE';
      NO_DIR_CHECK='TRUE';
      ALLOW_CONNECT='TRUE';
    'VCCIN153':
      PIN_NUMBER='(0,0,0,0,0,0,0,0,0,0,0,0,0,0,0,0,0,0,0,0,0,0,0,0,0,0,BV63,0,0,0,0,0,0,0,0,0,0,0,0,0,0,0)';
      PINUSE='POWER';
      NO_LOAD_CHECK='Both';
      NO_IO_CHECK='Both';
      NO_ASSERT_CHECK='TRUE';
      NO_DIR_CHECK='TRUE';
      ALLOW_CONNECT='TRUE';
    'VCCIN152':
      PIN_NUMBER='(0,0,0,0,0,0,0,0,0,0,0,0,0,0,0,0,0,0,0,0,0,0,0,0,0,0,BV61,0,0,0,0,0,0,0,0,0,0,0,0,0,0,0)';
      PINUSE='POWER';
      NO_LOAD_CHECK='Both';
      NO_IO_CHECK='Both';
      NO_ASSERT_CHECK='TRUE';
      NO_DIR_CHECK='TRUE';
      ALLOW_CONNECT='TRUE';
    'VCCIN151':
      PIN_NUMBER='(0,0,0,0,0,0,0,0,0,0,0,0,0,0,0,0,0,0,0,0,0,0,0,0,0,0,BV59,0,0,0,0,0,0,0,0,0,0,0,0,0,0,0)';
      PINUSE='POWER';
      NO_LOAD_CHECK='Both';
      NO_IO_CHECK='Both';
      NO_ASSERT_CHECK='TRUE';
      NO_DIR_CHECK='TRUE';
      ALLOW_CONNECT='TRUE';
    'VCCIN150':
      PIN_NUMBER='(0,0,0,0,0,0,0,0,0,0,0,0,0,0,0,0,0,0,0,0,0,0,0,0,0,0,BV57,0,0,0,0,0,0,0,0,0,0,0,0,0,0,0)';
      PINUSE='POWER';
      NO_LOAD_CHECK='Both';
      NO_IO_CHECK='Both';
      NO_ASSERT_CHECK='TRUE';
      NO_DIR_CHECK='TRUE';
      ALLOW_CONNECT='TRUE';
    'VCCIN149':
      PIN_NUMBER='(0,0,0,0,0,0,0,0,0,0,0,0,0,0,0,0,0,0,0,0,0,0,0,0,0,0,BV55,0,0,0,0,0,0,0,0,0,0,0,0,0,0,0)';
      PINUSE='POWER';
      NO_LOAD_CHECK='Both';
      NO_IO_CHECK='Both';
      NO_ASSERT_CHECK='TRUE';
      NO_DIR_CHECK='TRUE';
      ALLOW_CONNECT='TRUE';
    'VCCIN148':
      PIN_NUMBER='(0,0,0,0,0,0,0,0,0,0,0,0,0,0,0,0,0,0,0,0,0,0,0,0,0,0,BV53,0,0,0,0,0,0,0,0,0,0,0,0,0,0,0)';
      PINUSE='POWER';
      NO_LOAD_CHECK='Both';
      NO_IO_CHECK='Both';
      NO_ASSERT_CHECK='TRUE';
      NO_DIR_CHECK='TRUE';
      ALLOW_CONNECT='TRUE';
    'VCCIN147':
      PIN_NUMBER='(0,0,0,0,0,0,0,0,0,0,0,0,0,0,0,0,0,0,0,0,0,0,0,0,0,0,BV51,0,0,0,0,0,0,0,0,0,0,0,0,0,0,0)';
      PINUSE='POWER';
      NO_LOAD_CHECK='Both';
      NO_IO_CHECK='Both';
      NO_ASSERT_CHECK='TRUE';
      NO_DIR_CHECK='TRUE';
      ALLOW_CONNECT='TRUE';
    'VCCIN146':
      PIN_NUMBER='(0,0,0,0,0,0,0,0,0,0,0,0,0,0,0,0,0,0,0,0,0,0,0,0,0,0,BV49,0,0,0,0,0,0,0,0,0,0,0,0,0,0,0)';
      PINUSE='POWER';
      NO_LOAD_CHECK='Both';
      NO_IO_CHECK='Both';
      NO_ASSERT_CHECK='TRUE';
      NO_DIR_CHECK='TRUE';
      ALLOW_CONNECT='TRUE';
    'VCCIN145':
      PIN_NUMBER='(0,0,0,0,0,0,0,0,0,0,0,0,0,0,0,0,0,0,0,0,0,0,0,0,0,0,BV47,0,0,0,0,0,0,0,0,0,0,0,0,0,0,0)';
      PINUSE='POWER';
      NO_LOAD_CHECK='Both';
      NO_IO_CHECK='Both';
      NO_ASSERT_CHECK='TRUE';
      NO_DIR_CHECK='TRUE';
      ALLOW_CONNECT='TRUE';
    'VCCIN144':
      PIN_NUMBER='(0,0,0,0,0,0,0,0,0,0,0,0,0,0,0,0,0,0,0,0,0,0,0,0,0,0,BV44,0,0,0,0,0,0,0,0,0,0,0,0,0,0,0)';
      PINUSE='POWER';
      NO_LOAD_CHECK='Both';
      NO_IO_CHECK='Both';
      NO_ASSERT_CHECK='TRUE';
      NO_DIR_CHECK='TRUE';
      ALLOW_CONNECT='TRUE';
    'VCCIN143':
      PIN_NUMBER='(0,0,0,0,0,0,0,0,0,0,0,0,0,0,0,0,0,0,0,0,0,0,0,0,0,0,BV42,0,0,0,0,0,0,0,0,0,0,0,0,0,0,0)';
      PINUSE='POWER';
      NO_LOAD_CHECK='Both';
      NO_IO_CHECK='Both';
      NO_ASSERT_CHECK='TRUE';
      NO_DIR_CHECK='TRUE';
      ALLOW_CONNECT='TRUE';
    'VCCIN142':
      PIN_NUMBER='(0,0,0,0,0,0,0,0,0,0,0,0,0,0,0,0,0,0,0,0,0,0,0,0,0,0,BV40,0,0,0,0,0,0,0,0,0,0,0,0,0,0,0)';
      PINUSE='POWER';
      NO_LOAD_CHECK='Both';
      NO_IO_CHECK='Both';
      NO_ASSERT_CHECK='TRUE';
      NO_DIR_CHECK='TRUE';
      ALLOW_CONNECT='TRUE';
    'VCCIN141':
      PIN_NUMBER='(0,0,0,0,0,0,0,0,0,0,0,0,0,0,0,0,0,0,0,0,0,0,0,0,0,0,BV38,0,0,0,0,0,0,0,0,0,0,0,0,0,0,0)';
      PINUSE='POWER';
      NO_LOAD_CHECK='Both';
      NO_IO_CHECK='Both';
      NO_ASSERT_CHECK='TRUE';
      NO_DIR_CHECK='TRUE';
      ALLOW_CONNECT='TRUE';
    'VCCIN140':
      PIN_NUMBER='(0,0,0,0,0,0,0,0,0,0,0,0,0,0,0,0,0,0,0,0,0,0,0,0,0,0,BV36,0,0,0,0,0,0,0,0,0,0,0,0,0,0,0)';
      PINUSE='POWER';
      NO_LOAD_CHECK='Both';
      NO_IO_CHECK='Both';
      NO_ASSERT_CHECK='TRUE';
      NO_DIR_CHECK='TRUE';
      ALLOW_CONNECT='TRUE';
    'VCCIN139':
      PIN_NUMBER='(0,0,0,0,0,0,0,0,0,0,0,0,0,0,0,0,0,0,0,0,0,0,0,0,0,0,BV34,0,0,0,0,0,0,0,0,0,0,0,0,0,0,0)';
      PINUSE='POWER';
      NO_LOAD_CHECK='Both';
      NO_IO_CHECK='Both';
      NO_ASSERT_CHECK='TRUE';
      NO_DIR_CHECK='TRUE';
      ALLOW_CONNECT='TRUE';
    'VCCIN138':
      PIN_NUMBER='(0,0,0,0,0,0,0,0,0,0,0,0,0,0,0,0,0,0,0,0,0,0,0,0,0,0,BV32,0,0,0,0,0,0,0,0,0,0,0,0,0,0,0)';
      PINUSE='POWER';
      NO_LOAD_CHECK='Both';
      NO_IO_CHECK='Both';
      NO_ASSERT_CHECK='TRUE';
      NO_DIR_CHECK='TRUE';
      ALLOW_CONNECT='TRUE';
    'VCCIN137':
      PIN_NUMBER='(0,0,0,0,0,0,0,0,0,0,0,0,0,0,0,0,0,0,0,0,0,0,0,0,0,0,BU90,0,0,0,0,0,0,0,0,0,0,0,0,0,0,0)';
      PINUSE='POWER';
      NO_LOAD_CHECK='Both';
      NO_IO_CHECK='Both';
      NO_ASSERT_CHECK='TRUE';
      NO_DIR_CHECK='TRUE';
      ALLOW_CONNECT='TRUE';
    'VCCIN136':
      PIN_NUMBER='(0,0,0,0,0,0,0,0,0,0,0,0,0,0,0,0,0,0,0,0,0,0,0,0,0,0,BU88,0,0,0,0,0,0,0,0,0,0,0,0,0,0,0)';
      PINUSE='POWER';
      NO_LOAD_CHECK='Both';
      NO_IO_CHECK='Both';
      NO_ASSERT_CHECK='TRUE';
      NO_DIR_CHECK='TRUE';
      ALLOW_CONNECT='TRUE';
    'VCCIN135':
      PIN_NUMBER='(0,0,0,0,0,0,0,0,0,0,0,0,0,0,0,0,0,0,0,0,0,0,0,0,0,0,BU86,0,0,0,0,0,0,0,0,0,0,0,0,0,0,0)';
      PINUSE='POWER';
      NO_LOAD_CHECK='Both';
      NO_IO_CHECK='Both';
      NO_ASSERT_CHECK='TRUE';
      NO_DIR_CHECK='TRUE';
      ALLOW_CONNECT='TRUE';
    'VCCIN134':
      PIN_NUMBER='(0,0,0,0,0,0,0,0,0,0,0,0,0,0,0,0,0,0,0,0,0,0,0,0,0,0,BU84,0,0,0,0,0,0,0,0,0,0,0,0,0,0,0)';
      PINUSE='POWER';
      NO_LOAD_CHECK='Both';
      NO_IO_CHECK='Both';
      NO_ASSERT_CHECK='TRUE';
      NO_DIR_CHECK='TRUE';
      ALLOW_CONNECT='TRUE';
    'VCCIN133':
      PIN_NUMBER='(0,0,0,0,0,0,0,0,0,0,0,0,0,0,0,0,0,0,0,0,0,0,0,0,0,0,BU82,0,0,0,0,0,0,0,0,0,0,0,0,0,0,0)';
      PINUSE='POWER';
      NO_LOAD_CHECK='Both';
      NO_IO_CHECK='Both';
      NO_ASSERT_CHECK='TRUE';
      NO_DIR_CHECK='TRUE';
      ALLOW_CONNECT='TRUE';
    'VCCIN132':
      PIN_NUMBER='(0,0,0,0,0,0,0,0,0,0,0,0,0,0,0,0,0,0,0,0,0,0,0,0,0,0,BU80,0,0,0,0,0,0,0,0,0,0,0,0,0,0,0)';
      PINUSE='POWER';
      NO_LOAD_CHECK='Both';
      NO_IO_CHECK='Both';
      NO_ASSERT_CHECK='TRUE';
      NO_DIR_CHECK='TRUE';
      ALLOW_CONNECT='TRUE';
    'VCCIN131':
      PIN_NUMBER='(0,0,0,0,0,0,0,0,0,0,0,0,0,0,0,0,0,0,0,0,0,0,0,0,0,0,BU78,0,0,0,0,0,0,0,0,0,0,0,0,0,0,0)';
      PINUSE='POWER';
      NO_LOAD_CHECK='Both';
      NO_IO_CHECK='Both';
      NO_ASSERT_CHECK='TRUE';
      NO_DIR_CHECK='TRUE';
      ALLOW_CONNECT='TRUE';
    'VCCIN130':
      PIN_NUMBER='(0,0,0,0,0,0,0,0,0,0,0,0,0,0,0,0,0,0,0,0,0,0,0,0,0,0,BU76,0,0,0,0,0,0,0,0,0,0,0,0,0,0,0)';
      PINUSE='POWER';
      NO_LOAD_CHECK='Both';
      NO_IO_CHECK='Both';
      NO_ASSERT_CHECK='TRUE';
      NO_DIR_CHECK='TRUE';
      ALLOW_CONNECT='TRUE';
    'VCCIN129':
      PIN_NUMBER='(0,0,0,0,0,0,0,0,0,0,0,0,0,0,0,0,0,0,0,0,0,0,0,0,0,0,BU74,0,0,0,0,0,0,0,0,0,0,0,0,0,0,0)';
      PINUSE='POWER';
      NO_LOAD_CHECK='Both';
      NO_IO_CHECK='Both';
      NO_ASSERT_CHECK='TRUE';
      NO_DIR_CHECK='TRUE';
      ALLOW_CONNECT='TRUE';
    'VCCIN128':
      PIN_NUMBER='(0,0,0,0,0,0,0,0,0,0,0,0,0,0,0,0,0,0,0,0,0,0,0,0,0,0,BU72,0,0,0,0,0,0,0,0,0,0,0,0,0,0,0)';
      PINUSE='POWER';
      NO_LOAD_CHECK='Both';
      NO_IO_CHECK='Both';
      NO_ASSERT_CHECK='TRUE';
      NO_DIR_CHECK='TRUE';
      ALLOW_CONNECT='TRUE';
    'VCCIN127':
      PIN_NUMBER='(0,0,0,0,0,0,0,0,0,0,0,0,0,0,0,0,0,0,0,0,0,0,0,0,0,0,BU70,0,0,0,0,0,0,0,0,0,0,0,0,0,0,0)';
      PINUSE='POWER';
      NO_LOAD_CHECK='Both';
      NO_IO_CHECK='Both';
      NO_ASSERT_CHECK='TRUE';
      NO_DIR_CHECK='TRUE';
      ALLOW_CONNECT='TRUE';
    'VCCIN126':
      PIN_NUMBER='(0,0,0,0,0,0,0,0,0,0,0,0,0,0,0,0,0,0,0,0,0,0,0,0,0,0,BU68,0,0,0,0,0,0,0,0,0,0,0,0,0,0,0)';
      PINUSE='POWER';
      NO_LOAD_CHECK='Both';
      NO_IO_CHECK='Both';
      NO_ASSERT_CHECK='TRUE';
      NO_DIR_CHECK='TRUE';
      ALLOW_CONNECT='TRUE';
    'VCCIN125':
      PIN_NUMBER='(0,0,0,0,0,0,0,0,0,0,0,0,0,0,0,0,0,0,0,0,0,0,0,0,0,0,BU66,0,0,0,0,0,0,0,0,0,0,0,0,0,0,0)';
      PINUSE='POWER';
      NO_LOAD_CHECK='Both';
      NO_IO_CHECK='Both';
      NO_ASSERT_CHECK='TRUE';
      NO_DIR_CHECK='TRUE';
      ALLOW_CONNECT='TRUE';
    'VCCIN124':
      PIN_NUMBER='(0,0,0,0,0,0,0,0,0,0,0,0,0,0,0,0,0,0,0,0,0,0,0,0,0,0,BU64,0,0,0,0,0,0,0,0,0,0,0,0,0,0,0)';
      PINUSE='POWER';
      NO_LOAD_CHECK='Both';
      NO_IO_CHECK='Both';
      NO_ASSERT_CHECK='TRUE';
      NO_DIR_CHECK='TRUE';
      ALLOW_CONNECT='TRUE';
    'VCCIN123':
      PIN_NUMBER='(0,0,0,0,0,0,0,0,0,0,0,0,0,0,0,0,0,0,0,0,0,0,0,0,0,0,BU62,0,0,0,0,0,0,0,0,0,0,0,0,0,0,0)';
      PINUSE='POWER';
      NO_LOAD_CHECK='Both';
      NO_IO_CHECK='Both';
      NO_ASSERT_CHECK='TRUE';
      NO_DIR_CHECK='TRUE';
      ALLOW_CONNECT='TRUE';
    'VCCIN122':
      PIN_NUMBER='(0,0,0,0,0,0,0,0,0,0,0,0,0,0,0,0,0,0,0,0,0,0,0,0,0,0,BU60,0,0,0,0,0,0,0,0,0,0,0,0,0,0,0)';
      PINUSE='POWER';
      NO_LOAD_CHECK='Both';
      NO_IO_CHECK='Both';
      NO_ASSERT_CHECK='TRUE';
      NO_DIR_CHECK='TRUE';
      ALLOW_CONNECT='TRUE';
    'VCCIN121':
      PIN_NUMBER='(0,0,0,0,0,0,0,0,0,0,0,0,0,0,0,0,0,0,0,0,0,0,0,0,0,0,BU58,0,0,0,0,0,0,0,0,0,0,0,0,0,0,0)';
      PINUSE='POWER';
      NO_LOAD_CHECK='Both';
      NO_IO_CHECK='Both';
      NO_ASSERT_CHECK='TRUE';
      NO_DIR_CHECK='TRUE';
      ALLOW_CONNECT='TRUE';
    'VCCIN120':
      PIN_NUMBER='(0,0,0,0,0,0,0,0,0,0,0,0,0,0,0,0,0,0,0,0,0,0,0,0,0,0,BU56,0,0,0,0,0,0,0,0,0,0,0,0,0,0,0)';
      PINUSE='POWER';
      NO_LOAD_CHECK='Both';
      NO_IO_CHECK='Both';
      NO_ASSERT_CHECK='TRUE';
      NO_DIR_CHECK='TRUE';
      ALLOW_CONNECT='TRUE';
    'VCCIN119':
      PIN_NUMBER='(0,0,0,0,0,0,0,0,0,0,0,0,0,0,0,0,0,0,0,0,0,0,0,0,0,0,BU54,0,0,0,0,0,0,0,0,0,0,0,0,0,0,0)';
      PINUSE='POWER';
      NO_LOAD_CHECK='Both';
      NO_IO_CHECK='Both';
      NO_ASSERT_CHECK='TRUE';
      NO_DIR_CHECK='TRUE';
      ALLOW_CONNECT='TRUE';
    'VCCIN118':
      PIN_NUMBER='(0,0,0,0,0,0,0,0,0,0,0,0,0,0,0,0,0,0,0,0,0,0,0,0,0,0,BU52,0,0,0,0,0,0,0,0,0,0,0,0,0,0,0)';
      PINUSE='POWER';
      NO_LOAD_CHECK='Both';
      NO_IO_CHECK='Both';
      NO_ASSERT_CHECK='TRUE';
      NO_DIR_CHECK='TRUE';
      ALLOW_CONNECT='TRUE';
    'VCCIN117':
      PIN_NUMBER='(0,0,0,0,0,0,0,0,0,0,0,0,0,0,0,0,0,0,0,0,0,0,0,0,0,0,BU50,0,0,0,0,0,0,0,0,0,0,0,0,0,0,0)';
      PINUSE='POWER';
      NO_LOAD_CHECK='Both';
      NO_IO_CHECK='Both';
      NO_ASSERT_CHECK='TRUE';
      NO_DIR_CHECK='TRUE';
      ALLOW_CONNECT='TRUE';
    'VCCIN116':
      PIN_NUMBER='(0,0,0,0,0,0,0,0,0,0,0,0,0,0,0,0,0,0,0,0,0,0,0,0,0,0,BU48,0,0,0,0,0,0,0,0,0,0,0,0,0,0,0)';
      PINUSE='POWER';
      NO_LOAD_CHECK='Both';
      NO_IO_CHECK='Both';
      NO_ASSERT_CHECK='TRUE';
      NO_DIR_CHECK='TRUE';
      ALLOW_CONNECT='TRUE';
    'VCCIN115':
      PIN_NUMBER='(0,0,0,0,0,0,0,0,0,0,0,0,0,0,0,0,0,0,0,0,0,0,0,0,0,0,BU45,0,0,0,0,0,0,0,0,0,0,0,0,0,0,0)';
      PINUSE='POWER';
      NO_LOAD_CHECK='Both';
      NO_IO_CHECK='Both';
      NO_ASSERT_CHECK='TRUE';
      NO_DIR_CHECK='TRUE';
      ALLOW_CONNECT='TRUE';
    'VCCIN114':
      PIN_NUMBER='(0,0,0,0,0,0,0,0,0,0,0,0,0,0,0,0,0,0,0,0,0,0,0,0,0,0,BU43,0,0,0,0,0,0,0,0,0,0,0,0,0,0,0)';
      PINUSE='POWER';
      NO_LOAD_CHECK='Both';
      NO_IO_CHECK='Both';
      NO_ASSERT_CHECK='TRUE';
      NO_DIR_CHECK='TRUE';
      ALLOW_CONNECT='TRUE';
    'VCCIN113':
      PIN_NUMBER='(0,0,0,0,0,0,0,0,0,0,0,0,0,0,0,0,0,0,0,0,0,0,0,0,0,0,BU41,0,0,0,0,0,0,0,0,0,0,0,0,0,0,0)';
      PINUSE='POWER';
      NO_LOAD_CHECK='Both';
      NO_IO_CHECK='Both';
      NO_ASSERT_CHECK='TRUE';
      NO_DIR_CHECK='TRUE';
      ALLOW_CONNECT='TRUE';
    'VCCIN112':
      PIN_NUMBER='(0,0,0,0,0,0,0,0,0,0,0,0,0,0,0,0,0,0,0,0,0,0,0,0,0,0,BU39,0,0,0,0,0,0,0,0,0,0,0,0,0,0,0)';
      PINUSE='POWER';
      NO_LOAD_CHECK='Both';
      NO_IO_CHECK='Both';
      NO_ASSERT_CHECK='TRUE';
      NO_DIR_CHECK='TRUE';
      ALLOW_CONNECT='TRUE';
    'VCCIN111':
      PIN_NUMBER='(0,0,0,0,0,0,0,0,0,0,0,0,0,0,0,0,0,0,0,0,0,0,0,0,0,0,BU37,0,0,0,0,0,0,0,0,0,0,0,0,0,0,0)';
      PINUSE='POWER';
      NO_LOAD_CHECK='Both';
      NO_IO_CHECK='Both';
      NO_ASSERT_CHECK='TRUE';
      NO_DIR_CHECK='TRUE';
      ALLOW_CONNECT='TRUE';
    'VCCIN110':
      PIN_NUMBER='(0,0,0,0,0,0,0,0,0,0,0,0,0,0,0,0,0,0,0,0,0,0,0,0,0,0,BU35,0,0,0,0,0,0,0,0,0,0,0,0,0,0,0)';
      PINUSE='POWER';
      NO_LOAD_CHECK='Both';
      NO_IO_CHECK='Both';
      NO_ASSERT_CHECK='TRUE';
      NO_DIR_CHECK='TRUE';
      ALLOW_CONNECT='TRUE';
    'VCCIN109':
      PIN_NUMBER='(0,0,0,0,0,0,0,0,0,0,0,0,0,0,0,0,0,0,0,0,0,0,0,0,0,0,BU33,0,0,0,0,0,0,0,0,0,0,0,0,0,0,0)';
      PINUSE='POWER';
      NO_LOAD_CHECK='Both';
      NO_IO_CHECK='Both';
      NO_ASSERT_CHECK='TRUE';
      NO_DIR_CHECK='TRUE';
      ALLOW_CONNECT='TRUE';
    'VCCIN108':
      PIN_NUMBER='(0,0,0,0,0,0,0,0,0,0,0,0,0,0,0,0,0,0,0,0,0,0,0,0,0,0,BT89,0,0,0,0,0,0,0,0,0,0,0,0,0,0,0)';
      PINUSE='POWER';
      NO_LOAD_CHECK='Both';
      NO_IO_CHECK='Both';
      NO_ASSERT_CHECK='TRUE';
      NO_DIR_CHECK='TRUE';
      ALLOW_CONNECT='TRUE';
    'VCCIN107':
      PIN_NUMBER='(0,0,0,0,0,0,0,0,0,0,0,0,0,0,0,0,0,0,0,0,0,0,0,0,0,0,BT87,0,0,0,0,0,0,0,0,0,0,0,0,0,0,0)';
      PINUSE='POWER';
      NO_LOAD_CHECK='Both';
      NO_IO_CHECK='Both';
      NO_ASSERT_CHECK='TRUE';
      NO_DIR_CHECK='TRUE';
      ALLOW_CONNECT='TRUE';
    'VCCIN106':
      PIN_NUMBER='(0,0,0,0,0,0,0,0,0,0,0,0,0,0,0,0,0,0,0,0,0,0,0,0,0,0,BT85,0,0,0,0,0,0,0,0,0,0,0,0,0,0,0)';
      PINUSE='POWER';
      NO_LOAD_CHECK='Both';
      NO_IO_CHECK='Both';
      NO_ASSERT_CHECK='TRUE';
      NO_DIR_CHECK='TRUE';
      ALLOW_CONNECT='TRUE';
    'VCCIN105':
      PIN_NUMBER='(0,0,0,0,0,0,0,0,0,0,0,0,0,0,0,0,0,0,0,0,0,0,0,0,0,0,BT83,0,0,0,0,0,0,0,0,0,0,0,0,0,0,0)';
      PINUSE='POWER';
      NO_LOAD_CHECK='Both';
      NO_IO_CHECK='Both';
      NO_ASSERT_CHECK='TRUE';
      NO_DIR_CHECK='TRUE';
      ALLOW_CONNECT='TRUE';
    'VCCIN104':
      PIN_NUMBER='(0,0,0,0,0,0,0,0,0,0,0,0,0,0,0,0,0,0,0,0,0,0,0,0,0,0,BT81,0,0,0,0,0,0,0,0,0,0,0,0,0,0,0)';
      PINUSE='POWER';
      NO_LOAD_CHECK='Both';
      NO_IO_CHECK='Both';
      NO_ASSERT_CHECK='TRUE';
      NO_DIR_CHECK='TRUE';
      ALLOW_CONNECT='TRUE';
    'VCCIN103':
      PIN_NUMBER='(0,0,0,0,0,0,0,0,0,0,0,0,0,0,0,0,0,0,0,0,0,0,0,0,0,0,BT79,0,0,0,0,0,0,0,0,0,0,0,0,0,0,0)';
      PINUSE='POWER';
      NO_LOAD_CHECK='Both';
      NO_IO_CHECK='Both';
      NO_ASSERT_CHECK='TRUE';
      NO_DIR_CHECK='TRUE';
      ALLOW_CONNECT='TRUE';
    'VCCIN102':
      PIN_NUMBER='(0,0,0,0,0,0,0,0,0,0,0,0,0,0,0,0,0,0,0,0,0,0,0,0,0,0,BT77,0,0,0,0,0,0,0,0,0,0,0,0,0,0,0)';
      PINUSE='POWER';
      NO_LOAD_CHECK='Both';
      NO_IO_CHECK='Both';
      NO_ASSERT_CHECK='TRUE';
      NO_DIR_CHECK='TRUE';
      ALLOW_CONNECT='TRUE';
    'VCCIN101':
      PIN_NUMBER='(0,0,0,0,0,0,0,0,0,0,0,0,0,0,0,0,0,0,0,0,0,0,0,0,0,0,BT75,0,0,0,0,0,0,0,0,0,0,0,0,0,0,0)';
      PINUSE='POWER';
      NO_LOAD_CHECK='Both';
      NO_IO_CHECK='Both';
      NO_ASSERT_CHECK='TRUE';
      NO_DIR_CHECK='TRUE';
      ALLOW_CONNECT='TRUE';
    'VCCIN100':
      PIN_NUMBER='(0,0,0,0,0,0,0,0,0,0,0,0,0,0,0,0,0,0,0,0,0,0,0,0,0,0,BT73,0,0,0,0,0,0,0,0,0,0,0,0,0,0,0)';
      PINUSE='POWER';
      NO_LOAD_CHECK='Both';
      NO_IO_CHECK='Both';
      NO_ASSERT_CHECK='TRUE';
      NO_DIR_CHECK='TRUE';
      ALLOW_CONNECT='TRUE';
    'VCCIN99':
      PIN_NUMBER='(0,0,0,0,0,0,0,0,0,0,0,0,0,0,0,0,0,0,0,0,0,0,0,0,0,0,BT71,0,0,0,0,0,0,0,0,0,0,0,0,0,0,0)';
      PINUSE='POWER';
      NO_LOAD_CHECK='Both';
      NO_IO_CHECK='Both';
      NO_ASSERT_CHECK='TRUE';
      NO_DIR_CHECK='TRUE';
      ALLOW_CONNECT='TRUE';
    'VCCIN98':
      PIN_NUMBER='(0,0,0,0,0,0,0,0,0,0,0,0,0,0,0,0,0,0,0,0,0,0,0,0,0,0,BT69,0,0,0,0,0,0,0,0,0,0,0,0,0,0,0)';
      PINUSE='POWER';
      NO_LOAD_CHECK='Both';
      NO_IO_CHECK='Both';
      NO_ASSERT_CHECK='TRUE';
      NO_DIR_CHECK='TRUE';
      ALLOW_CONNECT='TRUE';
    'VCCIN97':
      PIN_NUMBER='(0,0,0,0,0,0,0,0,0,0,0,0,0,0,0,0,0,0,0,0,0,0,0,0,0,0,BT67,0,0,0,0,0,0,0,0,0,0,0,0,0,0,0)';
      PINUSE='POWER';
      NO_LOAD_CHECK='Both';
      NO_IO_CHECK='Both';
      NO_ASSERT_CHECK='TRUE';
      NO_DIR_CHECK='TRUE';
      ALLOW_CONNECT='TRUE';
    'VCCIN96':
      PIN_NUMBER='(0,0,0,0,0,0,0,0,0,0,0,0,0,0,0,0,0,0,0,0,0,0,0,0,0,0,BT65,0,0,0,0,0,0,0,0,0,0,0,0,0,0,0)';
      PINUSE='POWER';
      NO_LOAD_CHECK='Both';
      NO_IO_CHECK='Both';
      NO_ASSERT_CHECK='TRUE';
      NO_DIR_CHECK='TRUE';
      ALLOW_CONNECT='TRUE';
    'VCCIN95':
      PIN_NUMBER='(0,0,0,0,0,0,0,0,0,0,0,0,0,0,0,0,0,0,0,0,0,0,0,0,0,0,BT63,0,0,0,0,0,0,0,0,0,0,0,0,0,0,0)';
      PINUSE='POWER';
      NO_LOAD_CHECK='Both';
      NO_IO_CHECK='Both';
      NO_ASSERT_CHECK='TRUE';
      NO_DIR_CHECK='TRUE';
      ALLOW_CONNECT='TRUE';
    'VCCIN94':
      PIN_NUMBER='(0,0,0,0,0,0,0,0,0,0,0,0,0,0,0,0,0,0,0,0,0,0,0,0,0,0,BT61,0,0,0,0,0,0,0,0,0,0,0,0,0,0,0)';
      PINUSE='POWER';
      NO_LOAD_CHECK='Both';
      NO_IO_CHECK='Both';
      NO_ASSERT_CHECK='TRUE';
      NO_DIR_CHECK='TRUE';
      ALLOW_CONNECT='TRUE';
    'VCCIN93':
      PIN_NUMBER='(0,0,0,0,0,0,0,0,0,0,0,0,0,0,0,0,0,0,0,0,0,0,0,0,0,0,BT59,0,0,0,0,0,0,0,0,0,0,0,0,0,0,0)';
      PINUSE='POWER';
      NO_LOAD_CHECK='Both';
      NO_IO_CHECK='Both';
      NO_ASSERT_CHECK='TRUE';
      NO_DIR_CHECK='TRUE';
      ALLOW_CONNECT='TRUE';
    'VCCIN92':
      PIN_NUMBER='(0,0,0,0,0,0,0,0,0,0,0,0,0,0,0,0,0,0,0,0,0,0,0,0,0,0,BT57,0,0,0,0,0,0,0,0,0,0,0,0,0,0,0)';
      PINUSE='POWER';
      NO_LOAD_CHECK='Both';
      NO_IO_CHECK='Both';
      NO_ASSERT_CHECK='TRUE';
      NO_DIR_CHECK='TRUE';
      ALLOW_CONNECT='TRUE';
    'VCCIN91':
      PIN_NUMBER='(0,0,0,0,0,0,0,0,0,0,0,0,0,0,0,0,0,0,0,0,0,0,0,0,0,0,BT55,0,0,0,0,0,0,0,0,0,0,0,0,0,0,0)';
      PINUSE='POWER';
      NO_LOAD_CHECK='Both';
      NO_IO_CHECK='Both';
      NO_ASSERT_CHECK='TRUE';
      NO_DIR_CHECK='TRUE';
      ALLOW_CONNECT='TRUE';
    'VCCIN90':
      PIN_NUMBER='(0,0,0,0,0,0,0,0,0,0,0,0,0,0,0,0,0,0,0,0,0,0,0,0,0,0,BT53,0,0,0,0,0,0,0,0,0,0,0,0,0,0,0)';
      PINUSE='POWER';
      NO_LOAD_CHECK='Both';
      NO_IO_CHECK='Both';
      NO_ASSERT_CHECK='TRUE';
      NO_DIR_CHECK='TRUE';
      ALLOW_CONNECT='TRUE';
    'VCCIN89':
      PIN_NUMBER='(0,0,0,0,0,0,0,0,0,0,0,0,0,0,0,0,0,0,0,0,0,0,0,0,0,0,BT51,0,0,0,0,0,0,0,0,0,0,0,0,0,0,0)';
      PINUSE='POWER';
      NO_LOAD_CHECK='Both';
      NO_IO_CHECK='Both';
      NO_ASSERT_CHECK='TRUE';
      NO_DIR_CHECK='TRUE';
      ALLOW_CONNECT='TRUE';
    'VCCIN88':
      PIN_NUMBER='(0,0,0,0,0,0,0,0,0,0,0,0,0,0,0,0,0,0,0,0,0,0,0,0,0,0,BT49,0,0,0,0,0,0,0,0,0,0,0,0,0,0,0)';
      PINUSE='POWER';
      NO_LOAD_CHECK='Both';
      NO_IO_CHECK='Both';
      NO_ASSERT_CHECK='TRUE';
      NO_DIR_CHECK='TRUE';
      ALLOW_CONNECT='TRUE';
    'VCCIN87':
      PIN_NUMBER='(0,0,0,0,0,0,0,0,0,0,0,0,0,0,0,0,0,0,0,0,0,0,0,0,0,0,BT47,0,0,0,0,0,0,0,0,0,0,0,0,0,0,0)';
      PINUSE='POWER';
      NO_LOAD_CHECK='Both';
      NO_IO_CHECK='Both';
      NO_ASSERT_CHECK='TRUE';
      NO_DIR_CHECK='TRUE';
      ALLOW_CONNECT='TRUE';
    'VCCIN86':
      PIN_NUMBER='(0,0,0,0,0,0,0,0,0,0,0,0,0,0,0,0,0,0,0,0,0,0,0,0,0,0,BT44,0,0,0,0,0,0,0,0,0,0,0,0,0,0,0)';
      PINUSE='POWER';
      NO_LOAD_CHECK='Both';
      NO_IO_CHECK='Both';
      NO_ASSERT_CHECK='TRUE';
      NO_DIR_CHECK='TRUE';
      ALLOW_CONNECT='TRUE';
    'VCCIN85':
      PIN_NUMBER='(0,0,0,0,0,0,0,0,0,0,0,0,0,0,0,0,0,0,0,0,0,0,0,0,0,0,BT42,0,0,0,0,0,0,0,0,0,0,0,0,0,0,0)';
      PINUSE='POWER';
      NO_LOAD_CHECK='Both';
      NO_IO_CHECK='Both';
      NO_ASSERT_CHECK='TRUE';
      NO_DIR_CHECK='TRUE';
      ALLOW_CONNECT='TRUE';
    'VCCIN84':
      PIN_NUMBER='(0,0,0,0,0,0,0,0,0,0,0,0,0,0,0,0,0,0,0,0,0,0,0,0,0,0,BT40,0,0,0,0,0,0,0,0,0,0,0,0,0,0,0)';
      PINUSE='POWER';
      NO_LOAD_CHECK='Both';
      NO_IO_CHECK='Both';
      NO_ASSERT_CHECK='TRUE';
      NO_DIR_CHECK='TRUE';
      ALLOW_CONNECT='TRUE';
    'VCCIN83':
      PIN_NUMBER='(0,0,0,0,0,0,0,0,0,0,0,0,0,0,0,0,0,0,0,0,0,0,0,0,0,0,BT38,0,0,0,0,0,0,0,0,0,0,0,0,0,0,0)';
      PINUSE='POWER';
      NO_LOAD_CHECK='Both';
      NO_IO_CHECK='Both';
      NO_ASSERT_CHECK='TRUE';
      NO_DIR_CHECK='TRUE';
      ALLOW_CONNECT='TRUE';
    'VCCIN82':
      PIN_NUMBER='(0,0,0,0,0,0,0,0,0,0,0,0,0,0,0,0,0,0,0,0,0,0,0,0,0,0,BT36,0,0,0,0,0,0,0,0,0,0,0,0,0,0,0)';
      PINUSE='POWER';
      NO_LOAD_CHECK='Both';
      NO_IO_CHECK='Both';
      NO_ASSERT_CHECK='TRUE';
      NO_DIR_CHECK='TRUE';
      ALLOW_CONNECT='TRUE';
    'VCCIN81':
      PIN_NUMBER='(0,0,0,0,0,0,0,0,0,0,0,0,0,0,0,0,0,0,0,0,0,0,0,0,0,0,BT34,0,0,0,0,0,0,0,0,0,0,0,0,0,0,0)';
      PINUSE='POWER';
      NO_LOAD_CHECK='Both';
      NO_IO_CHECK='Both';
      NO_ASSERT_CHECK='TRUE';
      NO_DIR_CHECK='TRUE';
      ALLOW_CONNECT='TRUE';
    'VCCIN80':
      PIN_NUMBER='(0,0,0,0,0,0,0,0,0,0,0,0,0,0,0,0,0,0,0,0,0,0,0,0,0,0,BT32,0,0,0,0,0,0,0,0,0,0,0,0,0,0,0)';
      PINUSE='POWER';
      NO_LOAD_CHECK='Both';
      NO_IO_CHECK='Both';
      NO_ASSERT_CHECK='TRUE';
      NO_DIR_CHECK='TRUE';
      ALLOW_CONNECT='TRUE';
    'VCCIN79':
      PIN_NUMBER='(0,0,0,0,0,0,0,0,0,0,0,0,0,0,0,0,0,0,0,0,0,0,0,0,0,0,BR78,0,0,0,0,0,0,0,0,0,0,0,0,0,0,0)';
      PINUSE='POWER';
      NO_LOAD_CHECK='Both';
      NO_IO_CHECK='Both';
      NO_ASSERT_CHECK='TRUE';
      NO_DIR_CHECK='TRUE';
      ALLOW_CONNECT='TRUE';
    'VCCIN78':
      PIN_NUMBER='(0,0,0,0,0,0,0,0,0,0,0,0,0,0,0,0,0,0,0,0,0,0,0,0,0,0,BR62,0,0,0,0,0,0,0,0,0,0,0,0,0,0,0)';
      PINUSE='POWER';
      NO_LOAD_CHECK='Both';
      NO_IO_CHECK='Both';
      NO_ASSERT_CHECK='TRUE';
      NO_DIR_CHECK='TRUE';
      ALLOW_CONNECT='TRUE';
    'VCCIN77':
      PIN_NUMBER='(0,0,0,0,0,0,0,0,0,0,0,0,0,0,0,0,0,0,0,0,0,0,0,0,0,0,BR60,0,0,0,0,0,0,0,0,0,0,0,0,0,0,0)';
      PINUSE='POWER';
      NO_LOAD_CHECK='Both';
      NO_IO_CHECK='Both';
      NO_ASSERT_CHECK='TRUE';
      NO_DIR_CHECK='TRUE';
      ALLOW_CONNECT='TRUE';
    'VCCIN76':
      PIN_NUMBER='(0,0,0,0,0,0,0,0,0,0,0,0,0,0,0,0,0,0,0,0,0,0,0,0,0,0,BP89,0,0,0,0,0,0,0,0,0,0,0,0,0,0,0)';
      PINUSE='POWER';
      NO_LOAD_CHECK='Both';
      NO_IO_CHECK='Both';
      NO_ASSERT_CHECK='TRUE';
      NO_DIR_CHECK='TRUE';
      ALLOW_CONNECT='TRUE';
    'VCCIN75':
      PIN_NUMBER='(0,0,0,0,0,0,0,0,0,0,0,0,0,0,0,0,0,0,0,0,0,0,0,0,0,0,BP87,0,0,0,0,0,0,0,0,0,0,0,0,0,0,0)';
      PINUSE='POWER';
      NO_LOAD_CHECK='Both';
      NO_IO_CHECK='Both';
      NO_ASSERT_CHECK='TRUE';
      NO_DIR_CHECK='TRUE';
      ALLOW_CONNECT='TRUE';
    'VCCIN74':
      PIN_NUMBER='(0,0,0,0,0,0,0,0,0,0,0,0,0,0,0,0,0,0,0,0,0,0,0,0,0,0,BP85,0,0,0,0,0,0,0,0,0,0,0,0,0,0,0)';
      PINUSE='POWER';
      NO_LOAD_CHECK='Both';
      NO_IO_CHECK='Both';
      NO_ASSERT_CHECK='TRUE';
      NO_DIR_CHECK='TRUE';
      ALLOW_CONNECT='TRUE';
    'VCCIN73':
      PIN_NUMBER='(0,0,0,0,0,0,0,0,0,0,0,0,0,0,0,0,0,0,0,0,0,0,0,0,0,0,BP83,0,0,0,0,0,0,0,0,0,0,0,0,0,0,0)';
      PINUSE='POWER';
      NO_LOAD_CHECK='Both';
      NO_IO_CHECK='Both';
      NO_ASSERT_CHECK='TRUE';
      NO_DIR_CHECK='TRUE';
      ALLOW_CONNECT='TRUE';
    'VCCIN72':
      PIN_NUMBER='(0,0,0,0,0,0,0,0,0,0,0,0,0,0,0,0,0,0,0,0,0,0,0,0,0,0,BP81,0,0,0,0,0,0,0,0,0,0,0,0,0,0,0)';
      PINUSE='POWER';
      NO_LOAD_CHECK='Both';
      NO_IO_CHECK='Both';
      NO_ASSERT_CHECK='TRUE';
      NO_DIR_CHECK='TRUE';
      ALLOW_CONNECT='TRUE';
    'VCCIN71':
      PIN_NUMBER='(0,0,0,0,0,0,0,0,0,0,0,0,0,0,0,0,0,0,0,0,0,0,0,0,0,0,BP79,0,0,0,0,0,0,0,0,0,0,0,0,0,0,0)';
      PINUSE='POWER';
      NO_LOAD_CHECK='Both';
      NO_IO_CHECK='Both';
      NO_ASSERT_CHECK='TRUE';
      NO_DIR_CHECK='TRUE';
      ALLOW_CONNECT='TRUE';
    'VCCIN70':
      PIN_NUMBER='(0,0,0,0,0,0,0,0,0,0,0,0,0,0,0,0,0,0,0,0,0,0,0,0,0,0,BP61,0,0,0,0,0,0,0,0,0,0,0,0,0,0,0)';
      PINUSE='POWER';
      NO_LOAD_CHECK='Both';
      NO_IO_CHECK='Both';
      NO_ASSERT_CHECK='TRUE';
      NO_DIR_CHECK='TRUE';
      ALLOW_CONNECT='TRUE';
    'VCCIN69':
      PIN_NUMBER='(0,0,0,0,0,0,0,0,0,0,0,0,0,0,0,0,0,0,0,0,0,0,0,0,0,0,BP59,0,0,0,0,0,0,0,0,0,0,0,0,0,0,0)';
      PINUSE='POWER';
      NO_LOAD_CHECK='Both';
      NO_IO_CHECK='Both';
      NO_ASSERT_CHECK='TRUE';
      NO_DIR_CHECK='TRUE';
      ALLOW_CONNECT='TRUE';
    'VCCIN68':
      PIN_NUMBER='(0,0,0,0,0,0,0,0,0,0,0,0,0,0,0,0,0,0,0,0,0,0,0,0,0,0,BP57,0,0,0,0,0,0,0,0,0,0,0,0,0,0,0)';
      PINUSE='POWER';
      NO_LOAD_CHECK='Both';
      NO_IO_CHECK='Both';
      NO_ASSERT_CHECK='TRUE';
      NO_DIR_CHECK='TRUE';
      ALLOW_CONNECT='TRUE';
    'VCCIN67':
      PIN_NUMBER='(0,0,0,0,0,0,0,0,0,0,0,0,0,0,0,0,0,0,0,0,0,0,0,0,0,0,BP55,0,0,0,0,0,0,0,0,0,0,0,0,0,0,0)';
      PINUSE='POWER';
      NO_LOAD_CHECK='Both';
      NO_IO_CHECK='Both';
      NO_ASSERT_CHECK='TRUE';
      NO_DIR_CHECK='TRUE';
      ALLOW_CONNECT='TRUE';
    'VCCIN66':
      PIN_NUMBER='(0,0,0,0,0,0,0,0,0,0,0,0,0,0,0,0,0,0,0,0,0,0,0,0,0,0,BP53,0,0,0,0,0,0,0,0,0,0,0,0,0,0,0)';
      PINUSE='POWER';
      NO_LOAD_CHECK='Both';
      NO_IO_CHECK='Both';
      NO_ASSERT_CHECK='TRUE';
      NO_DIR_CHECK='TRUE';
      ALLOW_CONNECT='TRUE';
    'VCCIN65':
      PIN_NUMBER='(0,0,0,0,0,0,0,0,0,0,0,0,0,0,0,0,0,0,0,0,0,0,0,0,0,0,BP51,0,0,0,0,0,0,0,0,0,0,0,0,0,0,0)';
      PINUSE='POWER';
      NO_LOAD_CHECK='Both';
      NO_IO_CHECK='Both';
      NO_ASSERT_CHECK='TRUE';
      NO_DIR_CHECK='TRUE';
      ALLOW_CONNECT='TRUE';
    'VCCIN64':
      PIN_NUMBER='(0,0,0,0,0,0,0,0,0,0,0,0,0,0,0,0,0,0,0,0,0,0,0,0,0,0,BP49,0,0,0,0,0,0,0,0,0,0,0,0,0,0,0)';
      PINUSE='POWER';
      NO_LOAD_CHECK='Both';
      NO_IO_CHECK='Both';
      NO_ASSERT_CHECK='TRUE';
      NO_DIR_CHECK='TRUE';
      ALLOW_CONNECT='TRUE';
    'VCCIN63':
      PIN_NUMBER='(0,0,0,0,0,0,0,0,0,0,0,0,0,0,0,0,0,0,0,0,0,0,0,0,0,0,BP47,0,0,0,0,0,0,0,0,0,0,0,0,0,0,0)';
      PINUSE='POWER';
      NO_LOAD_CHECK='Both';
      NO_IO_CHECK='Both';
      NO_ASSERT_CHECK='TRUE';
      NO_DIR_CHECK='TRUE';
      ALLOW_CONNECT='TRUE';
    'VCCIN62':
      PIN_NUMBER='(0,0,0,0,0,0,0,0,0,0,0,0,0,0,0,0,0,0,0,0,0,0,0,0,0,0,BP44,0,0,0,0,0,0,0,0,0,0,0,0,0,0,0)';
      PINUSE='POWER';
      NO_LOAD_CHECK='Both';
      NO_IO_CHECK='Both';
      NO_ASSERT_CHECK='TRUE';
      NO_DIR_CHECK='TRUE';
      ALLOW_CONNECT='TRUE';
    'VCCIN61':
      PIN_NUMBER='(0,0,0,0,0,0,0,0,0,0,0,0,0,0,0,0,0,0,0,0,0,0,0,0,0,0,BP42,0,0,0,0,0,0,0,0,0,0,0,0,0,0,0)';
      PINUSE='POWER';
      NO_LOAD_CHECK='Both';
      NO_IO_CHECK='Both';
      NO_ASSERT_CHECK='TRUE';
      NO_DIR_CHECK='TRUE';
      ALLOW_CONNECT='TRUE';
    'VCCIN60':
      PIN_NUMBER='(0,0,0,0,0,0,0,0,0,0,0,0,0,0,0,0,0,0,0,0,0,0,0,0,0,0,BP40,0,0,0,0,0,0,0,0,0,0,0,0,0,0,0)';
      PINUSE='POWER';
      NO_LOAD_CHECK='Both';
      NO_IO_CHECK='Both';
      NO_ASSERT_CHECK='TRUE';
      NO_DIR_CHECK='TRUE';
      ALLOW_CONNECT='TRUE';
    'VCCIN59':
      PIN_NUMBER='(0,0,0,0,0,0,0,0,0,0,0,0,0,0,0,0,0,0,0,0,0,0,0,0,0,0,BP38,0,0,0,0,0,0,0,0,0,0,0,0,0,0,0)';
      PINUSE='POWER';
      NO_LOAD_CHECK='Both';
      NO_IO_CHECK='Both';
      NO_ASSERT_CHECK='TRUE';
      NO_DIR_CHECK='TRUE';
      ALLOW_CONNECT='TRUE';
    'VCCIN58':
      PIN_NUMBER='(0,0,0,0,0,0,0,0,0,0,0,0,0,0,0,0,0,0,0,0,0,0,0,0,0,0,BP36,0,0,0,0,0,0,0,0,0,0,0,0,0,0,0)';
      PINUSE='POWER';
      NO_LOAD_CHECK='Both';
      NO_IO_CHECK='Both';
      NO_ASSERT_CHECK='TRUE';
      NO_DIR_CHECK='TRUE';
      ALLOW_CONNECT='TRUE';
    'VCCIN57':
      PIN_NUMBER='(0,0,0,0,0,0,0,0,0,0,0,0,0,0,0,0,0,0,0,0,0,0,0,0,0,0,BP34,0,0,0,0,0,0,0,0,0,0,0,0,0,0,0)';
      PINUSE='POWER';
      NO_LOAD_CHECK='Both';
      NO_IO_CHECK='Both';
      NO_ASSERT_CHECK='TRUE';
      NO_DIR_CHECK='TRUE';
      ALLOW_CONNECT='TRUE';
    'VCCIN56':
      PIN_NUMBER='(0,0,0,0,0,0,0,0,0,0,0,0,0,0,0,0,0,0,0,0,0,0,0,0,0,0,BP32,0,0,0,0,0,0,0,0,0,0,0,0,0,0,0)';
      PINUSE='POWER';
      NO_LOAD_CHECK='Both';
      NO_IO_CHECK='Both';
      NO_ASSERT_CHECK='TRUE';
      NO_DIR_CHECK='TRUE';
      ALLOW_CONNECT='TRUE';
    'VCCIN55':
      PIN_NUMBER='(0,0,0,0,0,0,0,0,0,0,0,0,0,0,0,0,0,0,0,0,0,0,0,0,0,0,BN90,0,0,0,0,0,0,0,0,0,0,0,0,0,0,0)';
      PINUSE='POWER';
      NO_LOAD_CHECK='Both';
      NO_IO_CHECK='Both';
      NO_ASSERT_CHECK='TRUE';
      NO_DIR_CHECK='TRUE';
      ALLOW_CONNECT='TRUE';
    'VCCIN54':
      PIN_NUMBER='(0,0,0,0,0,0,0,0,0,0,0,0,0,0,0,0,0,0,0,0,0,0,0,0,0,0,BN88,0,0,0,0,0,0,0,0,0,0,0,0,0,0,0)';
      PINUSE='POWER';
      NO_LOAD_CHECK='Both';
      NO_IO_CHECK='Both';
      NO_ASSERT_CHECK='TRUE';
      NO_DIR_CHECK='TRUE';
      ALLOW_CONNECT='TRUE';
    'VCCIN53':
      PIN_NUMBER='(0,0,0,0,0,0,0,0,0,0,0,0,0,0,0,0,0,0,0,0,0,0,0,0,0,0,BN86,0,0,0,0,0,0,0,0,0,0,0,0,0,0,0)';
      PINUSE='POWER';
      NO_LOAD_CHECK='Both';
      NO_IO_CHECK='Both';
      NO_ASSERT_CHECK='TRUE';
      NO_DIR_CHECK='TRUE';
      ALLOW_CONNECT='TRUE';
    'VCCIN52':
      PIN_NUMBER='(0,0,0,0,0,0,0,0,0,0,0,0,0,0,0,0,0,0,0,0,0,0,0,0,0,0,BN84,0,0,0,0,0,0,0,0,0,0,0,0,0,0,0)';
      PINUSE='POWER';
      NO_LOAD_CHECK='Both';
      NO_IO_CHECK='Both';
      NO_ASSERT_CHECK='TRUE';
      NO_DIR_CHECK='TRUE';
      ALLOW_CONNECT='TRUE';
    'VCCIN51':
      PIN_NUMBER='(0,0,0,0,0,0,0,0,0,0,0,0,0,0,0,0,0,0,0,0,0,0,0,0,0,0,BN82,0,0,0,0,0,0,0,0,0,0,0,0,0,0,0)';
      PINUSE='POWER';
      NO_LOAD_CHECK='Both';
      NO_IO_CHECK='Both';
      NO_ASSERT_CHECK='TRUE';
      NO_DIR_CHECK='TRUE';
      ALLOW_CONNECT='TRUE';
    'VCCIN50':
      PIN_NUMBER='(0,0,0,0,0,0,0,0,0,0,0,0,0,0,0,0,0,0,0,0,0,0,0,0,0,0,BN80,0,0,0,0,0,0,0,0,0,0,0,0,0,0,0)';
      PINUSE='POWER';
      NO_LOAD_CHECK='Both';
      NO_IO_CHECK='Both';
      NO_ASSERT_CHECK='TRUE';
      NO_DIR_CHECK='TRUE';
      ALLOW_CONNECT='TRUE';
    'VCCIN49':
      PIN_NUMBER='(0,0,0,0,0,0,0,0,0,0,0,0,0,0,0,0,0,0,0,0,0,0,0,0,0,0,BN78,0,0,0,0,0,0,0,0,0,0,0,0,0,0,0)';
      PINUSE='POWER';
      NO_LOAD_CHECK='Both';
      NO_IO_CHECK='Both';
      NO_ASSERT_CHECK='TRUE';
      NO_DIR_CHECK='TRUE';
      ALLOW_CONNECT='TRUE';
    'VCCIN48':
      PIN_NUMBER='(0,0,0,0,0,0,0,0,0,0,0,0,0,0,0,0,0,0,0,0,0,0,0,0,0,0,BN60,0,0,0,0,0,0,0,0,0,0,0,0,0,0,0)';
      PINUSE='POWER';
      NO_LOAD_CHECK='Both';
      NO_IO_CHECK='Both';
      NO_ASSERT_CHECK='TRUE';
      NO_DIR_CHECK='TRUE';
      ALLOW_CONNECT='TRUE';
    'VCCIN47':
      PIN_NUMBER='(0,0,0,0,0,0,0,0,0,0,0,0,0,0,0,0,0,0,0,0,0,0,0,0,0,0,BN58,0,0,0,0,0,0,0,0,0,0,0,0,0,0,0)';
      PINUSE='POWER';
      NO_LOAD_CHECK='Both';
      NO_IO_CHECK='Both';
      NO_ASSERT_CHECK='TRUE';
      NO_DIR_CHECK='TRUE';
      ALLOW_CONNECT='TRUE';
    'VCCIN46':
      PIN_NUMBER='(0,0,0,0,0,0,0,0,0,0,0,0,0,0,0,0,0,0,0,0,0,0,0,0,0,0,BN56,0,0,0,0,0,0,0,0,0,0,0,0,0,0,0)';
      PINUSE='POWER';
      NO_LOAD_CHECK='Both';
      NO_IO_CHECK='Both';
      NO_ASSERT_CHECK='TRUE';
      NO_DIR_CHECK='TRUE';
      ALLOW_CONNECT='TRUE';
    'VCCIN45':
      PIN_NUMBER='(0,0,0,0,0,0,0,0,0,0,0,0,0,0,0,0,0,0,0,0,0,0,0,0,0,0,BN54,0,0,0,0,0,0,0,0,0,0,0,0,0,0,0)';
      PINUSE='POWER';
      NO_LOAD_CHECK='Both';
      NO_IO_CHECK='Both';
      NO_ASSERT_CHECK='TRUE';
      NO_DIR_CHECK='TRUE';
      ALLOW_CONNECT='TRUE';
    'VCCIN44':
      PIN_NUMBER='(0,0,0,0,0,0,0,0,0,0,0,0,0,0,0,0,0,0,0,0,0,0,0,0,0,0,BN52,0,0,0,0,0,0,0,0,0,0,0,0,0,0,0)';
      PINUSE='POWER';
      NO_LOAD_CHECK='Both';
      NO_IO_CHECK='Both';
      NO_ASSERT_CHECK='TRUE';
      NO_DIR_CHECK='TRUE';
      ALLOW_CONNECT='TRUE';
    'VCCIN43':
      PIN_NUMBER='(0,0,0,0,0,0,0,0,0,0,0,0,0,0,0,0,0,0,0,0,0,0,0,0,0,0,BN50,0,0,0,0,0,0,0,0,0,0,0,0,0,0,0)';
      PINUSE='POWER';
      NO_LOAD_CHECK='Both';
      NO_IO_CHECK='Both';
      NO_ASSERT_CHECK='TRUE';
      NO_DIR_CHECK='TRUE';
      ALLOW_CONNECT='TRUE';
    'VCCIN42':
      PIN_NUMBER='(0,0,0,0,0,0,0,0,0,0,0,0,0,0,0,0,0,0,0,0,0,0,0,0,0,0,BN48,0,0,0,0,0,0,0,0,0,0,0,0,0,0,0)';
      PINUSE='POWER';
      NO_LOAD_CHECK='Both';
      NO_IO_CHECK='Both';
      NO_ASSERT_CHECK='TRUE';
      NO_DIR_CHECK='TRUE';
      ALLOW_CONNECT='TRUE';
    'VCCIN41':
      PIN_NUMBER='(0,0,0,0,0,0,0,0,0,0,0,0,0,0,0,0,0,0,0,0,0,0,0,0,0,0,BN45,0,0,0,0,0,0,0,0,0,0,0,0,0,0,0)';
      PINUSE='POWER';
      NO_LOAD_CHECK='Both';
      NO_IO_CHECK='Both';
      NO_ASSERT_CHECK='TRUE';
      NO_DIR_CHECK='TRUE';
      ALLOW_CONNECT='TRUE';
    'VCCIN40':
      PIN_NUMBER='(0,0,0,0,0,0,0,0,0,0,0,0,0,0,0,0,0,0,0,0,0,0,0,0,0,0,BN43,0,0,0,0,0,0,0,0,0,0,0,0,0,0,0)';
      PINUSE='POWER';
      NO_LOAD_CHECK='Both';
      NO_IO_CHECK='Both';
      NO_ASSERT_CHECK='TRUE';
      NO_DIR_CHECK='TRUE';
      ALLOW_CONNECT='TRUE';
    'VCCIN39':
      PIN_NUMBER='(0,0,0,0,0,0,0,0,0,0,0,0,0,0,0,0,0,0,0,0,0,0,0,0,0,0,0,BN41,0,0,0,0,0,0,0,0,0,0,0,0,0,0)';
      PINUSE='POWER';
      NO_LOAD_CHECK='Both';
      NO_IO_CHECK='Both';
      NO_ASSERT_CHECK='TRUE';
      NO_DIR_CHECK='TRUE';
      ALLOW_CONNECT='TRUE';
    'VCCIN38':
      PIN_NUMBER='(0,0,0,0,0,0,0,0,0,0,0,0,0,0,0,0,0,0,0,0,0,0,0,0,0,0,0,BN39,0,0,0,0,0,0,0,0,0,0,0,0,0,0)';
      PINUSE='POWER';
      NO_LOAD_CHECK='Both';
      NO_IO_CHECK='Both';
      NO_ASSERT_CHECK='TRUE';
      NO_DIR_CHECK='TRUE';
      ALLOW_CONNECT='TRUE';
    'VCCIN37':
      PIN_NUMBER='(0,0,0,0,0,0,0,0,0,0,0,0,0,0,0,0,0,0,0,0,0,0,0,0,0,0,0,BN37,0,0,0,0,0,0,0,0,0,0,0,0,0,0)';
      PINUSE='POWER';
      NO_LOAD_CHECK='Both';
      NO_IO_CHECK='Both';
      NO_ASSERT_CHECK='TRUE';
      NO_DIR_CHECK='TRUE';
      ALLOW_CONNECT='TRUE';
    'VCCIN36':
      PIN_NUMBER='(0,0,0,0,0,0,0,0,0,0,0,0,0,0,0,0,0,0,0,0,0,0,0,0,0,0,0,BN35,0,0,0,0,0,0,0,0,0,0,0,0,0,0)';
      PINUSE='POWER';
      NO_LOAD_CHECK='Both';
      NO_IO_CHECK='Both';
      NO_ASSERT_CHECK='TRUE';
      NO_DIR_CHECK='TRUE';
      ALLOW_CONNECT='TRUE';
    'VCCIN35':
      PIN_NUMBER='(0,0,0,0,0,0,0,0,0,0,0,0,0,0,0,0,0,0,0,0,0,0,0,0,0,0,0,BN33,0,0,0,0,0,0,0,0,0,0,0,0,0,0)';
      PINUSE='POWER';
      NO_LOAD_CHECK='Both';
      NO_IO_CHECK='Both';
      NO_ASSERT_CHECK='TRUE';
      NO_DIR_CHECK='TRUE';
      ALLOW_CONNECT='TRUE';
    'VCCIN34':
      PIN_NUMBER='(0,0,0,0,0,0,0,0,0,0,0,0,0,0,0,0,0,0,0,0,0,0,0,0,0,0,0,BM91,0,0,0,0,0,0,0,0,0,0,0,0,0,0)';
      PINUSE='POWER';
      NO_LOAD_CHECK='Both';
      NO_IO_CHECK='Both';
      NO_ASSERT_CHECK='TRUE';
      NO_DIR_CHECK='TRUE';
      ALLOW_CONNECT='TRUE';
    'VCCIN33':
      PIN_NUMBER='(0,0,0,0,0,0,0,0,0,0,0,0,0,0,0,0,0,0,0,0,0,0,0,0,0,0,0,BM89,0,0,0,0,0,0,0,0,0,0,0,0,0,0)';
      PINUSE='POWER';
      NO_LOAD_CHECK='Both';
      NO_IO_CHECK='Both';
      NO_ASSERT_CHECK='TRUE';
      NO_DIR_CHECK='TRUE';
      ALLOW_CONNECT='TRUE';
    'VCCIN32':
      PIN_NUMBER='(0,0,0,0,0,0,0,0,0,0,0,0,0,0,0,0,0,0,0,0,0,0,0,0,0,0,0,BM87,0,0,0,0,0,0,0,0,0,0,0,0,0,0)';
      PINUSE='POWER';
      NO_LOAD_CHECK='Both';
      NO_IO_CHECK='Both';
      NO_ASSERT_CHECK='TRUE';
      NO_DIR_CHECK='TRUE';
      ALLOW_CONNECT='TRUE';
    'VCCIN31':
      PIN_NUMBER='(0,0,0,0,0,0,0,0,0,0,0,0,0,0,0,0,0,0,0,0,0,0,0,0,0,0,0,BM85,0,0,0,0,0,0,0,0,0,0,0,0,0,0)';
      PINUSE='POWER';
      NO_LOAD_CHECK='Both';
      NO_IO_CHECK='Both';
      NO_ASSERT_CHECK='TRUE';
      NO_DIR_CHECK='TRUE';
      ALLOW_CONNECT='TRUE';
    'VCCIN30':
      PIN_NUMBER='(0,0,0,0,0,0,0,0,0,0,0,0,0,0,0,0,0,0,0,0,0,0,0,0,0,0,0,BM83,0,0,0,0,0,0,0,0,0,0,0,0,0,0)';
      PINUSE='POWER';
      NO_LOAD_CHECK='Both';
      NO_IO_CHECK='Both';
      NO_ASSERT_CHECK='TRUE';
      NO_DIR_CHECK='TRUE';
      ALLOW_CONNECT='TRUE';
    'VCCIN29':
      PIN_NUMBER='(0,0,0,0,0,0,0,0,0,0,0,0,0,0,0,0,0,0,0,0,0,0,0,0,0,0,0,BM81,0,0,0,0,0,0,0,0,0,0,0,0,0,0)';
      PINUSE='POWER';
      NO_LOAD_CHECK='Both';
      NO_IO_CHECK='Both';
      NO_ASSERT_CHECK='TRUE';
      NO_DIR_CHECK='TRUE';
      ALLOW_CONNECT='TRUE';
    'VCCIN28':
      PIN_NUMBER='(0,0,0,0,0,0,0,0,0,0,0,0,0,0,0,0,0,0,0,0,0,0,0,0,0,0,0,BM79,0,0,0,0,0,0,0,0,0,0,0,0,0,0)';
      PINUSE='POWER';
      NO_LOAD_CHECK='Both';
      NO_IO_CHECK='Both';
      NO_ASSERT_CHECK='TRUE';
      NO_DIR_CHECK='TRUE';
      ALLOW_CONNECT='TRUE';
    'VCCIN27':
      PIN_NUMBER='(0,0,0,0,0,0,0,0,0,0,0,0,0,0,0,0,0,0,0,0,0,0,0,0,0,0,0,BL90,0,0,0,0,0,0,0,0,0,0,0,0,0,0)';
      PINUSE='POWER';
      NO_LOAD_CHECK='Both';
      NO_IO_CHECK='Both';
      NO_ASSERT_CHECK='TRUE';
      NO_DIR_CHECK='TRUE';
      ALLOW_CONNECT='TRUE';
    'VCCIN26':
      PIN_NUMBER='(0,0,0,0,0,0,0,0,0,0,0,0,0,0,0,0,0,0,0,0,0,0,0,0,0,0,0,BL88,0,0,0,0,0,0,0,0,0,0,0,0,0,0)';
      PINUSE='POWER';
      NO_LOAD_CHECK='Both';
      NO_IO_CHECK='Both';
      NO_ASSERT_CHECK='TRUE';
      NO_DIR_CHECK='TRUE';
      ALLOW_CONNECT='TRUE';
    'VCCIN25':
      PIN_NUMBER='(0,0,0,0,0,0,0,0,0,0,0,0,0,0,0,0,0,0,0,0,0,0,0,0,0,0,0,BL86,0,0,0,0,0,0,0,0,0,0,0,0,0,0)';
      PINUSE='POWER';
      NO_LOAD_CHECK='Both';
      NO_IO_CHECK='Both';
      NO_ASSERT_CHECK='TRUE';
      NO_DIR_CHECK='TRUE';
      ALLOW_CONNECT='TRUE';
    'VCCIN24':
      PIN_NUMBER='(0,0,0,0,0,0,0,0,0,0,0,0,0,0,0,0,0,0,0,0,0,0,0,0,0,0,0,BL84,0,0,0,0,0,0,0,0,0,0,0,0,0,0)';
      PINUSE='POWER';
      NO_LOAD_CHECK='Both';
      NO_IO_CHECK='Both';
      NO_ASSERT_CHECK='TRUE';
      NO_DIR_CHECK='TRUE';
      ALLOW_CONNECT='TRUE';
    'VCCIN23':
      PIN_NUMBER='(0,0,0,0,0,0,0,0,0,0,0,0,0,0,0,0,0,0,0,0,0,0,0,0,0,0,0,BL82,0,0,0,0,0,0,0,0,0,0,0,0,0,0)';
      PINUSE='POWER';
      NO_LOAD_CHECK='Both';
      NO_IO_CHECK='Both';
      NO_ASSERT_CHECK='TRUE';
      NO_DIR_CHECK='TRUE';
      ALLOW_CONNECT='TRUE';
    'VCCIN22':
      PIN_NUMBER='(0,0,0,0,0,0,0,0,0,0,0,0,0,0,0,0,0,0,0,0,0,0,0,0,0,0,0,BL80,0,0,0,0,0,0,0,0,0,0,0,0,0,0)';
      PINUSE='POWER';
      NO_LOAD_CHECK='Both';
      NO_IO_CHECK='Both';
      NO_ASSERT_CHECK='TRUE';
      NO_DIR_CHECK='TRUE';
      ALLOW_CONNECT='TRUE';
    'VCCIN21':
      PIN_NUMBER='(0,0,0,0,0,0,0,0,0,0,0,0,0,0,0,0,0,0,0,0,0,0,0,0,0,0,0,BK91,0,0,0,0,0,0,0,0,0,0,0,0,0,0)';
      PINUSE='POWER';
      NO_LOAD_CHECK='Both';
      NO_IO_CHECK='Both';
      NO_ASSERT_CHECK='TRUE';
      NO_DIR_CHECK='TRUE';
      ALLOW_CONNECT='TRUE';
    'VCCIN20':
      PIN_NUMBER='(0,0,0,0,0,0,0,0,0,0,0,0,0,0,0,0,0,0,0,0,0,0,0,0,0,0,0,BK89,0,0,0,0,0,0,0,0,0,0,0,0,0,0)';
      PINUSE='POWER';
      NO_LOAD_CHECK='Both';
      NO_IO_CHECK='Both';
      NO_ASSERT_CHECK='TRUE';
      NO_DIR_CHECK='TRUE';
      ALLOW_CONNECT='TRUE';
    'VCCIN19':
      PIN_NUMBER='(0,0,0,0,0,0,0,0,0,0,0,0,0,0,0,0,0,0,0,0,0,0,0,0,0,0,0,BK87,0,0,0,0,0,0,0,0,0,0,0,0,0,0)';
      PINUSE='POWER';
      NO_LOAD_CHECK='Both';
      NO_IO_CHECK='Both';
      NO_ASSERT_CHECK='TRUE';
      NO_DIR_CHECK='TRUE';
      ALLOW_CONNECT='TRUE';
    'VCCIN18':
      PIN_NUMBER='(0,0,0,0,0,0,0,0,0,0,0,0,0,0,0,0,0,0,0,0,0,0,0,0,0,0,0,BK85,0,0,0,0,0,0,0,0,0,0,0,0,0,0)';
      PINUSE='POWER';
      NO_LOAD_CHECK='Both';
      NO_IO_CHECK='Both';
      NO_ASSERT_CHECK='TRUE';
      NO_DIR_CHECK='TRUE';
      ALLOW_CONNECT='TRUE';
    'VCCIN17':
      PIN_NUMBER='(0,0,0,0,0,0,0,0,0,0,0,0,0,0,0,0,0,0,0,0,0,0,0,0,0,0,0,BK83,0,0,0,0,0,0,0,0,0,0,0,0,0,0)';
      PINUSE='POWER';
      NO_LOAD_CHECK='Both';
      NO_IO_CHECK='Both';
      NO_ASSERT_CHECK='TRUE';
      NO_DIR_CHECK='TRUE';
      ALLOW_CONNECT='TRUE';
    'VCCIN16':
      PIN_NUMBER='(0,0,0,0,0,0,0,0,0,0,0,0,0,0,0,0,0,0,0,0,0,0,0,0,0,0,0,BK81,0,0,0,0,0,0,0,0,0,0,0,0,0,0)';
      PINUSE='POWER';
      NO_LOAD_CHECK='Both';
      NO_IO_CHECK='Both';
      NO_ASSERT_CHECK='TRUE';
      NO_DIR_CHECK='TRUE';
      ALLOW_CONNECT='TRUE';
    'VCCIN15':
      PIN_NUMBER='(0,0,0,0,0,0,0,0,0,0,0,0,0,0,0,0,0,0,0,0,0,0,0,0,0,0,0,BH91,0,0,0,0,0,0,0,0,0,0,0,0,0,0)';
      PINUSE='POWER';
      NO_LOAD_CHECK='Both';
      NO_IO_CHECK='Both';
      NO_ASSERT_CHECK='TRUE';
      NO_DIR_CHECK='TRUE';
      ALLOW_CONNECT='TRUE';
    'VCCIN14':
      PIN_NUMBER='(0,0,0,0,0,0,0,0,0,0,0,0,0,0,0,0,0,0,0,0,0,0,0,0,0,0,0,BH89,0,0,0,0,0,0,0,0,0,0,0,0,0,0)';
      PINUSE='POWER';
      NO_LOAD_CHECK='Both';
      NO_IO_CHECK='Both';
      NO_ASSERT_CHECK='TRUE';
      NO_DIR_CHECK='TRUE';
      ALLOW_CONNECT='TRUE';
    'VCCIN13':
      PIN_NUMBER='(0,0,0,0,0,0,0,0,0,0,0,0,0,0,0,0,0,0,0,0,0,0,0,0,0,0,0,BH87,0,0,0,0,0,0,0,0,0,0,0,0,0,0)';
      PINUSE='POWER';
      NO_LOAD_CHECK='Both';
      NO_IO_CHECK='Both';
      NO_ASSERT_CHECK='TRUE';
      NO_DIR_CHECK='TRUE';
      ALLOW_CONNECT='TRUE';
    'VCCIN12':
      PIN_NUMBER='(0,0,0,0,0,0,0,0,0,0,0,0,0,0,0,0,0,0,0,0,0,0,0,0,0,0,0,BH85,0,0,0,0,0,0,0,0,0,0,0,0,0,0)';
      PINUSE='POWER';
      NO_LOAD_CHECK='Both';
      NO_IO_CHECK='Both';
      NO_ASSERT_CHECK='TRUE';
      NO_DIR_CHECK='TRUE';
      ALLOW_CONNECT='TRUE';
    'VCCIN11':
      PIN_NUMBER='(0,0,0,0,0,0,0,0,0,0,0,0,0,0,0,0,0,0,0,0,0,0,0,0,0,0,0,BG90,0,0,0,0,0,0,0,0,0,0,0,0,0,0)';
      PINUSE='POWER';
      NO_LOAD_CHECK='Both';
      NO_IO_CHECK='Both';
      NO_ASSERT_CHECK='TRUE';
      NO_DIR_CHECK='TRUE';
      ALLOW_CONNECT='TRUE';
    'VCCIN10':
      PIN_NUMBER='(0,0,0,0,0,0,0,0,0,0,0,0,0,0,0,0,0,0,0,0,0,0,0,0,0,0,0,BG88,0,0,0,0,0,0,0,0,0,0,0,0,0,0)';
      PINUSE='POWER';
      NO_LOAD_CHECK='Both';
      NO_IO_CHECK='Both';
      NO_ASSERT_CHECK='TRUE';
      NO_DIR_CHECK='TRUE';
      ALLOW_CONNECT='TRUE';
    'VCCIN9':
      PIN_NUMBER='(0,0,0,0,0,0,0,0,0,0,0,0,0,0,0,0,0,0,0,0,0,0,0,0,0,0,0,BG86,0,0,0,0,0,0,0,0,0,0,0,0,0,0)';
      PINUSE='POWER';
      NO_LOAD_CHECK='Both';
      NO_IO_CHECK='Both';
      NO_ASSERT_CHECK='TRUE';
      NO_DIR_CHECK='TRUE';
      ALLOW_CONNECT='TRUE';
    'VCCIN8':
      PIN_NUMBER='(0,0,0,0,0,0,0,0,0,0,0,0,0,0,0,0,0,0,0,0,0,0,0,0,0,0,0,BG84,0,0,0,0,0,0,0,0,0,0,0,0,0,0)';
      PINUSE='POWER';
      NO_LOAD_CHECK='Both';
      NO_IO_CHECK='Both';
      NO_ASSERT_CHECK='TRUE';
      NO_DIR_CHECK='TRUE';
      ALLOW_CONNECT='TRUE';
    'VCCIN7':
      PIN_NUMBER='(0,0,0,0,0,0,0,0,0,0,0,0,0,0,0,0,0,0,0,0,0,0,0,0,0,0,0,BF91,0,0,0,0,0,0,0,0,0,0,0,0,0,0)';
      PINUSE='POWER';
      NO_LOAD_CHECK='Both';
      NO_IO_CHECK='Both';
      NO_ASSERT_CHECK='TRUE';
      NO_DIR_CHECK='TRUE';
      ALLOW_CONNECT='TRUE';
    'VCCIN6':
      PIN_NUMBER='(0,0,0,0,0,0,0,0,0,0,0,0,0,0,0,0,0,0,0,0,0,0,0,0,0,0,0,BF89,0,0,0,0,0,0,0,0,0,0,0,0,0,0)';
      PINUSE='POWER';
      NO_LOAD_CHECK='Both';
      NO_IO_CHECK='Both';
      NO_ASSERT_CHECK='TRUE';
      NO_DIR_CHECK='TRUE';
      ALLOW_CONNECT='TRUE';
    'VCCIN5':
      PIN_NUMBER='(0,0,0,0,0,0,0,0,0,0,0,0,0,0,0,0,0,0,0,0,0,0,0,0,0,0,0,BF87,0,0,0,0,0,0,0,0,0,0,0,0,0,0)';
      PINUSE='POWER';
      NO_LOAD_CHECK='Both';
      NO_IO_CHECK='Both';
      NO_ASSERT_CHECK='TRUE';
      NO_DIR_CHECK='TRUE';
      ALLOW_CONNECT='TRUE';
    'VCCIN4':
      PIN_NUMBER='(0,0,0,0,0,0,0,0,0,0,0,0,0,0,0,0,0,0,0,0,0,0,0,0,0,0,0,BF85,0,0,0,0,0,0,0,0,0,0,0,0,0,0)';
      PINUSE='POWER';
      NO_LOAD_CHECK='Both';
      NO_IO_CHECK='Both';
      NO_ASSERT_CHECK='TRUE';
      NO_DIR_CHECK='TRUE';
      ALLOW_CONNECT='TRUE';
    'VCCIN3':
      PIN_NUMBER='(0,0,0,0,0,0,0,0,0,0,0,0,0,0,0,0,0,0,0,0,0,0,0,0,0,0,0,BE90,0,0,0,0,0,0,0,0,0,0,0,0,0,0)';
      PINUSE='POWER';
      NO_LOAD_CHECK='Both';
      NO_IO_CHECK='Both';
      NO_ASSERT_CHECK='TRUE';
      NO_DIR_CHECK='TRUE';
      ALLOW_CONNECT='TRUE';
    'VCCIN2':
      PIN_NUMBER='(0,0,0,0,0,0,0,0,0,0,0,0,0,0,0,0,0,0,0,0,0,0,0,0,0,0,0,BE88,0,0,0,0,0,0,0,0,0,0,0,0,0,0)';
      PINUSE='POWER';
      NO_LOAD_CHECK='Both';
      NO_IO_CHECK='Both';
      NO_ASSERT_CHECK='TRUE';
      NO_DIR_CHECK='TRUE';
      ALLOW_CONNECT='TRUE';
    'VCCIN1':
      PIN_NUMBER='(0,0,0,0,0,0,0,0,0,0,0,0,0,0,0,0,0,0,0,0,0,0,0,0,0,0,0,BE86,0,0,0,0,0,0,0,0,0,0,0,0,0,0)';
      PINUSE='POWER';
      NO_LOAD_CHECK='Both';
      NO_IO_CHECK='Both';
      NO_ASSERT_CHECK='TRUE';
      NO_DIR_CHECK='TRUE';
      ALLOW_CONNECT='TRUE';
    'VCCIN0':
      PIN_NUMBER='(0,0,0,0,0,0,0,0,0,0,0,0,0,0,0,0,0,0,0,0,0,0,0,0,0,0,0,BD91,0,0,0,0,0,0,0,0,0,0,0,0,0,0)';
      PINUSE='POWER';
      NO_LOAD_CHECK='Both';
      NO_IO_CHECK='Both';
      NO_ASSERT_CHECK='TRUE';
      NO_DIR_CHECK='TRUE';
      ALLOW_CONNECT='TRUE';
    'VCCINFAON53':
      PIN_NUMBER='(0,0,0,0,0,0,0,0,0,0,0,0,0,0,0,0,0,0,0,0,0,0,0,0,0,0,0,DA21,0,0,0,0,0,0,0,0,0,0,0,0,0,0)';
      PINUSE='POWER';
      NO_LOAD_CHECK='Both';
      NO_IO_CHECK='Both';
      NO_ASSERT_CHECK='TRUE';
      NO_DIR_CHECK='TRUE';
      ALLOW_CONNECT='TRUE';
    'VCCINFAON52':
      PIN_NUMBER='(0,0,0,0,0,0,0,0,0,0,0,0,0,0,0,0,0,0,0,0,0,0,0,0,0,0,0,CW62,0,0,0,0,0,0,0,0,0,0,0,0,0,0)';
      PINUSE='POWER';
      NO_LOAD_CHECK='Both';
      NO_IO_CHECK='Both';
      NO_ASSERT_CHECK='TRUE';
      NO_DIR_CHECK='TRUE';
      ALLOW_CONNECT='TRUE';
    'VCCINFAON51':
      PIN_NUMBER='(0,0,0,0,0,0,0,0,0,0,0,0,0,0,0,0,0,0,0,0,0,0,0,0,0,0,0,CV63,0,0,0,0,0,0,0,0,0,0,0,0,0,0)';
      PINUSE='POWER';
      NO_LOAD_CHECK='Both';
      NO_IO_CHECK='Both';
      NO_ASSERT_CHECK='TRUE';
      NO_DIR_CHECK='TRUE';
      ALLOW_CONNECT='TRUE';
    'VCCINFAON50':
      PIN_NUMBER='(0,0,0,0,0,0,0,0,0,0,0,0,0,0,0,0,0,0,0,0,0,0,0,0,0,0,0,CV61,0,0,0,0,0,0,0,0,0,0,0,0,0,0)';
      PINUSE='POWER';
      NO_LOAD_CHECK='Both';
      NO_IO_CHECK='Both';
      NO_ASSERT_CHECK='TRUE';
      NO_DIR_CHECK='TRUE';
      ALLOW_CONNECT='TRUE';
    'VCCINFAON49':
      PIN_NUMBER='(0,0,0,0,0,0,0,0,0,0,0,0,0,0,0,0,0,0,0,0,0,0,0,0,0,0,0,CT63,0,0,0,0,0,0,0,0,0,0,0,0,0,0)';
      PINUSE='POWER';
      NO_LOAD_CHECK='Both';
      NO_IO_CHECK='Both';
      NO_ASSERT_CHECK='TRUE';
      NO_DIR_CHECK='TRUE';
      ALLOW_CONNECT='TRUE';
    'VCCINFAON48':
      PIN_NUMBER='(0,0,0,0,0,0,0,0,0,0,0,0,0,0,0,0,0,0,0,0,0,0,0,0,0,0,0,CP63,0,0,0,0,0,0,0,0,0,0,0,0,0,0)';
      PINUSE='POWER';
      NO_LOAD_CHECK='Both';
      NO_IO_CHECK='Both';
      NO_ASSERT_CHECK='TRUE';
      NO_DIR_CHECK='TRUE';
      ALLOW_CONNECT='TRUE';
    'VCCINFAON47':
      PIN_NUMBER='(0,0,0,0,0,0,0,0,0,0,0,0,0,0,0,0,0,0,0,0,0,0,0,0,0,0,0,CN19,0,0,0,0,0,0,0,0,0,0,0,0,0,0)';
      PINUSE='POWER';
      NO_LOAD_CHECK='Both';
      NO_IO_CHECK='Both';
      NO_ASSERT_CHECK='TRUE';
      NO_DIR_CHECK='TRUE';
      ALLOW_CONNECT='TRUE';
    'VCCINFAON46':
      PIN_NUMBER='(0,0,0,0,0,0,0,0,0,0,0,0,0,0,0,0,0,0,0,0,0,0,0,0,0,0,0,CJ19,0,0,0,0,0,0,0,0,0,0,0,0,0,0)';
      PINUSE='POWER';
      NO_LOAD_CHECK='Both';
      NO_IO_CHECK='Both';
      NO_ASSERT_CHECK='TRUE';
      NO_DIR_CHECK='TRUE';
      ALLOW_CONNECT='TRUE';
    'VCCINFAON45':
      PIN_NUMBER='(0,0,0,0,0,0,0,0,0,0,0,0,0,0,0,0,0,0,0,0,0,0,0,0,0,0,0,CJ11,0,0,0,0,0,0,0,0,0,0,0,0,0,0)';
      PINUSE='POWER';
      NO_LOAD_CHECK='Both';
      NO_IO_CHECK='Both';
      NO_ASSERT_CHECK='TRUE';
      NO_DIR_CHECK='TRUE';
      ALLOW_CONNECT='TRUE';
    'VCCINFAON44':
      PIN_NUMBER='(0,0,0,0,0,0,0,0,0,0,0,0,0,0,0,0,0,0,0,0,0,0,0,0,0,0,0,CE19,0,0,0,0,0,0,0,0,0,0,0,0,0,0)';
      PINUSE='POWER';
      NO_LOAD_CHECK='Both';
      NO_IO_CHECK='Both';
      NO_ASSERT_CHECK='TRUE';
      NO_DIR_CHECK='TRUE';
      ALLOW_CONNECT='TRUE';
    'VCCINFAON43':
      PIN_NUMBER='(0,0,0,0,0,0,0,0,0,0,0,0,0,0,0,0,0,0,0,0,0,0,0,0,0,0,0,CA15,0,0,0,0,0,0,0,0,0,0,0,0,0,0)';
      PINUSE='POWER';
      NO_LOAD_CHECK='Both';
      NO_IO_CHECK='Both';
      NO_ASSERT_CHECK='TRUE';
      NO_DIR_CHECK='TRUE';
      ALLOW_CONNECT='TRUE';
    'VCCINFAON42':
      PIN_NUMBER='(0,0,0,0,0,0,0,0,0,0,0,0,0,0,0,0,0,0,0,0,0,0,0,0,0,0,0,BN15,0,0,0,0,0,0,0,0,0,0,0,0,0,0)';
      PINUSE='POWER';
      NO_LOAD_CHECK='Both';
      NO_IO_CHECK='Both';
      NO_ASSERT_CHECK='TRUE';
      NO_DIR_CHECK='TRUE';
      ALLOW_CONNECT='TRUE';
    'VCCINFAON41':
      PIN_NUMBER='(0,0,0,0,0,0,0,0,0,0,0,0,0,0,0,0,0,0,0,0,0,0,0,0,0,0,0,BK61,0,0,0,0,0,0,0,0,0,0,0,0,0,0)';
      PINUSE='POWER';
      NO_LOAD_CHECK='Both';
      NO_IO_CHECK='Both';
      NO_ASSERT_CHECK='TRUE';
      NO_DIR_CHECK='TRUE';
      ALLOW_CONNECT='TRUE';
    'VCCINFAON40':
      PIN_NUMBER='(0,0,0,0,0,0,0,0,0,0,0,0,0,0,0,0,0,0,0,0,0,0,0,0,0,0,0,BJ60,0,0,0,0,0,0,0,0,0,0,0,0,0,0)';
      PINUSE='POWER';
      NO_LOAD_CHECK='Both';
      NO_IO_CHECK='Both';
      NO_ASSERT_CHECK='TRUE';
      NO_DIR_CHECK='TRUE';
      ALLOW_CONNECT='TRUE';
    'VCCINFAON39':
      PIN_NUMBER='(0,0,0,0,0,0,0,0,0,0,0,0,0,0,0,0,0,0,0,0,0,0,0,0,0,0,0,BJ15,0,0,0,0,0,0,0,0,0,0,0,0,0,0)';
      PINUSE='POWER';
      NO_LOAD_CHECK='Both';
      NO_IO_CHECK='Both';
      NO_ASSERT_CHECK='TRUE';
      NO_DIR_CHECK='TRUE';
      ALLOW_CONNECT='TRUE';
    'VCCINFAON38':
      PIN_NUMBER='(0,0,0,0,0,0,0,0,0,0,0,0,0,0,0,0,0,0,0,0,0,0,0,0,0,0,0,BG60,0,0,0,0,0,0,0,0,0,0,0,0,0,0)';
      PINUSE='POWER';
      NO_LOAD_CHECK='Both';
      NO_IO_CHECK='Both';
      NO_ASSERT_CHECK='TRUE';
      NO_DIR_CHECK='TRUE';
      ALLOW_CONNECT='TRUE';
    'VCCINFAON37':
      PIN_NUMBER='(0,0,0,0,0,0,0,0,0,0,0,0,0,0,0,0,0,0,0,0,0,0,0,0,0,0,0,BE60,0,0,0,0,0,0,0,0,0,0,0,0,0,0)';
      PINUSE='POWER';
      NO_LOAD_CHECK='Both';
      NO_IO_CHECK='Both';
      NO_ASSERT_CHECK='TRUE';
      NO_DIR_CHECK='TRUE';
      ALLOW_CONNECT='TRUE';
    'VCCINFAON36':
      PIN_NUMBER='(0,0,0,0,0,0,0,0,0,0,0,0,0,0,0,0,0,0,0,0,0,0,0,0,0,0,0,BE15,0,0,0,0,0,0,0,0,0,0,0,0,0,0)';
      PINUSE='POWER';
      NO_LOAD_CHECK='Both';
      NO_IO_CHECK='Both';
      NO_ASSERT_CHECK='TRUE';
      NO_DIR_CHECK='TRUE';
      ALLOW_CONNECT='TRUE';
    'VCCINFAON35':
      PIN_NUMBER='(0,0,0,0,0,0,0,0,0,0,0,0,0,0,0,0,0,0,0,0,0,0,0,0,0,0,0,BC60,0,0,0,0,0,0,0,0,0,0,0,0,0,0)';
      PINUSE='POWER';
      NO_LOAD_CHECK='Both';
      NO_IO_CHECK='Both';
      NO_ASSERT_CHECK='TRUE';
      NO_DIR_CHECK='TRUE';
      ALLOW_CONNECT='TRUE';
    'VCCINFAON34':
      PIN_NUMBER='(0,0,0,0,0,0,0,0,0,0,0,0,0,0,0,0,0,0,0,0,0,0,0,0,0,0,0,BA15,0,0,0,0,0,0,0,0,0,0,0,0,0,0)';
      PINUSE='POWER';
      NO_LOAD_CHECK='Both';
      NO_IO_CHECK='Both';
      NO_ASSERT_CHECK='TRUE';
      NO_DIR_CHECK='TRUE';
      ALLOW_CONNECT='TRUE';
    'VCCINFAON33':
      PIN_NUMBER='(0,0,0,0,0,0,0,0,0,0,0,0,0,0,0,0,0,0,0,0,0,0,0,0,0,0,0,AY18,0,0,0,0,0,0,0,0,0,0,0,0,0,0)';
      PINUSE='POWER';
      NO_LOAD_CHECK='Both';
      NO_IO_CHECK='Both';
      NO_ASSERT_CHECK='TRUE';
      NO_DIR_CHECK='TRUE';
      ALLOW_CONNECT='TRUE';
    'VCC_3P3_AUX0':
      PIN_NUMBER='(0,0,0,0,0,0,0,0,0,0,0,0,0,0,0,0,0,0,0,0,0,0,0,0,0,0,0,0,BC21,0,0,0,0,0,0,0,0,0,0,0,0,0)';
      PINUSE='POWER';
      NO_LOAD_CHECK='Both';
      NO_IO_CHECK='Both';
      NO_ASSERT_CHECK='TRUE';
      NO_DIR_CHECK='TRUE';
      ALLOW_CONNECT='TRUE';
    'VCC_3P3_AUX1':
      PIN_NUMBER='(0,0,0,0,0,0,0,0,0,0,0,0,0,0,0,0,0,0,0,0,0,0,0,0,0,0,0,0,BA21,0,0,0,0,0,0,0,0,0,0,0,0,0)';
      PINUSE='POWER';
      NO_LOAD_CHECK='Both';
      NO_IO_CHECK='Both';
      NO_ASSERT_CHECK='TRUE';
      NO_DIR_CHECK='TRUE';
      ALLOW_CONNECT='TRUE';
    'VCCD_HV28':
      PIN_NUMBER='(0,0,0,0,0,0,0,0,0,0,0,0,0,0,0,0,0,0,0,0,0,0,0,0,0,0,0,0,CY53,0,0,0,0,0,0,0,0,0,0,0,0,0)';
      PINUSE='POWER';
      NO_LOAD_CHECK='Both';
      NO_IO_CHECK='Both';
      NO_ASSERT_CHECK='TRUE';
      NO_DIR_CHECK='TRUE';
      ALLOW_CONNECT='TRUE';
    'VCCD_HV27':
      PIN_NUMBER='(0,0,0,0,0,0,0,0,0,0,0,0,0,0,0,0,0,0,0,0,0,0,0,0,0,0,0,0,CY36,0,0,0,0,0,0,0,0,0,0,0,0,0)';
      PINUSE='POWER';
      NO_LOAD_CHECK='Both';
      NO_IO_CHECK='Both';
      NO_ASSERT_CHECK='TRUE';
      NO_DIR_CHECK='TRUE';
      ALLOW_CONNECT='TRUE';
    'VCCD_HV24':
      PIN_NUMBER='(0,0,0,0,0,0,0,0,0,0,0,0,0,0,0,0,0,0,0,0,0,0,0,0,0,0,0,0,CW54,0,0,0,0,0,0,0,0,0,0,0,0,0)';
      PINUSE='POWER';
      NO_LOAD_CHECK='Both';
      NO_IO_CHECK='Both';
      NO_ASSERT_CHECK='TRUE';
      NO_DIR_CHECK='TRUE';
      ALLOW_CONNECT='TRUE';
    'VCCD_HV26':
      PIN_NUMBER='(0,0,0,0,0,0,0,0,0,0,0,0,0,0,0,0,0,0,0,0,0,0,0,0,0,0,0,0,CY34,0,0,0,0,0,0,0,0,0,0,0,0,0)';
      PINUSE='POWER';
      NO_LOAD_CHECK='Both';
      NO_IO_CHECK='Both';
      NO_ASSERT_CHECK='TRUE';
      NO_DIR_CHECK='TRUE';
      ALLOW_CONNECT='TRUE';
    'VCCD_HV25':
      PIN_NUMBER='(0,0,0,0,0,0,0,0,0,0,0,0,0,0,0,0,0,0,0,0,0,0,0,0,0,0,0,0,CW56,0,0,0,0,0,0,0,0,0,0,0,0,0)';
      PINUSE='POWER';
      NO_LOAD_CHECK='Both';
      NO_IO_CHECK='Both';
      NO_ASSERT_CHECK='TRUE';
      NO_DIR_CHECK='TRUE';
      ALLOW_CONNECT='TRUE';
    'VCCD_HV23':
      PIN_NUMBER='(0,0,0,0,0,0,0,0,0,0,0,0,0,0,0,0,0,0,0,0,0,0,0,0,0,0,0,0,CW52,0,0,0,0,0,0,0,0,0,0,0,0,0)';
      PINUSE='POWER';
      NO_LOAD_CHECK='Both';
      NO_IO_CHECK='Both';
      NO_ASSERT_CHECK='TRUE';
      NO_DIR_CHECK='TRUE';
      ALLOW_CONNECT='TRUE';
    'VCCD_HV22':
      PIN_NUMBER='(0,0,0,0,0,0,0,0,0,0,0,0,0,0,0,0,0,0,0,0,0,0,0,0,0,0,0,0,CW37,0,0,0,0,0,0,0,0,0,0,0,0,0)';
      PINUSE='POWER';
      NO_LOAD_CHECK='Both';
      NO_IO_CHECK='Both';
      NO_ASSERT_CHECK='TRUE';
      NO_DIR_CHECK='TRUE';
      ALLOW_CONNECT='TRUE';
    'VCCD_HV21':
      PIN_NUMBER='(0,0,0,0,0,0,0,0,0,0,0,0,0,0,0,0,0,0,0,0,0,0,0,0,0,0,0,0,CW35,0,0,0,0,0,0,0,0,0,0,0,0,0)';
      PINUSE='POWER';
      NO_LOAD_CHECK='Both';
      NO_IO_CHECK='Both';
      NO_ASSERT_CHECK='TRUE';
      NO_DIR_CHECK='TRUE';
      ALLOW_CONNECT='TRUE';
    'VCCD_HV20':
      PIN_NUMBER='(0,0,0,0,0,0,0,0,0,0,0,0,0,0,0,0,0,0,0,0,0,0,0,0,0,0,0,0,CE7,0,0,0,0,0,0,0,0,0,0,0,0,0)';
      PINUSE='POWER';
      NO_LOAD_CHECK='Both';
      NO_IO_CHECK='Both';
      NO_ASSERT_CHECK='TRUE';
      NO_DIR_CHECK='TRUE';
      ALLOW_CONNECT='TRUE';
    'VCCD_HV19':
      PIN_NUMBER='(0,0,0,0,0,0,0,0,0,0,0,0,0,0,0,0,0,0,0,0,0,0,0,0,0,0,0,0,CA7,0,0,0,0,0,0,0,0,0,0,0,0,0)';
      PINUSE='POWER';
      NO_LOAD_CHECK='Both';
      NO_IO_CHECK='Both';
      NO_ASSERT_CHECK='TRUE';
      NO_DIR_CHECK='TRUE';
      ALLOW_CONNECT='TRUE';
    'VCCD_HV18':
      PIN_NUMBER='(0,0,0,0,0,0,0,0,0,0,0,0,0,0,0,0,0,0,0,0,0,0,0,0,0,0,0,0,BN7,0,0,0,0,0,0,0,0,0,0,0,0,0)';
      PINUSE='POWER';
      NO_LOAD_CHECK='Both';
      NO_IO_CHECK='Both';
      NO_ASSERT_CHECK='TRUE';
      NO_DIR_CHECK='TRUE';
      ALLOW_CONNECT='TRUE';
    'VCCD_HV17':
      PIN_NUMBER='(0,0,0,0,0,0,0,0,0,0,0,0,0,0,0,0,0,0,0,0,0,0,0,0,0,0,0,0,BJ7,0,0,0,0,0,0,0,0,0,0,0,0,0)';
      PINUSE='POWER';
      NO_LOAD_CHECK='Both';
      NO_IO_CHECK='Both';
      NO_ASSERT_CHECK='TRUE';
      NO_DIR_CHECK='TRUE';
      ALLOW_CONNECT='TRUE';
    'VCCD_HV16':
      PIN_NUMBER='(0,0,0,0,0,0,0,0,0,0,0,0,0,0,0,0,0,0,0,0,0,0,0,0,0,0,0,0,BJ3,0,0,0,0,0,0,0,0,0,0,0,0,0)';
      PINUSE='POWER';
      NO_LOAD_CHECK='Both';
      NO_IO_CHECK='Both';
      NO_ASSERT_CHECK='TRUE';
      NO_DIR_CHECK='TRUE';
      ALLOW_CONNECT='TRUE';
    'VCCD_HV15':
      PIN_NUMBER='(0,0,0,0,0,0,0,0,0,0,0,0,0,0,0,0,0,0,0,0,0,0,0,0,0,0,0,0,BJ11,0,0,0,0,0,0,0,0,0,0,0,0,0)';
      PINUSE='POWER';
      NO_LOAD_CHECK='Both';
      NO_IO_CHECK='Both';
      NO_ASSERT_CHECK='TRUE';
      NO_DIR_CHECK='TRUE';
      ALLOW_CONNECT='TRUE';
    'VCCD_HV14':
      PIN_NUMBER='(0,0,0,0,0,0,0,0,0,0,0,0,0,0,0,0,0,0,0,0,0,0,0,0,0,0,0,0,BE7,0,0,0,0,0,0,0,0,0,0,0,0,0)';
      PINUSE='POWER';
      NO_LOAD_CHECK='Both';
      NO_IO_CHECK='Both';
      NO_ASSERT_CHECK='TRUE';
      NO_DIR_CHECK='TRUE';
      ALLOW_CONNECT='TRUE';
    'VCCD_HV13':
      PIN_NUMBER='(0,0,0,0,0,0,0,0,0,0,0,0,0,0,0,0,0,0,0,0,0,0,0,0,0,0,0,0,BE3,0,0,0,0,0,0,0,0,0,0,0,0,0)';
      PINUSE='POWER';
      NO_LOAD_CHECK='Both';
      NO_IO_CHECK='Both';
      NO_ASSERT_CHECK='TRUE';
      NO_DIR_CHECK='TRUE';
      ALLOW_CONNECT='TRUE';
    'VCCD_HV12':
      PIN_NUMBER='(0,0,0,0,0,0,0,0,0,0,0,0,0,0,0,0,0,0,0,0,0,0,0,0,0,0,0,0,BE11,0,0,0,0,0,0,0,0,0,0,0,0,0)';
      PINUSE='POWER';
      NO_LOAD_CHECK='Both';
      NO_IO_CHECK='Both';
      NO_ASSERT_CHECK='TRUE';
      NO_DIR_CHECK='TRUE';
      ALLOW_CONNECT='TRUE';
    'VCCD_HV11':
      PIN_NUMBER='(0,0,0,0,0,0,0,0,0,0,0,0,0,0,0,0,0,0,0,0,0,0,0,0,0,0,0,0,BA7,0,0,0,0,0,0,0,0,0,0,0,0,0)';
      PINUSE='POWER';
      NO_LOAD_CHECK='Both';
      NO_IO_CHECK='Both';
      NO_ASSERT_CHECK='TRUE';
      NO_DIR_CHECK='TRUE';
      ALLOW_CONNECT='TRUE';
    'VCCD_HV10':
      PIN_NUMBER='(0,0,0,0,0,0,0,0,0,0,0,0,0,0,0,0,0,0,0,0,0,0,0,0,0,0,0,0,BA3,0,0,0,0,0,0,0,0,0,0,0,0,0)';
      PINUSE='POWER';
      NO_LOAD_CHECK='Both';
      NO_IO_CHECK='Both';
      NO_ASSERT_CHECK='TRUE';
      NO_DIR_CHECK='TRUE';
      ALLOW_CONNECT='TRUE';
    'VCCD_HV9':
      PIN_NUMBER='(0,0,0,0,0,0,0,0,0,0,0,0,0,0,0,0,0,0,0,0,0,0,0,0,0,0,0,0,AV55,0,0,0,0,0,0,0,0,0,0,0,0,0)';
      PINUSE='POWER';
      NO_LOAD_CHECK='Both';
      NO_IO_CHECK='Both';
      NO_ASSERT_CHECK='TRUE';
      NO_DIR_CHECK='TRUE';
      ALLOW_CONNECT='TRUE';
    'VCCD_HV8':
      PIN_NUMBER='(0,0,0,0,0,0,0,0,0,0,0,0,0,0,0,0,0,0,0,0,0,0,0,0,0,0,0,0,AV53,0,0,0,0,0,0,0,0,0,0,0,0,0)';
      PINUSE='POWER';
      NO_LOAD_CHECK='Both';
      NO_IO_CHECK='Both';
      NO_ASSERT_CHECK='TRUE';
      NO_DIR_CHECK='TRUE';
      ALLOW_CONNECT='TRUE';
    'VCCD_HV7':
      PIN_NUMBER='(0,0,0,0,0,0,0,0,0,0,0,0,0,0,0,0,0,0,0,0,0,0,0,0,0,0,0,0,AV36,0,0,0,0,0,0,0,0,0,0,0,0,0)';
      PINUSE='POWER';
      NO_LOAD_CHECK='Both';
      NO_IO_CHECK='Both';
      NO_ASSERT_CHECK='TRUE';
      NO_DIR_CHECK='TRUE';
      ALLOW_CONNECT='TRUE';
    'VCCD_HV6':
      PIN_NUMBER='(0,0,0,0,0,0,0,0,0,0,0,0,0,0,0,0,0,0,0,0,0,0,0,0,0,0,0,0,AV34,0,0,0,0,0,0,0,0,0,0,0,0,0)';
      PINUSE='POWER';
      NO_LOAD_CHECK='Both';
      NO_IO_CHECK='Both';
      NO_ASSERT_CHECK='TRUE';
      NO_DIR_CHECK='TRUE';
      ALLOW_CONNECT='TRUE';
    'VCCD_HV5':
      PIN_NUMBER='(0,0,0,0,0,0,0,0,0,0,0,0,0,0,0,0,0,0,0,0,0,0,0,0,0,0,0,0,AU7,0,0,0,0,0,0,0,0,0,0,0,0,0)';
      PINUSE='POWER';
      NO_LOAD_CHECK='Both';
      NO_IO_CHECK='Both';
      NO_ASSERT_CHECK='TRUE';
      NO_DIR_CHECK='TRUE';
      ALLOW_CONNECT='TRUE';
    'VCCD_HV4':
      PIN_NUMBER='(0,0,0,0,0,0,0,0,0,0,0,0,0,0,0,0,0,0,0,0,0,0,0,0,0,0,0,0,AU54,0,0,0,0,0,0,0,0,0,0,0,0,0)';
      PINUSE='POWER';
      NO_LOAD_CHECK='Both';
      NO_IO_CHECK='Both';
      NO_ASSERT_CHECK='TRUE';
      NO_DIR_CHECK='TRUE';
      ALLOW_CONNECT='TRUE';
    'VCCD_HV3':
      PIN_NUMBER='(0,0,0,0,0,0,0,0,0,0,0,0,0,0,0,0,0,0,0,0,0,0,0,0,0,0,0,0,AU35,0,0,0,0,0,0,0,0,0,0,0,0,0)';
      PINUSE='POWER';
      NO_LOAD_CHECK='Both';
      NO_IO_CHECK='Both';
      NO_ASSERT_CHECK='TRUE';
      NO_DIR_CHECK='TRUE';
      ALLOW_CONNECT='TRUE';
    'VCCD_HV2':
      PIN_NUMBER='(0,0,0,0,0,0,0,0,0,0,0,0,0,0,0,0,0,0,0,0,0,0,0,0,0,0,0,0,AU3,0,0,0,0,0,0,0,0,0,0,0,0,0)';
      PINUSE='POWER';
      NO_LOAD_CHECK='Both';
      NO_IO_CHECK='Both';
      NO_ASSERT_CHECK='TRUE';
      NO_DIR_CHECK='TRUE';
      ALLOW_CONNECT='TRUE';
    'VCCD_HV1':
      PIN_NUMBER='(0,0,0,0,0,0,0,0,0,0,0,0,0,0,0,0,0,0,0,0,0,0,0,0,0,0,0,0,AT55,0,0,0,0,0,0,0,0,0,0,0,0,0)';
      PINUSE='POWER';
      NO_LOAD_CHECK='Both';
      NO_IO_CHECK='Both';
      NO_ASSERT_CHECK='TRUE';
      NO_DIR_CHECK='TRUE';
      ALLOW_CONNECT='TRUE';
    'VCCD_HV0':
      PIN_NUMBER='(0,0,0,0,0,0,0,0,0,0,0,0,0,0,0,0,0,0,0,0,0,0,0,0,0,0,0,0,AT36,0,0,0,0,0,0,0,0,0,0,0,0,0)';
      PINUSE='POWER';
      NO_LOAD_CHECK='Both';
      NO_IO_CHECK='Both';
      NO_ASSERT_CHECK='TRUE';
      NO_DIR_CHECK='TRUE';
      ALLOW_CONNECT='TRUE';
    'VCCFA_EHV8':
      PIN_NUMBER='(0,0,0,0,0,0,0,0,0,0,0,0,0,0,0,0,0,0,0,0,0,0,0,0,0,0,0,0,N3,0,0,0,0,0,0,0,0,0,0,0,0,0)';
      PINUSE='POWER';
      NO_LOAD_CHECK='Both';
      NO_IO_CHECK='Both';
      NO_ASSERT_CHECK='TRUE';
      NO_DIR_CHECK='TRUE';
      ALLOW_CONNECT='TRUE';
    'VCCFA_EHV9':
      PIN_NUMBER='(0,0,0,0,0,0,0,0,0,0,0,0,0,0,0,0,0,0,0,0,0,0,0,0,0,0,0,0,U3,0,0,0,0,0,0,0,0,0,0,0,0,0)';
      PINUSE='POWER';
      NO_LOAD_CHECK='Both';
      NO_IO_CHECK='Both';
      NO_ASSERT_CHECK='TRUE';
      NO_DIR_CHECK='TRUE';
      ALLOW_CONNECT='TRUE';
    'VCCFA_EHV7':
      PIN_NUMBER='(0,0,0,0,0,0,0,0,0,0,0,0,0,0,0,0,0,0,0,0,0,0,0,0,0,0,0,0,AW60,0,0,0,0,0,0,0,0,0,0,0,0,0)';
      PINUSE='POWER';
      NO_LOAD_CHECK='Both';
      NO_IO_CHECK='Both';
      NO_ASSERT_CHECK='TRUE';
      NO_DIR_CHECK='TRUE';
      ALLOW_CONNECT='TRUE';
    'VCCFA_EHV6':
      PIN_NUMBER='(0,0,0,0,0,0,0,0,0,0,0,0,0,0,0,0,0,0,0,0,0,0,0,0,0,0,0,0,AV61,0,0,0,0,0,0,0,0,0,0,0,0,0)';
      PINUSE='POWER';
      NO_LOAD_CHECK='Both';
      NO_IO_CHECK='Both';
      NO_ASSERT_CHECK='TRUE';
      NO_DIR_CHECK='TRUE';
      ALLOW_CONNECT='TRUE';
    'VCCFA_EHV5':
      PIN_NUMBER='(0,0,0,0,0,0,0,0,0,0,0,0,0,0,0,0,0,0,0,0,0,0,0,0,0,0,0,0,AU60,0,0,0,0,0,0,0,0,0,0,0,0,0)';
      PINUSE='POWER';
      NO_LOAD_CHECK='Both';
      NO_IO_CHECK='Both';
      NO_ASSERT_CHECK='TRUE';
      NO_DIR_CHECK='TRUE';
      ALLOW_CONNECT='TRUE';
    'VCCFA_EHV4':
      PIN_NUMBER='(0,0,0,0,0,0,0,0,0,0,0,0,0,0,0,0,0,0,0,0,0,0,0,0,0,0,0,0,AT61,0,0,0,0,0,0,0,0,0,0,0,0,0)';
      PINUSE='POWER';
      NO_LOAD_CHECK='Both';
      NO_IO_CHECK='Both';
      NO_ASSERT_CHECK='TRUE';
      NO_DIR_CHECK='TRUE';
      ALLOW_CONNECT='TRUE';
    'VCCFA_EHV3':
      PIN_NUMBER='(0,0,0,0,0,0,0,0,0,0,0,0,0,0,0,0,0,0,0,0,0,0,0,0,0,0,0,0,AN3,0,0,0,0,0,0,0,0,0,0,0,0,0)';
      PINUSE='POWER';
      NO_LOAD_CHECK='Both';
      NO_IO_CHECK='Both';
      NO_ASSERT_CHECK='TRUE';
      NO_DIR_CHECK='TRUE';
      ALLOW_CONNECT='TRUE';
    'VCCFA_EHV2':
      PIN_NUMBER='(0,0,0,0,0,0,0,0,0,0,0,0,0,0,0,0,0,0,0,0,0,0,0,0,0,0,0,0,AJ3,0,0,0,0,0,0,0,0,0,0,0,0,0)';
      PINUSE='POWER';
      NO_LOAD_CHECK='Both';
      NO_IO_CHECK='Both';
      NO_ASSERT_CHECK='TRUE';
      NO_DIR_CHECK='TRUE';
      ALLOW_CONNECT='TRUE';
    'VCCFA_EHV1':
      PIN_NUMBER='(0,0,0,0,0,0,0,0,0,0,0,0,0,0,0,0,0,0,0,0,0,0,0,0,0,0,0,0,AE3,0,0,0,0,0,0,0,0,0,0,0,0,0)';
      PINUSE='POWER';
      NO_LOAD_CHECK='Both';
      NO_IO_CHECK='Both';
      NO_ASSERT_CHECK='TRUE';
      NO_DIR_CHECK='TRUE';
      ALLOW_CONNECT='TRUE';
    'VCCFA_EHV0':
      PIN_NUMBER='(0,0,0,0,0,0,0,0,0,0,0,0,0,0,0,0,0,0,0,0,0,0,0,0,0,0,0,0,AA3,0,0,0,0,0,0,0,0,0,0,0,0,0)';
      PINUSE='POWER';
      NO_LOAD_CHECK='Both';
      NO_IO_CHECK='Both';
      NO_ASSERT_CHECK='TRUE';
      NO_DIR_CHECK='TRUE';
      ALLOW_CONNECT='TRUE';
    'VCCINFAON59':
      PIN_NUMBER='(0,0,0,0,0,0,0,0,0,0,0,0,0,0,0,0,0,0,0,0,0,0,0,0,0,0,0,0,DJ11,0,0,0,0,0,0,0,0,0,0,0,0,0)';
      PINUSE='POWER';
      NO_LOAD_CHECK='Both';
      NO_IO_CHECK='Both';
      NO_ASSERT_CHECK='TRUE';
      NO_DIR_CHECK='TRUE';
      ALLOW_CONNECT='TRUE';
    'VCCINFAON58':
      PIN_NUMBER='(0,0,0,0,0,0,0,0,0,0,0,0,0,0,0,0,0,0,0,0,0,0,0,0,0,0,0,0,DE7,0,0,0,0,0,0,0,0,0,0,0,0,0)';
      PINUSE='POWER';
      NO_LOAD_CHECK='Both';
      NO_IO_CHECK='Both';
      NO_ASSERT_CHECK='TRUE';
      NO_DIR_CHECK='TRUE';
      ALLOW_CONNECT='TRUE';
    'VCCINFAON57':
      PIN_NUMBER='(0,0,0,0,0,0,0,0,0,0,0,0,0,0,0,0,0,0,0,0,0,0,0,0,0,0,0,0,DA7,0,0,0,0,0,0,0,0,0,0,0,0,0)';
      PINUSE='POWER';
      NO_LOAD_CHECK='Both';
      NO_IO_CHECK='Both';
      NO_ASSERT_CHECK='TRUE';
      NO_DIR_CHECK='TRUE';
      ALLOW_CONNECT='TRUE';
    'VCCINFAON56':
      PIN_NUMBER='(0,0,0,0,0,0,0,0,0,0,0,0,0,0,0,0,0,0,0,0,0,0,0,0,0,0,0,0,DA3,0,0,0,0,0,0,0,0,0,0,0,0,0)';
      PINUSE='POWER';
      NO_LOAD_CHECK='Both';
      NO_IO_CHECK='Both';
      NO_ASSERT_CHECK='TRUE';
      NO_DIR_CHECK='TRUE';
      ALLOW_CONNECT='TRUE';
    'VCCINFAON55':
      PIN_NUMBER='(0,0,0,0,0,0,0,0,0,0,0,0,0,0,0,0,0,0,0,0,0,0,0,0,0,0,0,0,CW64,0,0,0,0,0,0,0,0,0,0,0,0,0)';
      PINUSE='POWER';
      NO_LOAD_CHECK='Both';
      NO_IO_CHECK='Both';
      NO_ASSERT_CHECK='TRUE';
      NO_DIR_CHECK='TRUE';
      ALLOW_CONNECT='TRUE';
    'VCCINFAON54':
      PIN_NUMBER='(0,0,0,0,0,0,0,0,0,0,0,0,0,0,0,0,0,0,0,0,0,0,0,0,0,0,0,0,CR66,0,0,0,0,0,0,0,0,0,0,0,0,0)';
      PINUSE='POWER';
      NO_LOAD_CHECK='Both';
      NO_IO_CHECK='Both';
      NO_ASSERT_CHECK='TRUE';
      NO_DIR_CHECK='TRUE';
      ALLOW_CONNECT='TRUE';
    'VCCINFAON32':
      PIN_NUMBER='(0,0,0,0,0,0,0,0,0,0,0,0,0,0,0,0,0,0,0,0,0,0,0,0,0,0,0,0,DJ7,0,0,0,0,0,0,0,0,0,0,0,0,0)';
      PINUSE='POWER';
      NO_LOAD_CHECK='Both';
      NO_IO_CHECK='Both';
      NO_ASSERT_CHECK='TRUE';
      NO_DIR_CHECK='TRUE';
      ALLOW_CONNECT='TRUE';
    'VCCINFAON31':
      PIN_NUMBER='(0,0,0,0,0,0,0,0,0,0,0,0,0,0,0,0,0,0,0,0,0,0,0,0,0,0,0,0,DJ3,0,0,0,0,0,0,0,0,0,0,0,0,0)';
      PINUSE='POWER';
      NO_LOAD_CHECK='Both';
      NO_IO_CHECK='Both';
      NO_ASSERT_CHECK='TRUE';
      NO_DIR_CHECK='TRUE';
      ALLOW_CONNECT='TRUE';
    'VCCINFAON30':
      PIN_NUMBER='(0,0,0,0,0,0,0,0,0,0,0,0,0,0,0,0,0,0,0,0,0,0,0,0,0,0,0,0,DJ15,0,0,0,0,0,0,0,0,0,0,0,0,0)';
      PINUSE='POWER';
      NO_LOAD_CHECK='Both';
      NO_IO_CHECK='Both';
      NO_ASSERT_CHECK='TRUE';
      NO_DIR_CHECK='TRUE';
      ALLOW_CONNECT='TRUE';
    'VCCINFAON29':
      PIN_NUMBER='(0,0,0,0,0,0,0,0,0,0,0,0,0,0,0,0,0,0,0,0,0,0,0,0,0,0,0,0,DE3,0,0,0,0,0,0,0,0,0,0,0,0,0)';
      PINUSE='POWER';
      NO_LOAD_CHECK='Both';
      NO_IO_CHECK='Both';
      NO_ASSERT_CHECK='TRUE';
      NO_DIR_CHECK='TRUE';
      ALLOW_CONNECT='TRUE';
    'VCCINFAON28':
      PIN_NUMBER='(0,0,0,0,0,0,0,0,0,0,0,0,0,0,0,0,0,0,0,0,0,0,0,0,0,0,0,0,DE15,0,0,0,0,0,0,0,0,0,0,0,0,0)';
      PINUSE='POWER';
      NO_LOAD_CHECK='Both';
      NO_IO_CHECK='Both';
      NO_ASSERT_CHECK='TRUE';
      NO_DIR_CHECK='TRUE';
      ALLOW_CONNECT='TRUE';
    'VCCINFAON27':
      PIN_NUMBER='(0,0,0,0,0,0,0,0,0,0,0,0,0,0,0,0,0,0,0,0,0,0,0,0,0,0,0,0,DE11,0,0,0,0,0,0,0,0,0,0,0,0,0)';
      PINUSE='POWER';
      NO_LOAD_CHECK='Both';
      NO_IO_CHECK='Both';
      NO_ASSERT_CHECK='TRUE';
      NO_DIR_CHECK='TRUE';
      ALLOW_CONNECT='TRUE';
    'VCCINFAON26':
      PIN_NUMBER='(0,0,0,0,0,0,0,0,0,0,0,0,0,0,0,0,0,0,0,0,0,0,0,0,0,0,0,0,DA64,0,0,0,0,0,0,0,0,0,0,0,0,0)';
      PINUSE='POWER';
      NO_LOAD_CHECK='Both';
      NO_IO_CHECK='Both';
      NO_ASSERT_CHECK='TRUE';
      NO_DIR_CHECK='TRUE';
      ALLOW_CONNECT='TRUE';
    'VCCINFAON25':
      PIN_NUMBER='(0,0,0,0,0,0,0,0,0,0,0,0,0,0,0,0,0,0,0,0,0,0,0,0,0,0,0,0,DA15,0,0,0,0,0,0,0,0,0,0,0,0,0)';
      PINUSE='POWER';
      NO_LOAD_CHECK='Both';
      NO_IO_CHECK='Both';
      NO_ASSERT_CHECK='TRUE';
      NO_DIR_CHECK='TRUE';
      ALLOW_CONNECT='TRUE';
    'VCCINFAON24':
      PIN_NUMBER='(0,0,0,0,0,0,0,0,0,0,0,0,0,0,0,0,0,0,0,0,0,0,0,0,0,0,0,0,DA11,0,0,0,0,0,0,0,0,0,0,0,0,0)';
      PINUSE='POWER';
      NO_LOAD_CHECK='Both';
      NO_IO_CHECK='Both';
      NO_ASSERT_CHECK='TRUE';
      NO_DIR_CHECK='TRUE';
      ALLOW_CONNECT='TRUE';
    'VCCINFAON23':
      PIN_NUMBER='(0,0,0,0,0,0,0,0,0,0,0,0,0,0,0,0,0,0,0,0,0,0,0,0,0,0,0,0,CY67,0,0,0,0,0,0,0,0,0,0,0,0,0)';
      PINUSE='POWER';
      NO_LOAD_CHECK='Both';
      NO_IO_CHECK='Both';
      NO_ASSERT_CHECK='TRUE';
      NO_DIR_CHECK='TRUE';
      ALLOW_CONNECT='TRUE';
    'VCCINFAON22':
      PIN_NUMBER='(0,0,0,0,0,0,0,0,0,0,0,0,0,0,0,0,0,0,0,0,0,0,0,0,0,0,0,0,CY65,0,0,0,0,0,0,0,0,0,0,0,0,0)';
      PINUSE='POWER';
      NO_LOAD_CHECK='Both';
      NO_IO_CHECK='Both';
      NO_ASSERT_CHECK='TRUE';
      NO_DIR_CHECK='TRUE';
      ALLOW_CONNECT='TRUE';
    'VCCINFAON21':
      PIN_NUMBER='(0,0,0,0,0,0,0,0,0,0,0,0,0,0,0,0,0,0,0,0,0,0,0,0,0,0,0,0,CW66,0,0,0,0,0,0,0,0,0,0,0,0,0)';
      PINUSE='POWER';
      NO_LOAD_CHECK='Both';
      NO_IO_CHECK='Both';
      NO_ASSERT_CHECK='TRUE';
      NO_DIR_CHECK='TRUE';
      ALLOW_CONNECT='TRUE';
    'VCCINFAON20':
      PIN_NUMBER='(0,0,0,0,0,0,0,0,0,0,0,0,0,0,0,0,0,0,0,0,0,0,0,0,0,0,0,0,CV67,0,0,0,0,0,0,0,0,0,0,0,0,0)';
      PINUSE='POWER';
      NO_LOAD_CHECK='Both';
      NO_IO_CHECK='Both';
      NO_ASSERT_CHECK='TRUE';
      NO_DIR_CHECK='TRUE';
      ALLOW_CONNECT='TRUE';
    'VCCINFAON19':
      PIN_NUMBER='(0,0,0,0,0,0,0,0,0,0,0,0,0,0,0,0,0,0,0,0,0,0,0,0,0,0,0,0,CV65,0,0,0,0,0,0,0,0,0,0,0,0,0)';
      PINUSE='POWER';
      NO_LOAD_CHECK='Both';
      NO_IO_CHECK='Both';
      NO_ASSERT_CHECK='TRUE';
      NO_DIR_CHECK='TRUE';
      ALLOW_CONNECT='TRUE';
    'VCCINFAON18':
      PIN_NUMBER='(0,0,0,0,0,0,0,0,0,0,0,0,0,0,0,0,0,0,0,0,0,0,0,0,0,0,0,0,CU7,0,0,0,0,0,0,0,0,0,0,0,0,0)';
      PINUSE='POWER';
      NO_LOAD_CHECK='Both';
      NO_IO_CHECK='Both';
      NO_ASSERT_CHECK='TRUE';
      NO_DIR_CHECK='TRUE';
      ALLOW_CONNECT='TRUE';
    'VCCINFAON17':
      PIN_NUMBER='(0,0,0,0,0,0,0,0,0,0,0,0,0,0,0,0,0,0,0,0,0,0,0,0,0,0,0,0,CU64,0,0,0,0,0,0,0,0,0,0,0,0,0)';
      PINUSE='POWER';
      NO_LOAD_CHECK='Both';
      NO_IO_CHECK='Both';
      NO_ASSERT_CHECK='TRUE';
      NO_DIR_CHECK='TRUE';
      ALLOW_CONNECT='TRUE';
    'VCCINFAON16':
      PIN_NUMBER='(0,0,0,0,0,0,0,0,0,0,0,0,0,0,0,0,0,0,0,0,0,0,0,0,0,0,0,0,CU3,0,0,0,0,0,0,0,0,0,0,0,0,0)';
      PINUSE='POWER';
      NO_LOAD_CHECK='Both';
      NO_IO_CHECK='Both';
      NO_ASSERT_CHECK='TRUE';
      NO_DIR_CHECK='TRUE';
      ALLOW_CONNECT='TRUE';
    'VCCINFAON15':
      PIN_NUMBER='(0,0,0,0,0,0,0,0,0,0,0,0,0,0,0,0,0,0,0,0,0,0,0,0,0,0,0,0,CU15,0,0,0,0,0,0,0,0,0,0,0,0,0)';
      PINUSE='POWER';
      NO_LOAD_CHECK='Both';
      NO_IO_CHECK='Both';
      NO_ASSERT_CHECK='TRUE';
      NO_DIR_CHECK='TRUE';
      ALLOW_CONNECT='TRUE';
    'VCCINFAON14':
      PIN_NUMBER='(0,0,0,0,0,0,0,0,0,0,0,0,0,0,0,0,0,0,0,0,0,0,0,0,0,0,0,0,CU11,0,0,0,0,0,0,0,0,0,0,0,0,0)';
      PINUSE='POWER';
      NO_LOAD_CHECK='Both';
      NO_IO_CHECK='Both';
      NO_ASSERT_CHECK='TRUE';
      NO_DIR_CHECK='TRUE';
      ALLOW_CONNECT='TRUE';
    'VCCINFAON13':
      PIN_NUMBER='(0,0,0,0,0,0,0,0,0,0,0,0,0,0,0,0,0,0,0,0,0,0,0,0,0,0,0,0,CT67,0,0,0,0,0,0,0,0,0,0,0,0,0)';
      PINUSE='POWER';
      NO_LOAD_CHECK='Both';
      NO_IO_CHECK='Both';
      NO_ASSERT_CHECK='TRUE';
      NO_DIR_CHECK='TRUE';
      ALLOW_CONNECT='TRUE';
    'VCCINFAON12':
      PIN_NUMBER='(0,0,0,0,0,0,0,0,0,0,0,0,0,0,0,0,0,0,0,0,0,0,0,0,0,0,0,0,CT65,0,0,0,0,0,0,0,0,0,0,0,0,0)';
      PINUSE='POWER';
      NO_LOAD_CHECK='Both';
      NO_IO_CHECK='Both';
      NO_ASSERT_CHECK='TRUE';
      NO_DIR_CHECK='TRUE';
      ALLOW_CONNECT='TRUE';
    'VCCINFAON11':
      PIN_NUMBER='(0,0,0,0,0,0,0,0,0,0,0,0,0,0,0,0,0,0,0,0,0,0,0,0,0,0,0,0,CP67,0,0,0,0,0,0,0,0,0,0,0,0,0)';
      PINUSE='POWER';
      NO_LOAD_CHECK='Both';
      NO_IO_CHECK='Both';
      NO_ASSERT_CHECK='TRUE';
      NO_DIR_CHECK='TRUE';
      ALLOW_CONNECT='TRUE';
    'VCCINFAON10':
      PIN_NUMBER='(0,0,0,0,0,0,0,0,0,0,0,0,0,0,0,0,0,0,0,0,0,0,0,0,0,0,0,0,CP65,0,0,0,0,0,0,0,0,0,0,0,0,0)';
      PINUSE='POWER';
      NO_LOAD_CHECK='Both';
      NO_IO_CHECK='Both';
      NO_ASSERT_CHECK='TRUE';
      NO_DIR_CHECK='TRUE';
      ALLOW_CONNECT='TRUE';
    'VCCINFAON9':
      PIN_NUMBER='(0,0,0,0,0,0,0,0,0,0,0,0,0,0,0,0,0,0,0,0,0,0,0,0,0,0,0,0,CN7,0,0,0,0,0,0,0,0,0,0,0,0,0)';
      PINUSE='POWER';
      NO_LOAD_CHECK='Both';
      NO_IO_CHECK='Both';
      NO_ASSERT_CHECK='TRUE';
      NO_DIR_CHECK='TRUE';
      ALLOW_CONNECT='TRUE';
    'VCCINFAON8':
      PIN_NUMBER='(0,0,0,0,0,0,0,0,0,0,0,0,0,0,0,0,0,0,0,0,0,0,0,0,0,0,0,0,CN66,0,0,0,0,0,0,0,0,0,0,0,0,0)';
      PINUSE='POWER';
      NO_LOAD_CHECK='Both';
      NO_IO_CHECK='Both';
      NO_ASSERT_CHECK='TRUE';
      NO_DIR_CHECK='TRUE';
      ALLOW_CONNECT='TRUE';
    'VCCINFAON7':
      PIN_NUMBER='(0,0,0,0,0,0,0,0,0,0,0,0,0,0,0,0,0,0,0,0,0,0,0,0,0,0,0,0,CN64,0,0,0,0,0,0,0,0,0,0,0,0,0)';
      PINUSE='POWER';
      NO_LOAD_CHECK='Both';
      NO_IO_CHECK='Both';
      NO_ASSERT_CHECK='TRUE';
      NO_DIR_CHECK='TRUE';
      ALLOW_CONNECT='TRUE';
    'VCCINFAON6':
      PIN_NUMBER='(0,0,0,0,0,0,0,0,0,0,0,0,0,0,0,0,0,0,0,0,0,0,0,0,0,0,0,0,CN3,0,0,0,0,0,0,0,0,0,0,0,0,0)';
      PINUSE='POWER';
      NO_LOAD_CHECK='Both';
      NO_IO_CHECK='Both';
      NO_ASSERT_CHECK='TRUE';
      NO_DIR_CHECK='TRUE';
      ALLOW_CONNECT='TRUE';
    'VCCINFAON5':
      PIN_NUMBER='(0,0,0,0,0,0,0,0,0,0,0,0,0,0,0,0,0,0,0,0,0,0,0,0,0,0,0,0,CN15,0,0,0,0,0,0,0,0,0,0,0,0,0)';
      PINUSE='POWER';
      NO_LOAD_CHECK='Both';
      NO_IO_CHECK='Both';
      NO_ASSERT_CHECK='TRUE';
      NO_DIR_CHECK='TRUE';
      ALLOW_CONNECT='TRUE';
    'VCCINFAON4':
      PIN_NUMBER='(0,0,0,0,0,0,0,0,0,0,0,0,0,0,0,0,0,0,0,0,0,0,0,0,0,0,0,0,CN11,0,0,0,0,0,0,0,0,0,0,0,0,0)';
      PINUSE='POWER';
      NO_LOAD_CHECK='Both';
      NO_IO_CHECK='Both';
      NO_ASSERT_CHECK='TRUE';
      NO_DIR_CHECK='TRUE';
      ALLOW_CONNECT='TRUE';
    'VCCINFAON3':
      PIN_NUMBER='(0,0,0,0,0,0,0,0,0,0,0,0,0,0,0,0,0,0,0,0,0,0,0,0,0,0,0,0,CJ7,0,0,0,0,0,0,0,0,0,0,0,0,0)';
      PINUSE='POWER';
      NO_LOAD_CHECK='Both';
      NO_IO_CHECK='Both';
      NO_ASSERT_CHECK='TRUE';
      NO_DIR_CHECK='TRUE';
      ALLOW_CONNECT='TRUE';
    'VCCINFAON2':
      PIN_NUMBER='(0,0,0,0,0,0,0,0,0,0,0,0,0,0,0,0,0,0,0,0,0,0,0,0,0,0,0,0,CJ3,0,0,0,0,0,0,0,0,0,0,0,0,0)';
      PINUSE='POWER';
      NO_LOAD_CHECK='Both';
      NO_IO_CHECK='Both';
      NO_ASSERT_CHECK='TRUE';
      NO_DIR_CHECK='TRUE';
      ALLOW_CONNECT='TRUE';
    'VCCINFAON1':
      PIN_NUMBER='(0,0,0,0,0,0,0,0,0,0,0,0,0,0,0,0,0,0,0,0,0,0,0,0,0,0,0,0,CJ15,0,0,0,0,0,0,0,0,0,0,0,0,0)';
      PINUSE='POWER';
      NO_LOAD_CHECK='Both';
      NO_IO_CHECK='Both';
      NO_ASSERT_CHECK='TRUE';
      NO_DIR_CHECK='TRUE';
      ALLOW_CONNECT='TRUE';
    'VCCINFAON0':
      PIN_NUMBER='(0,0,0,0,0,0,0,0,0,0,0,0,0,0,0,0,0,0,0,0,0,0,0,0,0,0,0,0,CE15,0,0,0,0,0,0,0,0,0,0,0,0,0)';
      PINUSE='POWER';
      NO_LOAD_CHECK='Both';
      NO_IO_CHECK='Both';
      NO_ASSERT_CHECK='TRUE';
      NO_DIR_CHECK='TRUE';
      ALLOW_CONNECT='TRUE';
    'VCCVNN3':
      PIN_NUMBER='(0,0,0,0,0,0,0,0,0,0,0,0,0,0,0,0,0,0,0,0,0,0,0,0,0,0,0,0,BN19,0,0,0,0,0,0,0,0,0,0,0,0,0)';
      PINUSE='POWER';
      NO_LOAD_CHECK='Both';
      NO_IO_CHECK='Both';
      NO_ASSERT_CHECK='TRUE';
      NO_DIR_CHECK='TRUE';
      ALLOW_CONNECT='TRUE';
    'VCCVNN2':
      PIN_NUMBER='(0,0,0,0,0,0,0,0,0,0,0,0,0,0,0,0,0,0,0,0,0,0,0,0,0,0,0,0,BJ19,0,0,0,0,0,0,0,0,0,0,0,0,0)';
      PINUSE='POWER';
      NO_LOAD_CHECK='Both';
      NO_IO_CHECK='Both';
      NO_ASSERT_CHECK='TRUE';
      NO_DIR_CHECK='TRUE';
      ALLOW_CONNECT='TRUE';
    'VCCVNN1':
      PIN_NUMBER='(0,0,0,0,0,0,0,0,0,0,0,0,0,0,0,0,0,0,0,0,0,0,0,0,0,0,0,0,BE19,0,0,0,0,0,0,0,0,0,0,0,0,0)';
      PINUSE='POWER';
      NO_LOAD_CHECK='Both';
      NO_IO_CHECK='Both';
      NO_ASSERT_CHECK='TRUE';
      NO_DIR_CHECK='TRUE';
      ALLOW_CONNECT='TRUE';
    'VCCVNN0':
      PIN_NUMBER='(0,0,0,0,0,0,0,0,0,0,0,0,0,0,0,0,0,0,0,0,0,0,0,0,0,0,0,0,BA19,0,0,0,0,0,0,0,0,0,0,0,0,0)';
      PINUSE='POWER';
      NO_LOAD_CHECK='Both';
      NO_IO_CHECK='Both';
      NO_ASSERT_CHECK='TRUE';
      NO_DIR_CHECK='TRUE';
      ALLOW_CONNECT='TRUE';
    'VPP_HBM':
      PIN_NUMBER='(0,0,0,0,0,0,0,0,0,0,0,0,0,0,0,0,0,0,0,0,0,0,0,0,0,0,0,0,CG68,0,0,0,0,0,0,0,0,0,0,0,0,0)';
      PINUSE='POWER';
      NO_LOAD_CHECK='Both';
      NO_IO_CHECK='Both';
      NO_ASSERT_CHECK='TRUE';
      NO_DIR_CHECK='TRUE';
      ALLOW_CONNECT='TRUE';
    'VPP_HBM1':
      PIN_NUMBER='(0,0,0,0,0,0,0,0,0,0,0,0,0,0,0,0,0,0,0,0,0,0,0,0,0,0,0,0,CF67,0,0,0,0,0,0,0,0,0,0,0,0,0)';
      PINUSE='POWER';
      NO_LOAD_CHECK='Both';
      NO_IO_CHECK='Both';
      NO_ASSERT_CHECK='TRUE';
      NO_DIR_CHECK='TRUE';
      ALLOW_CONNECT='TRUE';
    'VPP_HBM2':
      PIN_NUMBER='(0,0,0,0,0,0,0,0,0,0,0,0,0,0,0,0,0,0,0,0,0,0,0,0,0,0,0,0,CE68,0,0,0,0,0,0,0,0,0,0,0,0,0)';
      PINUSE='POWER';
      NO_LOAD_CHECK='Both';
      NO_IO_CHECK='Both';
      NO_ASSERT_CHECK='TRUE';
      NO_DIR_CHECK='TRUE';
      ALLOW_CONNECT='TRUE';
    'VPP_HBM3':
      PIN_NUMBER='(0,0,0,0,0,0,0,0,0,0,0,0,0,0,0,0,0,0,0,0,0,0,0,0,0,0,0,0,CD67,0,0,0,0,0,0,0,0,0,0,0,0,0)';
      PINUSE='POWER';
      NO_LOAD_CHECK='Both';
      NO_IO_CHECK='Both';
      NO_ASSERT_CHECK='TRUE';
      NO_DIR_CHECK='TRUE';
      ALLOW_CONNECT='TRUE';
    'VPP_HBM4':
      PIN_NUMBER='(0,0,0,0,0,0,0,0,0,0,0,0,0,0,0,0,0,0,0,0,0,0,0,0,0,0,0,0,CC68,0,0,0,0,0,0,0,0,0,0,0,0,0)';
      PINUSE='POWER';
      NO_LOAD_CHECK='Both';
      NO_IO_CHECK='Both';
      NO_ASSERT_CHECK='TRUE';
      NO_DIR_CHECK='TRUE';
      ALLOW_CONNECT='TRUE';
    'VCCFA_EHV_FIVRA104':
      PIN_NUMBER='(0,0,0,0,0,0,0,0,0,0,0,0,0,0,0,0,0,0,0,0,0,0,0,0,0,0,0,0,0,Y89,0,0,0,0,0,0,0,0,0,0,0,0)';
      PINUSE='POWER';
      NO_LOAD_CHECK='Both';
      NO_IO_CHECK='Both';
      NO_ASSERT_CHECK='TRUE';
      NO_DIR_CHECK='TRUE';
      ALLOW_CONNECT='TRUE';
    'VCCFA_EHV_FIVRA103':
      PIN_NUMBER='(0,0,0,0,0,0,0,0,0,0,0,0,0,0,0,0,0,0,0,0,0,0,0,0,0,0,0,0,0,Y85,0,0,0,0,0,0,0,0,0,0,0,0)';
      PINUSE='POWER';
      NO_LOAD_CHECK='Both';
      NO_IO_CHECK='Both';
      NO_ASSERT_CHECK='TRUE';
      NO_DIR_CHECK='TRUE';
      ALLOW_CONNECT='TRUE';
    'VCCFA_EHV_FIVRA102':
      PIN_NUMBER='(0,0,0,0,0,0,0,0,0,0,0,0,0,0,0,0,0,0,0,0,0,0,0,0,0,0,0,0,0,Y79,0,0,0,0,0,0,0,0,0,0,0,0)';
      PINUSE='POWER';
      NO_LOAD_CHECK='Both';
      NO_IO_CHECK='Both';
      NO_ASSERT_CHECK='TRUE';
      NO_DIR_CHECK='TRUE';
      ALLOW_CONNECT='TRUE';
    'VCCFA_EHV_FIVRA101':
      PIN_NUMBER='(0,0,0,0,0,0,0,0,0,0,0,0,0,0,0,0,0,0,0,0,0,0,0,0,0,0,0,0,0,W80,0,0,0,0,0,0,0,0,0,0,0,0)';
      PINUSE='POWER';
      NO_LOAD_CHECK='Both';
      NO_IO_CHECK='Both';
      NO_ASSERT_CHECK='TRUE';
      NO_DIR_CHECK='TRUE';
      ALLOW_CONNECT='TRUE';
    'VCCFA_EHV_FIVRA100':
      PIN_NUMBER='(0,0,0,0,0,0,0,0,0,0,0,0,0,0,0,0,0,0,0,0,0,0,0,0,0,0,0,0,0,U7,0,0,0,0,0,0,0,0,0,0,0,0)';
      PINUSE='POWER';
      NO_LOAD_CHECK='Both';
      NO_IO_CHECK='Both';
      NO_ASSERT_CHECK='TRUE';
      NO_DIR_CHECK='TRUE';
      ALLOW_CONNECT='TRUE';
    'VCCFA_EHV_FIVRA99':
      PIN_NUMBER='(0,0,0,0,0,0,0,0,0,0,0,0,0,0,0,0,0,0,0,0,0,0,0,0,0,0,0,0,0,U15,0,0,0,0,0,0,0,0,0,0,0,0)';
      PINUSE='POWER';
      NO_LOAD_CHECK='Both';
      NO_IO_CHECK='Both';
      NO_ASSERT_CHECK='TRUE';
      NO_DIR_CHECK='TRUE';
      ALLOW_CONNECT='TRUE';
    'VCCFA_EHV_FIVRA98':
      PIN_NUMBER='(0,0,0,0,0,0,0,0,0,0,0,0,0,0,0,0,0,0,0,0,0,0,0,0,0,0,0,0,0,U11,0,0,0,0,0,0,0,0,0,0,0,0)';
      PINUSE='POWER';
      NO_LOAD_CHECK='Both';
      NO_IO_CHECK='Both';
      NO_ASSERT_CHECK='TRUE';
      NO_DIR_CHECK='TRUE';
      ALLOW_CONNECT='TRUE';
    'VCCFA_EHV_FIVRA97':
      PIN_NUMBER='(0,0,0,0,0,0,0,0,0,0,0,0,0,0,0,0,0,0,0,0,0,0,0,0,0,0,0,0,0,T89,0,0,0,0,0,0,0,0,0,0,0,0)';
      PINUSE='POWER';
      NO_LOAD_CHECK='Both';
      NO_IO_CHECK='Both';
      NO_ASSERT_CHECK='TRUE';
      NO_DIR_CHECK='TRUE';
      ALLOW_CONNECT='TRUE';
    'VCCFA_EHV_FIVRA96':
      PIN_NUMBER='(0,0,0,0,0,0,0,0,0,0,0,0,0,0,0,0,0,0,0,0,0,0,0,0,0,0,0,0,0,T85,0,0,0,0,0,0,0,0,0,0,0,0)';
      PINUSE='POWER';
      NO_LOAD_CHECK='Both';
      NO_IO_CHECK='Both';
      NO_ASSERT_CHECK='TRUE';
      NO_DIR_CHECK='TRUE';
      ALLOW_CONNECT='TRUE';
    'VCCFA_EHV_FIVRA95':
      PIN_NUMBER='(0,0,0,0,0,0,0,0,0,0,0,0,0,0,0,0,0,0,0,0,0,0,0,0,0,0,0,0,0,R80,0,0,0,0,0,0,0,0,0,0,0,0)';
      PINUSE='POWER';
      NO_LOAD_CHECK='Both';
      NO_IO_CHECK='Both';
      NO_ASSERT_CHECK='TRUE';
      NO_DIR_CHECK='TRUE';
      ALLOW_CONNECT='TRUE';
    'VCCFA_EHV_FIVRA94':
      PIN_NUMBER='(0,0,0,0,0,0,0,0,0,0,0,0,0,0,0,0,0,0,0,0,0,0,0,0,0,0,0,0,0,P79,0,0,0,0,0,0,0,0,0,0,0,0)';
      PINUSE='POWER';
      NO_LOAD_CHECK='Both';
      NO_IO_CHECK='Both';
      NO_ASSERT_CHECK='TRUE';
      NO_DIR_CHECK='TRUE';
      ALLOW_CONNECT='TRUE';
    'VCCFA_EHV_FIVRA93':
      PIN_NUMBER='(0,0,0,0,0,0,0,0,0,0,0,0,0,0,0,0,0,0,0,0,0,0,0,0,0,0,0,0,0,N7,0,0,0,0,0,0,0,0,0,0,0,0)';
      PINUSE='POWER';
      NO_LOAD_CHECK='Both';
      NO_IO_CHECK='Both';
      NO_ASSERT_CHECK='TRUE';
      NO_DIR_CHECK='TRUE';
      ALLOW_CONNECT='TRUE';
    'VCCFA_EHV_FIVRA92':
      PIN_NUMBER='(0,0,0,0,0,0,0,0,0,0,0,0,0,0,0,0,0,0,0,0,0,0,0,0,0,0,0,0,0,N11,0,0,0,0,0,0,0,0,0,0,0,0)';
      PINUSE='POWER';
      NO_LOAD_CHECK='Both';
      NO_IO_CHECK='Both';
      NO_ASSERT_CHECK='TRUE';
      NO_DIR_CHECK='TRUE';
      ALLOW_CONNECT='TRUE';
    'VCCFA_EHV_FIVRA91':
      PIN_NUMBER='(0,0,0,0,0,0,0,0,0,0,0,0,0,0,0,0,0,0,0,0,0,0,0,0,0,0,0,0,0,M89,0,0,0,0,0,0,0,0,0,0,0,0)';
      PINUSE='POWER';
      NO_LOAD_CHECK='Both';
      NO_IO_CHECK='Both';
      NO_ASSERT_CHECK='TRUE';
      NO_DIR_CHECK='TRUE';
      ALLOW_CONNECT='TRUE';
    'VCCFA_EHV_FIVRA90':
      PIN_NUMBER='(0,0,0,0,0,0,0,0,0,0,0,0,0,0,0,0,0,0,0,0,0,0,0,0,0,0,0,0,0,M85,0,0,0,0,0,0,0,0,0,0,0,0)';
      PINUSE='POWER';
      NO_LOAD_CHECK='Both';
      NO_IO_CHECK='Both';
      NO_ASSERT_CHECK='TRUE';
      NO_DIR_CHECK='TRUE';
      ALLOW_CONNECT='TRUE';
    'VCCFA_EHV_FIVRA89':
      PIN_NUMBER='(0,0,0,0,0,0,0,0,0,0,0,0,0,0,0,0,0,0,0,0,0,0,0,0,0,0,0,0,0,L84,0,0,0,0,0,0,0,0,0,0,0,0)';
      PINUSE='POWER';
      NO_LOAD_CHECK='Both';
      NO_IO_CHECK='Both';
      NO_ASSERT_CHECK='TRUE';
      NO_DIR_CHECK='TRUE';
      ALLOW_CONNECT='TRUE';
    'VCCFA_EHV_FIVRA88':
      PIN_NUMBER='(0,0,0,0,0,0,0,0,0,0,0,0,0,0,0,0,0,0,0,0,0,0,0,0,0,0,0,0,0,K87,0,0,0,0,0,0,0,0,0,0,0,0)';
      PINUSE='POWER';
      NO_LOAD_CHECK='Both';
      NO_IO_CHECK='Both';
      NO_ASSERT_CHECK='TRUE';
      NO_DIR_CHECK='TRUE';
      ALLOW_CONNECT='TRUE';
    'VCCFA_EHV_FIVRA87':
      PIN_NUMBER='(0,0,0,0,0,0,0,0,0,0,0,0,0,0,0,0,0,0,0,0,0,0,0,0,0,0,0,0,0,J80,0,0,0,0,0,0,0,0,0,0,0,0)';
      PINUSE='POWER';
      NO_LOAD_CHECK='Both';
      NO_IO_CHECK='Both';
      NO_ASSERT_CHECK='TRUE';
      NO_DIR_CHECK='TRUE';
      ALLOW_CONNECT='TRUE';
    'VCCFA_EHV_FIVRA86':
      PIN_NUMBER='(0,0,0,0,0,0,0,0,0,0,0,0,0,0,0,0,0,0,0,0,0,0,0,0,0,0,0,0,0,J7,0,0,0,0,0,0,0,0,0,0,0,0)';
      PINUSE='POWER';
      NO_LOAD_CHECK='Both';
      NO_IO_CHECK='Both';
      NO_ASSERT_CHECK='TRUE';
      NO_DIR_CHECK='TRUE';
      ALLOW_CONNECT='TRUE';
    'VCCFA_EHV_FIVRA85':
      PIN_NUMBER='(0,0,0,0,0,0,0,0,0,0,0,0,0,0,0,0,0,0,0,0,0,0,0,0,0,0,0,0,0,J11,0,0,0,0,0,0,0,0,0,0,0,0)';
      PINUSE='POWER';
      NO_LOAD_CHECK='Both';
      NO_IO_CHECK='Both';
      NO_ASSERT_CHECK='TRUE';
      NO_DIR_CHECK='TRUE';
      ALLOW_CONNECT='TRUE';
    'VCCFA_EHV_FIVRA84':
      PIN_NUMBER='(0,0,0,0,0,0,0,0,0,0,0,0,0,0,0,0,0,0,0,0,0,0,0,0,0,0,0,0,0,H89,0,0,0,0,0,0,0,0,0,0,0,0)';
      PINUSE='POWER';
      NO_LOAD_CHECK='Both';
      NO_IO_CHECK='Both';
      NO_ASSERT_CHECK='TRUE';
      NO_DIR_CHECK='TRUE';
      ALLOW_CONNECT='TRUE';
    'VCCFA_EHV_FIVRA83':
      PIN_NUMBER='(0,0,0,0,0,0,0,0,0,0,0,0,0,0,0,0,0,0,0,0,0,0,0,0,0,0,0,0,0,EN84,0,0,0,0,0,0,0,0,0,0,0,0)';
      PINUSE='POWER';
      NO_LOAD_CHECK='Both';
      NO_IO_CHECK='Both';
      NO_ASSERT_CHECK='TRUE';
      NO_DIR_CHECK='TRUE';
      ALLOW_CONNECT='TRUE';
    'VCCFA_EHV_FIVRA82':
      PIN_NUMBER='(0,0,0,0,0,0,0,0,0,0,0,0,0,0,0,0,0,0,0,0,0,0,0,0,0,0,0,0,0,EJ84,0,0,0,0,0,0,0,0,0,0,0,0)';
      PINUSE='POWER';
      NO_LOAD_CHECK='Both';
      NO_IO_CHECK='Both';
      NO_ASSERT_CHECK='TRUE';
      NO_DIR_CHECK='TRUE';
      ALLOW_CONNECT='TRUE';
    'VCCFA_EHV_FIVRA81':
      PIN_NUMBER='(0,0,0,0,0,0,0,0,0,0,0,0,0,0,0,0,0,0,0,0,0,0,0,0,0,0,0,0,0,EJ15,0,0,0,0,0,0,0,0,0,0,0,0)';
      PINUSE='POWER';
      NO_LOAD_CHECK='Both';
      NO_IO_CHECK='Both';
      NO_ASSERT_CHECK='TRUE';
      NO_DIR_CHECK='TRUE';
      ALLOW_CONNECT='TRUE';
    'VCCFA_EHV_FIVRA80':
      PIN_NUMBER='(0,0,0,0,0,0,0,0,0,0,0,0,0,0,0,0,0,0,0,0,0,0,0,0,0,0,0,0,0,EG80,0,0,0,0,0,0,0,0,0,0,0,0)';
      PINUSE='POWER';
      NO_LOAD_CHECK='Both';
      NO_IO_CHECK='Both';
      NO_ASSERT_CHECK='TRUE';
      NO_DIR_CHECK='TRUE';
      ALLOW_CONNECT='TRUE';
    'VCCFA_EHV_FIVRA79':
      PIN_NUMBER='(0,0,0,0,0,0,0,0,0,0,0,0,0,0,0,0,0,0,0,0,0,0,0,0,0,0,0,0,0,EF79,0,0,0,0,0,0,0,0,0,0,0,0)';
      PINUSE='POWER';
      NO_LOAD_CHECK='Both';
      NO_IO_CHECK='Both';
      NO_ASSERT_CHECK='TRUE';
      NO_DIR_CHECK='TRUE';
      ALLOW_CONNECT='TRUE';
    'VCCFA_EHV_FIVRA78':
      PIN_NUMBER='(0,0,0,0,0,0,0,0,0,0,0,0,0,0,0,0,0,0,0,0,0,0,0,0,0,0,0,0,0,EE84,0,0,0,0,0,0,0,0,0,0,0,0)';
      PINUSE='POWER';
      NO_LOAD_CHECK='Both';
      NO_IO_CHECK='Both';
      NO_ASSERT_CHECK='TRUE';
      NO_DIR_CHECK='TRUE';
      ALLOW_CONNECT='TRUE';
    'VCCFA_EHV_FIVRA77':
      PIN_NUMBER='(0,0,0,0,0,0,0,0,0,0,0,0,0,0,0,0,0,0,0,0,0,0,0,0,0,0,0,0,0,EE7,0,0,0,0,0,0,0,0,0,0,0,0)';
      PINUSE='POWER';
      NO_LOAD_CHECK='Both';
      NO_IO_CHECK='Both';
      NO_ASSERT_CHECK='TRUE';
      NO_DIR_CHECK='TRUE';
      ALLOW_CONNECT='TRUE';
    'VCCFA_EHV_FIVRA76':
      PIN_NUMBER='(0,0,0,0,0,0,0,0,0,0,0,0,0,0,0,0,0,0,0,0,0,0,0,0,0,0,0,0,0,EE15,0,0,0,0,0,0,0,0,0,0,0,0)';
      PINUSE='POWER';
      NO_LOAD_CHECK='Both';
      NO_IO_CHECK='Both';
      NO_ASSERT_CHECK='TRUE';
      NO_DIR_CHECK='TRUE';
      ALLOW_CONNECT='TRUE';
    'VCCFA_EHV_FIVRA75':
      PIN_NUMBER='(0,0,0,0,0,0,0,0,0,0,0,0,0,0,0,0,0,0,0,0,0,0,0,0,0,0,0,0,0,EE11,0,0,0,0,0,0,0,0,0,0,0,0)';
      PINUSE='POWER';
      NO_LOAD_CHECK='Both';
      NO_IO_CHECK='Both';
      NO_ASSERT_CHECK='TRUE';
      NO_DIR_CHECK='TRUE';
      ALLOW_CONNECT='TRUE';
    'VCCFA_EHV_FIVRA74':
      PIN_NUMBER='(0,0,0,0,0,0,0,0,0,0,0,0,0,0,0,0,0,0,0,0,0,0,0,0,0,0,0,0,0,ED89,0,0,0,0,0,0,0,0,0,0,0,0)';
      PINUSE='POWER';
      NO_LOAD_CHECK='Both';
      NO_IO_CHECK='Both';
      NO_ASSERT_CHECK='TRUE';
      NO_DIR_CHECK='TRUE';
      ALLOW_CONNECT='TRUE';
    'VCCFA_EHV_FIVRA73':
      PIN_NUMBER='(0,0,0,0,0,0,0,0,0,0,0,0,0,0,0,0,0,0,0,0,0,0,0,0,0,0,0,0,0,ED85,0,0,0,0,0,0,0,0,0,0,0,0)';
      PINUSE='POWER';
      NO_LOAD_CHECK='Both';
      NO_IO_CHECK='Both';
      NO_ASSERT_CHECK='TRUE';
      NO_DIR_CHECK='TRUE';
      ALLOW_CONNECT='TRUE';
    'VCCFA_EHV_FIVRA72':
      PIN_NUMBER='(0,0,0,0,0,0,0,0,0,0,0,0,0,0,0,0,0,0,0,0,0,0,0,0,0,0,0,0,0,ED79,0,0,0,0,0,0,0,0,0,0,0,0)';
      PINUSE='POWER';
      NO_LOAD_CHECK='Both';
      NO_IO_CHECK='Both';
      NO_ASSERT_CHECK='TRUE';
      NO_DIR_CHECK='TRUE';
      ALLOW_CONNECT='TRUE';
    'VCCFA_EHV_FIVRA71':
      PIN_NUMBER='(0,0,0,0,0,0,0,0,0,0,0,0,0,0,0,0,0,0,0,0,0,0,0,0,0,0,0,0,0,EC78,0,0,0,0,0,0,0,0,0,0,0,0)';
      PINUSE='POWER';
      NO_LOAD_CHECK='Both';
      NO_IO_CHECK='Both';
      NO_ASSERT_CHECK='TRUE';
      NO_DIR_CHECK='TRUE';
      ALLOW_CONNECT='TRUE';
    'VCCFA_EHV_FIVRA70':
      PIN_NUMBER='(0,0,0,0,0,0,0,0,0,0,0,0,0,0,0,0,0,0,0,0,0,0,0,0,0,0,0,0,0,EA7,0,0,0,0,0,0,0,0,0,0,0,0)';
      PINUSE='POWER';
      NO_LOAD_CHECK='Both';
      NO_IO_CHECK='Both';
      NO_ASSERT_CHECK='TRUE';
      NO_DIR_CHECK='TRUE';
      ALLOW_CONNECT='TRUE';
    'VCCFA_EHV_FIVRA69':
      PIN_NUMBER='(0,0,0,0,0,0,0,0,0,0,0,0,0,0,0,0,0,0,0,0,0,0,0,0,0,0,0,0,0,EA3,0,0,0,0,0,0,0,0,0,0,0,0)';
      PINUSE='POWER';
      NO_LOAD_CHECK='Both';
      NO_IO_CHECK='Both';
      NO_ASSERT_CHECK='TRUE';
      NO_DIR_CHECK='TRUE';
      ALLOW_CONNECT='TRUE';
    'VCCFA_EHV_FIVRA68':
      PIN_NUMBER='(0,0,0,0,0,0,0,0,0,0,0,0,0,0,0,0,0,0,0,0,0,0,0,0,0,0,0,0,0,EA15,0,0,0,0,0,0,0,0,0,0,0,0)';
      PINUSE='POWER';
      NO_LOAD_CHECK='Both';
      NO_IO_CHECK='Both';
      NO_ASSERT_CHECK='TRUE';
      NO_DIR_CHECK='TRUE';
      ALLOW_CONNECT='TRUE';
    'VCCFA_EHV_FIVRA67':
      PIN_NUMBER='(0,0,0,0,0,0,0,0,0,0,0,0,0,0,0,0,0,0,0,0,0,0,0,0,0,0,0,0,0,EA11,0,0,0,0,0,0,0,0,0,0,0,0)';
      PINUSE='POWER';
      NO_LOAD_CHECK='Both';
      NO_IO_CHECK='Both';
      NO_ASSERT_CHECK='TRUE';
      NO_DIR_CHECK='TRUE';
      ALLOW_CONNECT='TRUE';
    'VCCFA_EHV_FIVRA66':
      PIN_NUMBER='(0,0,0,0,0,0,0,0,0,0,0,0,0,0,0,0,0,0,0,0,0,0,0,0,0,0,0,0,0,DY89,0,0,0,0,0,0,0,0,0,0,0,0)';
      PINUSE='POWER';
      NO_LOAD_CHECK='Both';
      NO_IO_CHECK='Both';
      NO_ASSERT_CHECK='TRUE';
      NO_DIR_CHECK='TRUE';
      ALLOW_CONNECT='TRUE';
    'VCCFA_EHV_FIVRA65':
      PIN_NUMBER='(0,0,0,0,0,0,0,0,0,0,0,0,0,0,0,0,0,0,0,0,0,0,0,0,0,0,0,0,0,DY85,0,0,0,0,0,0,0,0,0,0,0,0)';
      PINUSE='POWER';
      NO_LOAD_CHECK='Both';
      NO_IO_CHECK='Both';
      NO_ASSERT_CHECK='TRUE';
      NO_DIR_CHECK='TRUE';
      ALLOW_CONNECT='TRUE';
    'VCCFA_EHV_FIVRA64':
      PIN_NUMBER='(0,0,0,0,0,0,0,0,0,0,0,0,0,0,0,0,0,0,0,0,0,0,0,0,0,0,0,0,0,DU7,0,0,0,0,0,0,0,0,0,0,0,0)';
      PINUSE='POWER';
      NO_LOAD_CHECK='Both';
      NO_IO_CHECK='Both';
      NO_ASSERT_CHECK='TRUE';
      NO_DIR_CHECK='TRUE';
      ALLOW_CONNECT='TRUE';
    'VCCFA_EHV_FIVRA63':
      PIN_NUMBER='(0,0,0,0,0,0,0,0,0,0,0,0,0,0,0,0,0,0,0,0,0,0,0,0,0,0,0,0,0,DU3,0,0,0,0,0,0,0,0,0,0,0,0)';
      PINUSE='POWER';
      NO_LOAD_CHECK='Both';
      NO_IO_CHECK='Both';
      NO_ASSERT_CHECK='TRUE';
      NO_DIR_CHECK='TRUE';
      ALLOW_CONNECT='TRUE';
    'VCCFA_EHV_FIVRA62':
      PIN_NUMBER='(0,0,0,0,0,0,0,0,0,0,0,0,0,0,0,0,0,0,0,0,0,0,0,0,0,0,0,0,0,DU15,0,0,0,0,0,0,0,0,0,0,0,0)';
      PINUSE='POWER';
      NO_LOAD_CHECK='Both';
      NO_IO_CHECK='Both';
      NO_ASSERT_CHECK='TRUE';
      NO_DIR_CHECK='TRUE';
      ALLOW_CONNECT='TRUE';
    'VCCFA_EHV_FIVRA61':
      PIN_NUMBER='(0,0,0,0,0,0,0,0,0,0,0,0,0,0,0,0,0,0,0,0,0,0,0,0,0,0,0,0,0,DU11,0,0,0,0,0,0,0,0,0,0,0,0)';
      PINUSE='POWER';
      NO_LOAD_CHECK='Both';
      NO_IO_CHECK='Both';
      NO_ASSERT_CHECK='TRUE';
      NO_DIR_CHECK='TRUE';
      ALLOW_CONNECT='TRUE';
    'VCCFA_EHV_FIVRA60':
      PIN_NUMBER='(0,0,0,0,0,0,0,0,0,0,0,0,0,0,0,0,0,0,0,0,0,0,0,0,0,0,0,0,0,DT89,0,0,0,0,0,0,0,0,0,0,0,0)';
      PINUSE='POWER';
      NO_LOAD_CHECK='Both';
      NO_IO_CHECK='Both';
      NO_ASSERT_CHECK='TRUE';
      NO_DIR_CHECK='TRUE';
      ALLOW_CONNECT='TRUE';
    'VCCFA_EHV_FIVRA59':
      PIN_NUMBER='(0,0,0,0,0,0,0,0,0,0,0,0,0,0,0,0,0,0,0,0,0,0,0,0,0,0,0,0,0,DT85,0,0,0,0,0,0,0,0,0,0,0,0)';
      PINUSE='POWER';
      NO_LOAD_CHECK='Both';
      NO_IO_CHECK='Both';
      NO_ASSERT_CHECK='TRUE';
      NO_DIR_CHECK='TRUE';
      ALLOW_CONNECT='TRUE';
    'VCCFA_EHV_FIVRA58':
      PIN_NUMBER='(0,0,0,0,0,0,0,0,0,0,0,0,0,0,0,0,0,0,0,0,0,0,0,0,0,0,0,0,0,DT79,0,0,0,0,0,0,0,0,0,0,0,0)';
      PINUSE='POWER';
      NO_LOAD_CHECK='Both';
      NO_IO_CHECK='Both';
      NO_ASSERT_CHECK='TRUE';
      NO_DIR_CHECK='TRUE';
      ALLOW_CONNECT='TRUE';
    'VCCFA_EHV_FIVRA57':
      PIN_NUMBER='(0,0,0,0,0,0,0,0,0,0,0,0,0,0,0,0,0,0,0,0,0,0,0,0,0,0,0,0,0,DN7,0,0,0,0,0,0,0,0,0,0,0,0)';
      PINUSE='POWER';
      NO_LOAD_CHECK='Both';
      NO_IO_CHECK='Both';
      NO_ASSERT_CHECK='TRUE';
      NO_DIR_CHECK='TRUE';
      ALLOW_CONNECT='TRUE';
    'VCCFA_EHV_FIVRA56':
      PIN_NUMBER='(0,0,0,0,0,0,0,0,0,0,0,0,0,0,0,0,0,0,0,0,0,0,0,0,0,0,0,0,0,DN3,0,0,0,0,0,0,0,0,0,0,0,0)';
      PINUSE='POWER';
      NO_LOAD_CHECK='Both';
      NO_IO_CHECK='Both';
      NO_ASSERT_CHECK='TRUE';
      NO_DIR_CHECK='TRUE';
      ALLOW_CONNECT='TRUE';
    'VCCFA_EHV_FIVRA55':
      PIN_NUMBER='(0,0,0,0,0,0,0,0,0,0,0,0,0,0,0,0,0,0,0,0,0,0,0,0,0,0,0,0,0,DN15,0,0,0,0,0,0,0,0,0,0,0,0)';
      PINUSE='POWER';
      NO_LOAD_CHECK='Both';
      NO_IO_CHECK='Both';
      NO_ASSERT_CHECK='TRUE';
      NO_DIR_CHECK='TRUE';
      ALLOW_CONNECT='TRUE';
    'VCCFA_EHV_FIVRA54':
      PIN_NUMBER='(0,0,0,0,0,0,0,0,0,0,0,0,0,0,0,0,0,0,0,0,0,0,0,0,0,0,0,0,0,DN11,0,0,0,0,0,0,0,0,0,0,0,0)';
      PINUSE='POWER';
      NO_LOAD_CHECK='Both';
      NO_IO_CHECK='Both';
      NO_ASSERT_CHECK='TRUE';
      NO_DIR_CHECK='TRUE';
      ALLOW_CONNECT='TRUE';
    'VCCFA_EHV_FIVRA53':
      PIN_NUMBER='(0,0,0,0,0,0,0,0,0,0,0,0,0,0,0,0,0,0,0,0,0,0,0,0,0,0,0,0,0,DM89,0,0,0,0,0,0,0,0,0,0,0,0)';
      PINUSE='POWER';
      NO_LOAD_CHECK='Both';
      NO_IO_CHECK='Both';
      NO_ASSERT_CHECK='TRUE';
      NO_DIR_CHECK='TRUE';
      ALLOW_CONNECT='TRUE';
    'VCCFA_EHV_FIVRA52':
      PIN_NUMBER='(0,0,0,0,0,0,0,0,0,0,0,0,0,0,0,0,0,0,0,0,0,0,0,0,0,0,0,0,0,DM85,0,0,0,0,0,0,0,0,0,0,0,0)';
      PINUSE='POWER';
      NO_LOAD_CHECK='Both';
      NO_IO_CHECK='Both';
      NO_ASSERT_CHECK='TRUE';
      NO_DIR_CHECK='TRUE';
      ALLOW_CONNECT='TRUE';
    'VCCFA_EHV_FIVRA51':
      PIN_NUMBER='(0,0,0,0,0,0,0,0,0,0,0,0,0,0,0,0,0,0,0,0,0,0,0,0,0,0,0,0,0,DM83,0,0,0,0,0,0,0,0,0,0,0,0)';
      PINUSE='POWER';
      NO_LOAD_CHECK='Both';
      NO_IO_CHECK='Both';
      NO_ASSERT_CHECK='TRUE';
      NO_DIR_CHECK='TRUE';
      ALLOW_CONNECT='TRUE';
    'VCCFA_EHV_FIVRA50':
      PIN_NUMBER='(0,0,0,0,0,0,0,0,0,0,0,0,0,0,0,0,0,0,0,0,0,0,0,0,0,0,0,0,0,DH89,0,0,0,0,0,0,0,0,0,0,0,0)';
      PINUSE='POWER';
      NO_LOAD_CHECK='Both';
      NO_IO_CHECK='Both';
      NO_ASSERT_CHECK='TRUE';
      NO_DIR_CHECK='TRUE';
      ALLOW_CONNECT='TRUE';
    'VCCFA_EHV_FIVRA49':
      PIN_NUMBER='(0,0,0,0,0,0,0,0,0,0,0,0,0,0,0,0,0,0,0,0,0,0,0,0,0,0,0,0,0,DD89,0,0,0,0,0,0,0,0,0,0,0,0)';
      PINUSE='POWER';
      NO_LOAD_CHECK='Both';
      NO_IO_CHECK='Both';
      NO_ASSERT_CHECK='TRUE';
      NO_DIR_CHECK='TRUE';
      ALLOW_CONNECT='TRUE';
    'VCCFA_EHV_FIVRA48':
      PIN_NUMBER='(0,0,0,0,0,0,0,0,0,0,0,0,0,0,0,0,0,0,0,0,0,0,0,0,0,0,0,0,0,DD85,0,0,0,0,0,0,0,0,0,0,0,0)';
      PINUSE='POWER';
      NO_LOAD_CHECK='Both';
      NO_IO_CHECK='Both';
      NO_ASSERT_CHECK='TRUE';
      NO_DIR_CHECK='TRUE';
      ALLOW_CONNECT='TRUE';
    'VCCFA_EHV_FIVRA47':
      PIN_NUMBER='(0,0,0,0,0,0,0,0,0,0,0,0,0,0,0,0,0,0,0,0,0,0,0,0,0,0,0,0,0,DD83,0,0,0,0,0,0,0,0,0,0,0,0)';
      PINUSE='POWER';
      NO_LOAD_CHECK='Both';
      NO_IO_CHECK='Both';
      NO_ASSERT_CHECK='TRUE';
      NO_DIR_CHECK='TRUE';
      ALLOW_CONNECT='TRUE';
    'VCCFA_EHV_FIVRA46':
      PIN_NUMBER='(0,0,0,0,0,0,0,0,0,0,0,0,0,0,0,0,0,0,0,0,0,0,0,0,0,0,0,0,0,DD77,0,0,0,0,0,0,0,0,0,0,0,0)';
      PINUSE='POWER';
      NO_LOAD_CHECK='Both';
      NO_IO_CHECK='Both';
      NO_ASSERT_CHECK='TRUE';
      NO_DIR_CHECK='TRUE';
      ALLOW_CONNECT='TRUE';
    'VCCFA_EHV_FIVRA45':
      PIN_NUMBER='(0,0,0,0,0,0,0,0,0,0,0,0,0,0,0,0,0,0,0,0,0,0,0,0,0,0,0,0,0,CY89,0,0,0,0,0,0,0,0,0,0,0,0)';
      PINUSE='POWER';
      NO_LOAD_CHECK='Both';
      NO_IO_CHECK='Both';
      NO_ASSERT_CHECK='TRUE';
      NO_DIR_CHECK='TRUE';
      ALLOW_CONNECT='TRUE';
    'VCCFA_EHV_FIVRA44':
      PIN_NUMBER='(0,0,0,0,0,0,0,0,0,0,0,0,0,0,0,0,0,0,0,0,0,0,0,0,0,0,0,0,0,CY85,0,0,0,0,0,0,0,0,0,0,0,0)';
      PINUSE='POWER';
      NO_LOAD_CHECK='Both';
      NO_IO_CHECK='Both';
      NO_ASSERT_CHECK='TRUE';
      NO_DIR_CHECK='TRUE';
      ALLOW_CONNECT='TRUE';
    'VCCFA_EHV_FIVRA43':
      PIN_NUMBER='(0,0,0,0,0,0,0,0,0,0,0,0,0,0,0,0,0,0,0,0,0,0,0,0,0,0,0,0,0,CY79,0,0,0,0,0,0,0,0,0,0,0,0)';
      PINUSE='POWER';
      NO_LOAD_CHECK='Both';
      NO_IO_CHECK='Both';
      NO_ASSERT_CHECK='TRUE';
      NO_DIR_CHECK='TRUE';
      ALLOW_CONNECT='TRUE';
    'VCCFA_EHV_FIVRA42':
      PIN_NUMBER='(0,0,0,0,0,0,0,0,0,0,0,0,0,0,0,0,0,0,0,0,0,0,0,0,0,0,0,0,0,CY75,0,0,0,0,0,0,0,0,0,0,0,0)';
      PINUSE='POWER';
      NO_LOAD_CHECK='Both';
      NO_IO_CHECK='Both';
      NO_ASSERT_CHECK='TRUE';
      NO_DIR_CHECK='TRUE';
      ALLOW_CONNECT='TRUE';
    'VCCFA_EHV_FIVRA41':
      PIN_NUMBER='(0,0,0,0,0,0,0,0,0,0,0,0,0,0,0,0,0,0,0,0,0,0,0,0,0,0,0,0,0,CT85,0,0,0,0,0,0,0,0,0,0,0,0)';
      PINUSE='POWER';
      NO_LOAD_CHECK='Both';
      NO_IO_CHECK='Both';
      NO_ASSERT_CHECK='TRUE';
      NO_DIR_CHECK='TRUE';
      ALLOW_CONNECT='TRUE';
    'VCCFA_EHV_FIVRA40':
      PIN_NUMBER='(0,0,0,0,0,0,0,0,0,0,0,0,0,0,0,0,0,0,0,0,0,0,0,0,0,0,0,0,0,CT77,0,0,0,0,0,0,0,0,0,0,0,0)';
      PINUSE='POWER';
      NO_LOAD_CHECK='Both';
      NO_IO_CHECK='Both';
      NO_ASSERT_CHECK='TRUE';
      NO_DIR_CHECK='TRUE';
      ALLOW_CONNECT='TRUE';
    'VCCFA_EHV_FIVRA39':
      PIN_NUMBER='(0,0,0,0,0,0,0,0,0,0,0,0,0,0,0,0,0,0,0,0,0,0,0,0,0,0,0,0,0,CP73,0,0,0,0,0,0,0,0,0,0,0,0)';
      PINUSE='POWER';
      NO_LOAD_CHECK='Both';
      NO_IO_CHECK='Both';
      NO_ASSERT_CHECK='TRUE';
      NO_DIR_CHECK='TRUE';
      ALLOW_CONNECT='TRUE';
    'VCCFA_EHV_FIVRA38':
      PIN_NUMBER='(0,0,0,0,0,0,0,0,0,0,0,0,0,0,0,0,0,0,0,0,0,0,0,0,0,0,0,0,0,CN78,0,0,0,0,0,0,0,0,0,0,0,0)';
      PINUSE='POWER';
      NO_LOAD_CHECK='Both';
      NO_IO_CHECK='Both';
      NO_ASSERT_CHECK='TRUE';
      NO_DIR_CHECK='TRUE';
      ALLOW_CONNECT='TRUE';
    'VCCFA_EHV_FIVRA37':
      PIN_NUMBER='(0,0,0,0,0,0,0,0,0,0,0,0,0,0,0,0,0,0,0,0,0,0,0,0,0,0,0,0,0,CM73,0,0,0,0,0,0,0,0,0,0,0,0)';
      PINUSE='POWER';
      NO_LOAD_CHECK='Both';
      NO_IO_CHECK='Both';
      NO_ASSERT_CHECK='TRUE';
      NO_DIR_CHECK='TRUE';
      ALLOW_CONNECT='TRUE';
    'VCCFA_EHV_FIVRA36':
      PIN_NUMBER='(0,0,0,0,0,0,0,0,0,0,0,0,0,0,0,0,0,0,0,0,0,0,0,0,0,0,0,0,0,CK79,0,0,0,0,0,0,0,0,0,0,0,0)';
      PINUSE='POWER';
      NO_LOAD_CHECK='Both';
      NO_IO_CHECK='Both';
      NO_ASSERT_CHECK='TRUE';
      NO_DIR_CHECK='TRUE';
      ALLOW_CONNECT='TRUE';
    'VCCFA_EHV_FIVRA35':
      PIN_NUMBER='(0,0,0,0,0,0,0,0,0,0,0,0,0,0,0,0,0,0,0,0,0,0,0,0,0,0,0,0,0,CK73,0,0,0,0,0,0,0,0,0,0,0,0)';
      PINUSE='POWER';
      NO_LOAD_CHECK='Both';
      NO_IO_CHECK='Both';
      NO_ASSERT_CHECK='TRUE';
      NO_DIR_CHECK='TRUE';
      ALLOW_CONNECT='TRUE';
    'VCCFA_EHV_FIVRA34':
      PIN_NUMBER='(0,0,0,0,0,0,0,0,0,0,0,0,0,0,0,0,0,0,0,0,0,0,0,0,0,0,0,0,0,CE74,0,0,0,0,0,0,0,0,0,0,0,0)';
      PINUSE='POWER';
      NO_LOAD_CHECK='Both';
      NO_IO_CHECK='Both';
      NO_ASSERT_CHECK='TRUE';
      NO_DIR_CHECK='TRUE';
      ALLOW_CONNECT='TRUE';
    'VCCFA_EHV_FIVRA33':
      PIN_NUMBER='(0,0,0,0,0,0,0,0,0,0,0,0,0,0,0,0,0,0,0,0,0,0,0,0,0,0,0,0,0,C88,0,0,0,0,0,0,0,0,0,0,0,0)';
      PINUSE='POWER';
      NO_LOAD_CHECK='Both';
      NO_IO_CHECK='Both';
      NO_ASSERT_CHECK='TRUE';
      NO_DIR_CHECK='TRUE';
      ALLOW_CONNECT='TRUE';
    'VCCFA_EHV_FIVRA32':
      PIN_NUMBER='(0,0,0,0,0,0,0,0,0,0,0,0,0,0,0,0,0,0,0,0,0,0,0,0,0,0,0,0,0,C84,0,0,0,0,0,0,0,0,0,0,0,0)';
      PINUSE='POWER';
      NO_LOAD_CHECK='Both';
      NO_IO_CHECK='Both';
      NO_ASSERT_CHECK='TRUE';
      NO_DIR_CHECK='TRUE';
      ALLOW_CONNECT='TRUE';
    'VCCFA_EHV_FIVRA31':
      PIN_NUMBER='(0,0,0,0,0,0,0,0,0,0,0,0,0,0,0,0,0,0,0,0,0,0,0,0,0,0,0,0,0,BJ78,0,0,0,0,0,0,0,0,0,0,0,0)';
      PINUSE='POWER';
      NO_LOAD_CHECK='Both';
      NO_IO_CHECK='Both';
      NO_ASSERT_CHECK='TRUE';
      NO_DIR_CHECK='TRUE';
      ALLOW_CONNECT='TRUE';
    'VCCFA_EHV_FIVRA30':
      PIN_NUMBER='(0,0,0,0,0,0,0,0,0,0,0,0,0,0,0,0,0,0,0,0,0,0,0,0,0,0,0,0,0,BJ72,0,0,0,0,0,0,0,0,0,0,0,0)';
      PINUSE='POWER';
      NO_LOAD_CHECK='Both';
      NO_IO_CHECK='Both';
      NO_ASSERT_CHECK='TRUE';
      NO_DIR_CHECK='TRUE';
      ALLOW_CONNECT='TRUE';
    'VCCFA_EHV_FIVRA29':
      PIN_NUMBER='(0,0,0,0,0,0,0,0,0,0,0,0,0,0,0,0,0,0,0,0,0,0,0,0,0,0,0,0,0,BH79,0,0,0,0,0,0,0,0,0,0,0,0)';
      PINUSE='POWER';
      NO_LOAD_CHECK='Both';
      NO_IO_CHECK='Both';
      NO_ASSERT_CHECK='TRUE';
      NO_DIR_CHECK='TRUE';
      ALLOW_CONNECT='TRUE';
    'VCCFA_EHV_FIVRA28':
      PIN_NUMBER='(0,0,0,0,0,0,0,0,0,0,0,0,0,0,0,0,0,0,0,0,0,0,0,0,0,0,0,0,0,BF77,0,0,0,0,0,0,0,0,0,0,0,0)';
      PINUSE='POWER';
      NO_LOAD_CHECK='Both';
      NO_IO_CHECK='Both';
      NO_ASSERT_CHECK='TRUE';
      NO_DIR_CHECK='TRUE';
      ALLOW_CONNECT='TRUE';
    'VCCFA_EHV_FIVRA27':
      PIN_NUMBER='(0,0,0,0,0,0,0,0,0,0,0,0,0,0,0,0,0,0,0,0,0,0,0,0,0,0,0,0,0,BE72,0,0,0,0,0,0,0,0,0,0,0,0)';
      PINUSE='POWER';
      NO_LOAD_CHECK='Both';
      NO_IO_CHECK='Both';
      NO_ASSERT_CHECK='TRUE';
      NO_DIR_CHECK='TRUE';
      ALLOW_CONNECT='TRUE';
    'VCCFA_EHV_FIVRA26':
      PIN_NUMBER='(0,0,0,0,0,0,0,0,0,0,0,0,0,0,0,0,0,0,0,0,0,0,0,0,0,0,0,0,0,AY89,0,0,0,0,0,0,0,0,0,0,0,0)';
      PINUSE='POWER';
      NO_LOAD_CHECK='Both';
      NO_IO_CHECK='Both';
      NO_ASSERT_CHECK='TRUE';
      NO_DIR_CHECK='TRUE';
      ALLOW_CONNECT='TRUE';
    'VCCFA_EHV_FIVRA25':
      PIN_NUMBER='(0,0,0,0,0,0,0,0,0,0,0,0,0,0,0,0,0,0,0,0,0,0,0,0,0,0,0,0,0,AW76,0,0,0,0,0,0,0,0,0,0,0,0)';
      PINUSE='POWER';
      NO_LOAD_CHECK='Both';
      NO_IO_CHECK='Both';
      NO_ASSERT_CHECK='TRUE';
      NO_DIR_CHECK='TRUE';
      ALLOW_CONNECT='TRUE';
    'VCCFA_EHV_FIVRA24':
      PIN_NUMBER='(0,0,0,0,0,0,0,0,0,0,0,0,0,0,0,0,0,0,0,0,0,0,0,0,0,0,0,0,0,AU15,0,0,0,0,0,0,0,0,0,0,0,0)';
      PINUSE='POWER';
      NO_LOAD_CHECK='Both';
      NO_IO_CHECK='Both';
      NO_ASSERT_CHECK='TRUE';
      NO_DIR_CHECK='TRUE';
      ALLOW_CONNECT='TRUE';
    'VCCFA_EHV_FIVRA23':
      PIN_NUMBER='(0,0,0,0,0,0,0,0,0,0,0,0,0,0,0,0,0,0,0,0,0,0,0,0,0,0,0,0,0,AT89,0,0,0,0,0,0,0,0,0,0,0,0)';
      PINUSE='POWER';
      NO_LOAD_CHECK='Both';
      NO_IO_CHECK='Both';
      NO_ASSERT_CHECK='TRUE';
      NO_DIR_CHECK='TRUE';
      ALLOW_CONNECT='TRUE';
    'VCCFA_EHV_FIVRA22':
      PIN_NUMBER='(0,0,0,0,0,0,0,0,0,0,0,0,0,0,0,0,0,0,0,0,0,0,0,0,0,0,0,0,0,AT73,0,0,0,0,0,0,0,0,0,0,0,0)';
      PINUSE='POWER';
      NO_LOAD_CHECK='Both';
      NO_IO_CHECK='Both';
      NO_ASSERT_CHECK='TRUE';
      NO_DIR_CHECK='TRUE';
      ALLOW_CONNECT='TRUE';
    'VCCFA_EHV_FIVRA21':
      PIN_NUMBER='(0,0,0,0,0,0,0,0,0,0,0,0,0,0,0,0,0,0,0,0,0,0,0,0,0,0,0,0,0,AN80,0,0,0,0,0,0,0,0,0,0,0,0)';
      PINUSE='POWER';
      NO_LOAD_CHECK='Both';
      NO_IO_CHECK='Both';
      NO_ASSERT_CHECK='TRUE';
      NO_DIR_CHECK='TRUE';
      ALLOW_CONNECT='TRUE';
    'VCCFA_EHV_FIVRA20':
      PIN_NUMBER='(0,0,0,0,0,0,0,0,0,0,0,0,0,0,0,0,0,0,0,0,0,0,0,0,0,0,0,0,0,AN7,0,0,0,0,0,0,0,0,0,0,0,0)';
      PINUSE='POWER';
      NO_LOAD_CHECK='Both';
      NO_IO_CHECK='Both';
      NO_ASSERT_CHECK='TRUE';
      NO_DIR_CHECK='TRUE';
      ALLOW_CONNECT='TRUE';
    'VCCFA_EHV_FIVRA19':
      PIN_NUMBER='(0,0,0,0,0,0,0,0,0,0,0,0,0,0,0,0,0,0,0,0,0,0,0,0,0,0,0,0,0,AN15,0,0,0,0,0,0,0,0,0,0,0,0)';
      PINUSE='POWER';
      NO_LOAD_CHECK='Both';
      NO_IO_CHECK='Both';
      NO_ASSERT_CHECK='TRUE';
      NO_DIR_CHECK='TRUE';
      ALLOW_CONNECT='TRUE';
    'VCCFA_EHV_FIVRA18':
      PIN_NUMBER='(0,0,0,0,0,0,0,0,0,0,0,0,0,0,0,0,0,0,0,0,0,0,0,0,0,0,0,0,0,AN11,0,0,0,0,0,0,0,0,0,0,0,0)';
      PINUSE='POWER';
      NO_LOAD_CHECK='Both';
      NO_IO_CHECK='Both';
      NO_ASSERT_CHECK='TRUE';
      NO_DIR_CHECK='TRUE';
      ALLOW_CONNECT='TRUE';
    'VCCFA_EHV_FIVRA17':
      PIN_NUMBER='(0,0,0,0,0,0,0,0,0,0,0,0,0,0,0,0,0,0,0,0,0,0,0,0,0,0,0,0,0,AM89,0,0,0,0,0,0,0,0,0,0,0,0)';
      PINUSE='POWER';
      NO_LOAD_CHECK='Both';
      NO_IO_CHECK='Both';
      NO_ASSERT_CHECK='TRUE';
      NO_DIR_CHECK='TRUE';
      ALLOW_CONNECT='TRUE';
    'VCCFA_EHV_FIVRA16':
      PIN_NUMBER='(0,0,0,0,0,0,0,0,0,0,0,0,0,0,0,0,0,0,0,0,0,0,0,0,0,0,0,0,0,AM85,0,0,0,0,0,0,0,0,0,0,0,0)';
      PINUSE='POWER';
      NO_LOAD_CHECK='Both';
      NO_IO_CHECK='Both';
      NO_ASSERT_CHECK='TRUE';
      NO_DIR_CHECK='TRUE';
      ALLOW_CONNECT='TRUE';
    'VCCFA_EHV_FIVRA15':
      PIN_NUMBER='(0,0,0,0,0,0,0,0,0,0,0,0,0,0,0,0,0,0,0,0,0,0,0,0,0,0,0,0,0,AM79,0,0,0,0,0,0,0,0,0,0,0,0)';
      PINUSE='POWER';
      NO_LOAD_CHECK='Both';
      NO_IO_CHECK='Both';
      NO_ASSERT_CHECK='TRUE';
      NO_DIR_CHECK='TRUE';
      ALLOW_CONNECT='TRUE';
    'VCCFA_EHV_FIVRA14':
      PIN_NUMBER='(0,0,0,0,0,0,0,0,0,0,0,0,0,0,0,0,0,0,0,0,0,0,0,0,0,0,0,0,0,AJ7,0,0,0,0,0,0,0,0,0,0,0,0)';
      PINUSE='POWER';
      NO_LOAD_CHECK='Both';
      NO_IO_CHECK='Both';
      NO_ASSERT_CHECK='TRUE';
      NO_DIR_CHECK='TRUE';
      ALLOW_CONNECT='TRUE';
    'VCCFA_EHV_FIVRA13':
      PIN_NUMBER='(0,0,0,0,0,0,0,0,0,0,0,0,0,0,0,0,0,0,0,0,0,0,0,0,0,0,0,0,0,AJ15,0,0,0,0,0,0,0,0,0,0,0,0)';
      PINUSE='POWER';
      NO_LOAD_CHECK='Both';
      NO_IO_CHECK='Both';
      NO_ASSERT_CHECK='TRUE';
      NO_DIR_CHECK='TRUE';
      ALLOW_CONNECT='TRUE';
    'VCCFA_EHV_FIVRA12':
      PIN_NUMBER='(0,0,0,0,0,0,0,0,0,0,0,0,0,0,0,0,0,0,0,0,0,0,0,0,0,0,0,0,0,AJ11,0,0,0,0,0,0,0,0,0,0,0,0)';
      PINUSE='POWER';
      NO_LOAD_CHECK='Both';
      NO_IO_CHECK='Both';
      NO_ASSERT_CHECK='TRUE';
      NO_DIR_CHECK='TRUE';
      ALLOW_CONNECT='TRUE';
    'VCCFA_EHV_FIVRA11':
      PIN_NUMBER='(0,0,0,0,0,0,0,0,0,0,0,0,0,0,0,0,0,0,0,0,0,0,0,0,0,0,0,0,0,AH89,0,0,0,0,0,0,0,0,0,0,0,0)';
      PINUSE='POWER';
      NO_LOAD_CHECK='Both';
      NO_IO_CHECK='Both';
      NO_ASSERT_CHECK='TRUE';
      NO_DIR_CHECK='TRUE';
      ALLOW_CONNECT='TRUE';
    'VCCFA_EHV_FIVRA10':
      PIN_NUMBER='(0,0,0,0,0,0,0,0,0,0,0,0,0,0,0,0,0,0,0,0,0,0,0,0,0,0,0,0,0,AH85,0,0,0,0,0,0,0,0,0,0,0,0)';
      PINUSE='POWER';
      NO_LOAD_CHECK='Both';
      NO_IO_CHECK='Both';
      NO_ASSERT_CHECK='TRUE';
      NO_DIR_CHECK='TRUE';
      ALLOW_CONNECT='TRUE';
    'VCCFA_EHV_FIVRA9':
      PIN_NUMBER='(0,0,0,0,0,0,0,0,0,0,0,0,0,0,0,0,0,0,0,0,0,0,0,0,0,0,0,0,0,AG78,0,0,0,0,0,0,0,0,0,0,0,0)';
      PINUSE='POWER';
      NO_LOAD_CHECK='Both';
      NO_IO_CHECK='Both';
      NO_ASSERT_CHECK='TRUE';
      NO_DIR_CHECK='TRUE';
      ALLOW_CONNECT='TRUE';
    'VCCFA_EHV_FIVRA8':
      PIN_NUMBER='(0,0,0,0,0,0,0,0,0,0,0,0,0,0,0,0,0,0,0,0,0,0,0,0,0,0,0,0,0,AF77,0,0,0,0,0,0,0,0,0,0,0,0)';
      PINUSE='POWER';
      NO_LOAD_CHECK='Both';
      NO_IO_CHECK='Both';
      NO_ASSERT_CHECK='TRUE';
      NO_DIR_CHECK='TRUE';
      ALLOW_CONNECT='TRUE';
    'VCCFA_EHV_FIVRA7':
      PIN_NUMBER='(0,0,0,0,0,0,0,0,0,0,0,0,0,0,0,0,0,0,0,0,0,0,0,0,0,0,0,0,0,AE7,0,0,0,0,0,0,0,0,0,0,0,0)';
      PINUSE='POWER';
      NO_LOAD_CHECK='Both';
      NO_IO_CHECK='Both';
      NO_ASSERT_CHECK='TRUE';
      NO_DIR_CHECK='TRUE';
      ALLOW_CONNECT='TRUE';
    'VCCFA_EHV_FIVRA6':
      PIN_NUMBER='(0,0,0,0,0,0,0,0,0,0,0,0,0,0,0,0,0,0,0,0,0,0,0,0,0,0,0,0,0,AE15,0,0,0,0,0,0,0,0,0,0,0,0)';
      PINUSE='POWER';
      NO_LOAD_CHECK='Both';
      NO_IO_CHECK='Both';
      NO_ASSERT_CHECK='TRUE';
      NO_DIR_CHECK='TRUE';
      ALLOW_CONNECT='TRUE';
    'VCCFA_EHV_FIVRA5':
      PIN_NUMBER='(0,0,0,0,0,0,0,0,0,0,0,0,0,0,0,0,0,0,0,0,0,0,0,0,0,0,0,0,0,AE11,0,0,0,0,0,0,0,0,0,0,0,0)';
      PINUSE='POWER';
      NO_LOAD_CHECK='Both';
      NO_IO_CHECK='Both';
      NO_ASSERT_CHECK='TRUE';
      NO_DIR_CHECK='TRUE';
      ALLOW_CONNECT='TRUE';
    'VCCFA_EHV_FIVRA4':
      PIN_NUMBER='(0,0,0,0,0,0,0,0,0,0,0,0,0,0,0,0,0,0,0,0,0,0,0,0,0,0,0,0,0,AD89,0,0,0,0,0,0,0,0,0,0,0,0)';
      PINUSE='POWER';
      NO_LOAD_CHECK='Both';
      NO_IO_CHECK='Both';
      NO_ASSERT_CHECK='TRUE';
      NO_DIR_CHECK='TRUE';
      ALLOW_CONNECT='TRUE';
    'VCCFA_EHV_FIVRA3':
      PIN_NUMBER='(0,0,0,0,0,0,0,0,0,0,0,0,0,0,0,0,0,0,0,0,0,0,0,0,0,0,0,0,0,AD85,0,0,0,0,0,0,0,0,0,0,0,0)';
      PINUSE='POWER';
      NO_LOAD_CHECK='Both';
      NO_IO_CHECK='Both';
      NO_ASSERT_CHECK='TRUE';
      NO_DIR_CHECK='TRUE';
      ALLOW_CONNECT='TRUE';
    'VCCFA_EHV_FIVRA2':
      PIN_NUMBER='(0,0,0,0,0,0,0,0,0,0,0,0,0,0,0,0,0,0,0,0,0,0,0,0,0,0,0,0,0,AA7,0,0,0,0,0,0,0,0,0,0,0,0)';
      PINUSE='POWER';
      NO_LOAD_CHECK='Both';
      NO_IO_CHECK='Both';
      NO_ASSERT_CHECK='TRUE';
      NO_DIR_CHECK='TRUE';
      ALLOW_CONNECT='TRUE';
    'VCCFA_EHV_FIVRA1':
      PIN_NUMBER='(0,0,0,0,0,0,0,0,0,0,0,0,0,0,0,0,0,0,0,0,0,0,0,0,0,0,0,0,0,AA15,0,0,0,0,0,0,0,0,0,0,0,0)';
      PINUSE='POWER';
      NO_LOAD_CHECK='Both';
      NO_IO_CHECK='Both';
      NO_ASSERT_CHECK='TRUE';
      NO_DIR_CHECK='TRUE';
      ALLOW_CONNECT='TRUE';
    'VCCFA_EHV_FIVRA0':
      PIN_NUMBER='(0,0,0,0,0,0,0,0,0,0,0,0,0,0,0,0,0,0,0,0,0,0,0,0,0,0,0,0,0,AA11,0,0,0,0,0,0,0,0,0,0,0,0)';
      PINUSE='POWER';
      NO_LOAD_CHECK='Both';
      NO_IO_CHECK='Both';
      NO_ASSERT_CHECK='TRUE';
      NO_DIR_CHECK='TRUE';
      ALLOW_CONNECT='TRUE';
    'VSS1834':
      PIN_NUMBER='(0,0,0,0,0,0,0,0,0,0,0,0,0,0,0,0,0,0,0,0,0,0,0,0,0,0,0,0,0,0,ER41,0,0,0,0,0,0,0,0,0,0,0)';
      PINUSE='POWER';
      NO_LOAD_CHECK='Both';
      NO_IO_CHECK='Both';
      NO_ASSERT_CHECK='TRUE';
      NO_DIR_CHECK='TRUE';
      ALLOW_CONNECT='TRUE';
    'VSS1835':
      PIN_NUMBER='(0,0,0,0,0,0,0,0,0,0,0,0,0,0,0,0,0,0,0,0,0,0,0,0,0,0,0,0,0,0,ER43,0,0,0,0,0,0,0,0,0,0,0)';
      PINUSE='POWER';
      NO_LOAD_CHECK='Both';
      NO_IO_CHECK='Both';
      NO_ASSERT_CHECK='TRUE';
      NO_DIR_CHECK='TRUE';
      ALLOW_CONNECT='TRUE';
    'VSS1836':
      PIN_NUMBER='(0,0,0,0,0,0,0,0,0,0,0,0,0,0,0,0,0,0,0,0,0,0,0,0,0,0,0,0,0,0,ER48,0,0,0,0,0,0,0,0,0,0,0)';
      PINUSE='POWER';
      NO_LOAD_CHECK='Both';
      NO_IO_CHECK='Both';
      NO_ASSERT_CHECK='TRUE';
      NO_DIR_CHECK='TRUE';
      ALLOW_CONNECT='TRUE';
    'VSS1837':
      PIN_NUMBER='(0,0,0,0,0,0,0,0,0,0,0,0,0,0,0,0,0,0,0,0,0,0,0,0,0,0,0,0,0,0,ER50,0,0,0,0,0,0,0,0,0,0,0)';
      PINUSE='POWER';
      NO_LOAD_CHECK='Both';
      NO_IO_CHECK='Both';
      NO_ASSERT_CHECK='TRUE';
      NO_DIR_CHECK='TRUE';
      ALLOW_CONNECT='TRUE';
    'VSS1569':
      PIN_NUMBER='(0,0,0,0,0,0,0,0,0,0,0,0,0,0,0,0,0,0,0,0,0,0,0,0,0,0,0,0,0,0,ET57,0,0,0,0,0,0,0,0,0,0,0)';
      PINUSE='POWER';
      NO_LOAD_CHECK='Both';
      NO_IO_CHECK='Both';
      NO_ASSERT_CHECK='TRUE';
      NO_DIR_CHECK='TRUE';
      ALLOW_CONNECT='TRUE';
    'VSS1565':
      PIN_NUMBER='(0,0,0,0,0,0,0,0,0,0,0,0,0,0,0,0,0,0,0,0,0,0,0,0,0,0,0,0,0,0,ET38,0,0,0,0,0,0,0,0,0,0,0)';
      PINUSE='POWER';
      NO_LOAD_CHECK='Both';
      NO_IO_CHECK='Both';
      NO_ASSERT_CHECK='TRUE';
      NO_DIR_CHECK='TRUE';
      ALLOW_CONNECT='TRUE';
    'VSS1563':
      PIN_NUMBER='(0,0,0,0,0,0,0,0,0,0,0,0,0,0,0,0,0,0,0,0,0,0,0,0,0,0,0,0,0,0,ET34,0,0,0,0,0,0,0,0,0,0,0)';
      PINUSE='POWER';
      NO_LOAD_CHECK='Both';
      NO_IO_CHECK='Both';
      NO_ASSERT_CHECK='TRUE';
      NO_DIR_CHECK='TRUE';
      ALLOW_CONNECT='TRUE';
    'VSS1562':
      PIN_NUMBER='(0,0,0,0,0,0,0,0,0,0,0,0,0,0,0,0,0,0,0,0,0,0,0,0,0,0,0,0,0,0,ET28,0,0,0,0,0,0,0,0,0,0,0)';
      PINUSE='POWER';
      NO_LOAD_CHECK='Both';
      NO_IO_CHECK='Both';
      NO_ASSERT_CHECK='TRUE';
      NO_DIR_CHECK='TRUE';
      ALLOW_CONNECT='TRUE';
    'VSS1561':
      PIN_NUMBER='(0,0,0,0,0,0,0,0,0,0,0,0,0,0,0,0,0,0,0,0,0,0,0,0,0,0,0,0,0,0,ET22,0,0,0,0,0,0,0,0,0,0,0)';
      PINUSE='POWER';
      NO_LOAD_CHECK='Both';
      NO_IO_CHECK='Both';
      NO_ASSERT_CHECK='TRUE';
      NO_DIR_CHECK='TRUE';
      ALLOW_CONNECT='TRUE';
    'VSS1559':
      PIN_NUMBER='(0,0,0,0,0,0,0,0,0,0,0,0,0,0,0,0,0,0,0,0,0,0,0,0,0,0,0,0,0,0,ET16,0,0,0,0,0,0,0,0,0,0,0)';
      PINUSE='POWER';
      NO_LOAD_CHECK='Both';
      NO_IO_CHECK='Both';
      NO_ASSERT_CHECK='TRUE';
      NO_DIR_CHECK='TRUE';
      ALLOW_CONNECT='TRUE';
    'VSS1557':
      PIN_NUMBER='(0,0,0,0,0,0,0,0,0,0,0,0,0,0,0,0,0,0,0,0,0,0,0,0,0,0,0,0,0,0,ET10,0,0,0,0,0,0,0,0,0,0,0)';
      PINUSE='POWER';
      NO_LOAD_CHECK='Both';
      NO_IO_CHECK='Both';
      NO_ASSERT_CHECK='TRUE';
      NO_DIR_CHECK='TRUE';
      ALLOW_CONNECT='TRUE';
    'VSS1556':
      PIN_NUMBER='(0,0,0,0,0,0,0,0,0,0,0,0,0,0,0,0,0,0,0,0,0,0,0,0,0,0,0,0,0,0,ER86,0,0,0,0,0,0,0,0,0,0,0)';
      PINUSE='POWER';
      NO_LOAD_CHECK='Both';
      NO_IO_CHECK='Both';
      NO_ASSERT_CHECK='TRUE';
      NO_DIR_CHECK='TRUE';
      ALLOW_CONNECT='TRUE';
    'VSS1555':
      PIN_NUMBER='(0,0,0,0,0,0,0,0,0,0,0,0,0,0,0,0,0,0,0,0,0,0,0,0,0,0,0,0,0,0,ER84,0,0,0,0,0,0,0,0,0,0,0)';
      PINUSE='POWER';
      NO_LOAD_CHECK='Both';
      NO_IO_CHECK='Both';
      NO_ASSERT_CHECK='TRUE';
      NO_DIR_CHECK='TRUE';
      ALLOW_CONNECT='TRUE';
    'VSS1554':
      PIN_NUMBER='(0,0,0,0,0,0,0,0,0,0,0,0,0,0,0,0,0,0,0,0,0,0,0,0,0,0,0,0,0,0,ER80,0,0,0,0,0,0,0,0,0,0,0)';
      PINUSE='POWER';
      NO_LOAD_CHECK='Both';
      NO_IO_CHECK='Both';
      NO_ASSERT_CHECK='TRUE';
      NO_DIR_CHECK='TRUE';
      ALLOW_CONNECT='TRUE';
    'VSS1553':
      PIN_NUMBER='(0,0,0,0,0,0,0,0,0,0,0,0,0,0,0,0,0,0,0,0,0,0,0,0,0,0,0,0,0,0,ER78,0,0,0,0,0,0,0,0,0,0,0)';
      PINUSE='POWER';
      NO_LOAD_CHECK='Both';
      NO_IO_CHECK='Both';
      NO_ASSERT_CHECK='TRUE';
      NO_DIR_CHECK='TRUE';
      ALLOW_CONNECT='TRUE';
    'VSS1552':
      PIN_NUMBER='(0,0,0,0,0,0,0,0,0,0,0,0,0,0,0,0,0,0,0,0,0,0,0,0,0,0,0,0,0,0,ER74,0,0,0,0,0,0,0,0,0,0,0)';
      PINUSE='POWER';
      NO_LOAD_CHECK='Both';
      NO_IO_CHECK='Both';
      NO_ASSERT_CHECK='TRUE';
      NO_DIR_CHECK='TRUE';
      ALLOW_CONNECT='TRUE';
    'VSS1551':
      PIN_NUMBER='(0,0,0,0,0,0,0,0,0,0,0,0,0,0,0,0,0,0,0,0,0,0,0,0,0,0,0,0,0,0,ER70,0,0,0,0,0,0,0,0,0,0,0)';
      PINUSE='POWER';
      NO_LOAD_CHECK='Both';
      NO_IO_CHECK='Both';
      NO_ASSERT_CHECK='TRUE';
      NO_DIR_CHECK='TRUE';
      ALLOW_CONNECT='TRUE';
    'VSS1550':
      PIN_NUMBER='(0,0,0,0,0,0,0,0,0,0,0,0,0,0,0,0,0,0,0,0,0,0,0,0,0,0,0,0,0,0,ER7,0,0,0,0,0,0,0,0,0,0,0)';
      PINUSE='POWER';
      NO_LOAD_CHECK='Both';
      NO_IO_CHECK='Both';
      NO_ASSERT_CHECK='TRUE';
      NO_DIR_CHECK='TRUE';
      ALLOW_CONNECT='TRUE';
    'VSS1549':
      PIN_NUMBER='(0,0,0,0,0,0,0,0,0,0,0,0,0,0,0,0,0,0,0,0,0,0,0,0,0,0,0,0,0,0,ER5,0,0,0,0,0,0,0,0,0,0,0)';
      PINUSE='POWER';
      NO_LOAD_CHECK='Both';
      NO_IO_CHECK='Both';
      NO_ASSERT_CHECK='TRUE';
      NO_DIR_CHECK='TRUE';
      ALLOW_CONNECT='TRUE';
    'VSS1548':
      PIN_NUMBER='(0,0,0,0,0,0,0,0,0,0,0,0,0,0,0,0,0,0,0,0,0,0,0,0,0,0,0,0,0,0,ER33,0,0,0,0,0,0,0,0,0,0,0)';
      PINUSE='POWER';
      NO_LOAD_CHECK='Both';
      NO_IO_CHECK='Both';
      NO_ASSERT_CHECK='TRUE';
      NO_DIR_CHECK='TRUE';
      ALLOW_CONNECT='TRUE';
    'VSS1547':
      PIN_NUMBER='(0,0,0,0,0,0,0,0,0,0,0,0,0,0,0,0,0,0,0,0,0,0,0,0,0,0,0,0,0,0,ER27,0,0,0,0,0,0,0,0,0,0,0)';
      PINUSE='POWER';
      NO_LOAD_CHECK='Both';
      NO_IO_CHECK='Both';
      NO_ASSERT_CHECK='TRUE';
      NO_DIR_CHECK='TRUE';
      ALLOW_CONNECT='TRUE';
    'VSS1545':
      PIN_NUMBER='(0,0,0,0,0,0,0,0,0,0,0,0,0,0,0,0,0,0,0,0,0,0,0,0,0,0,0,0,0,0,EP83,0,0,0,0,0,0,0,0,0,0,0)';
      PINUSE='POWER';
      NO_LOAD_CHECK='Both';
      NO_IO_CHECK='Both';
      NO_ASSERT_CHECK='TRUE';
      NO_DIR_CHECK='TRUE';
      ALLOW_CONNECT='TRUE';
    'VSS1543':
      PIN_NUMBER='(0,0,0,0,0,0,0,0,0,0,0,0,0,0,0,0,0,0,0,0,0,0,0,0,0,0,0,0,0,0,EP67,0,0,0,0,0,0,0,0,0,0,0)';
      PINUSE='POWER';
      NO_LOAD_CHECK='Both';
      NO_IO_CHECK='Both';
      NO_ASSERT_CHECK='TRUE';
      NO_DIR_CHECK='TRUE';
      ALLOW_CONNECT='TRUE';
    'VSS1542':
      PIN_NUMBER='(0,0,0,0,0,0,0,0,0,0,0,0,0,0,0,0,0,0,0,0,0,0,0,0,0,0,0,0,0,0,EN80,0,0,0,0,0,0,0,0,0,0,0)';
      PINUSE='POWER';
      NO_LOAD_CHECK='Both';
      NO_IO_CHECK='Both';
      NO_ASSERT_CHECK='TRUE';
      NO_DIR_CHECK='TRUE';
      ALLOW_CONNECT='TRUE';
    'VSS1541':
      PIN_NUMBER='(0,0,0,0,0,0,0,0,0,0,0,0,0,0,0,0,0,0,0,0,0,0,0,0,0,0,0,0,0,0,EN78,0,0,0,0,0,0,0,0,0,0,0)';
      PINUSE='POWER';
      NO_LOAD_CHECK='Both';
      NO_IO_CHECK='Both';
      NO_ASSERT_CHECK='TRUE';
      NO_DIR_CHECK='TRUE';
      ALLOW_CONNECT='TRUE';
    'VSS1540':
      PIN_NUMBER='(0,0,0,0,0,0,0,0,0,0,0,0,0,0,0,0,0,0,0,0,0,0,0,0,0,0,0,0,0,0,EN64,0,0,0,0,0,0,0,0,0,0,0)';
      PINUSE='POWER';
      NO_LOAD_CHECK='Both';
      NO_IO_CHECK='Both';
      NO_ASSERT_CHECK='TRUE';
      NO_DIR_CHECK='TRUE';
      ALLOW_CONNECT='TRUE';
    'VSS1539':
      PIN_NUMBER='(0,0,0,0,0,0,0,0,0,0,0,0,0,0,0,0,0,0,0,0,0,0,0,0,0,0,0,0,0,0,EN56,0,0,0,0,0,0,0,0,0,0,0)';
      PINUSE='POWER';
      NO_LOAD_CHECK='Both';
      NO_IO_CHECK='Both';
      NO_ASSERT_CHECK='TRUE';
      NO_DIR_CHECK='TRUE';
      ALLOW_CONNECT='TRUE';
    'VSS1537':
      PIN_NUMBER='(0,0,0,0,0,0,0,0,0,0,0,0,0,0,0,0,0,0,0,0,0,0,0,0,0,0,0,0,0,0,EN54,0,0,0,0,0,0,0,0,0,0,0)';
      PINUSE='POWER';
      NO_LOAD_CHECK='Both';
      NO_IO_CHECK='Both';
      NO_ASSERT_CHECK='TRUE';
      NO_DIR_CHECK='TRUE';
      ALLOW_CONNECT='TRUE';
    'VSS1533':
      PIN_NUMBER='(0,0,0,0,0,0,0,0,0,0,0,0,0,0,0,0,0,0,0,0,0,0,0,0,0,0,0,0,0,0,EN52,0,0,0,0,0,0,0,0,0,0,0)';
      PINUSE='POWER';
      NO_LOAD_CHECK='Both';
      NO_IO_CHECK='Both';
      NO_ASSERT_CHECK='TRUE';
      NO_DIR_CHECK='TRUE';
      ALLOW_CONNECT='TRUE';
    'VSS1531':
      PIN_NUMBER='(0,0,0,0,0,0,0,0,0,0,0,0,0,0,0,0,0,0,0,0,0,0,0,0,0,0,0,0,0,0,EN50,0,0,0,0,0,0,0,0,0,0,0)';
      PINUSE='POWER';
      NO_LOAD_CHECK='Both';
      NO_IO_CHECK='Both';
      NO_ASSERT_CHECK='TRUE';
      NO_DIR_CHECK='TRUE';
      ALLOW_CONNECT='TRUE';
    'VSS1530':
      PIN_NUMBER='(0,0,0,0,0,0,0,0,0,0,0,0,0,0,0,0,0,0,0,0,0,0,0,0,0,0,0,0,0,0,EN48,0,0,0,0,0,0,0,0,0,0,0)';
      PINUSE='POWER';
      NO_LOAD_CHECK='Both';
      NO_IO_CHECK='Both';
      NO_ASSERT_CHECK='TRUE';
      NO_DIR_CHECK='TRUE';
      ALLOW_CONNECT='TRUE';
    'VSS1529':
      PIN_NUMBER='(0,0,0,0,0,0,0,0,0,0,0,0,0,0,0,0,0,0,0,0,0,0,0,0,0,0,0,0,0,0,EN45,0,0,0,0,0,0,0,0,0,0,0)';
      PINUSE='POWER';
      NO_LOAD_CHECK='Both';
      NO_IO_CHECK='Both';
      NO_ASSERT_CHECK='TRUE';
      NO_DIR_CHECK='TRUE';
      ALLOW_CONNECT='TRUE';
    'VSS1528':
      PIN_NUMBER='(0,0,0,0,0,0,0,0,0,0,0,0,0,0,0,0,0,0,0,0,0,0,0,0,0,0,0,0,0,0,EN43,0,0,0,0,0,0,0,0,0,0,0)';
      PINUSE='POWER';
      NO_LOAD_CHECK='Both';
      NO_IO_CHECK='Both';
      NO_ASSERT_CHECK='TRUE';
      NO_DIR_CHECK='TRUE';
      ALLOW_CONNECT='TRUE';
    'VSS1526':
      PIN_NUMBER='(0,0,0,0,0,0,0,0,0,0,0,0,0,0,0,0,0,0,0,0,0,0,0,0,0,0,0,0,0,0,EN41,0,0,0,0,0,0,0,0,0,0,0)';
      PINUSE='POWER';
      NO_LOAD_CHECK='Both';
      NO_IO_CHECK='Both';
      NO_ASSERT_CHECK='TRUE';
      NO_DIR_CHECK='TRUE';
      ALLOW_CONNECT='TRUE';
    'VSS1525':
      PIN_NUMBER='(0,0,0,0,0,0,0,0,0,0,0,0,0,0,0,0,0,0,0,0,0,0,0,0,0,0,0,0,0,0,EN37,0,0,0,0,0,0,0,0,0,0,0)';
      PINUSE='POWER';
      NO_LOAD_CHECK='Both';
      NO_IO_CHECK='Both';
      NO_ASSERT_CHECK='TRUE';
      NO_DIR_CHECK='TRUE';
      ALLOW_CONNECT='TRUE';
    'VSS1524':
      PIN_NUMBER='(0,0,0,0,0,0,0,0,0,0,0,0,0,0,0,0,0,0,0,0,0,0,0,0,0,0,0,0,0,0,EN35,0,0,0,0,0,0,0,0,0,0,0)';
      PINUSE='POWER';
      NO_LOAD_CHECK='Both';
      NO_IO_CHECK='Both';
      NO_ASSERT_CHECK='TRUE';
      NO_DIR_CHECK='TRUE';
      ALLOW_CONNECT='TRUE';
    'VSS1522':
      PIN_NUMBER='(0,0,0,0,0,0,0,0,0,0,0,0,0,0,0,0,0,0,0,0,0,0,0,0,0,0,0,0,0,0,EN33,0,0,0,0,0,0,0,0,0,0,0)';
      PINUSE='POWER';
      NO_LOAD_CHECK='Both';
      NO_IO_CHECK='Both';
      NO_ASSERT_CHECK='TRUE';
      NO_DIR_CHECK='TRUE';
      ALLOW_CONNECT='TRUE';
    'VSS1520':
      PIN_NUMBER='(0,0,0,0,0,0,0,0,0,0,0,0,0,0,0,0,0,0,0,0,0,0,0,0,0,0,0,0,0,0,EN31,0,0,0,0,0,0,0,0,0,0,0)';
      PINUSE='POWER';
      NO_LOAD_CHECK='Both';
      NO_IO_CHECK='Both';
      NO_ASSERT_CHECK='TRUE';
      NO_DIR_CHECK='TRUE';
      ALLOW_CONNECT='TRUE';
    'VSS1518':
      PIN_NUMBER='(0,0,0,0,0,0,0,0,0,0,0,0,0,0,0,0,0,0,0,0,0,0,0,0,0,0,0,0,0,0,EN29,0,0,0,0,0,0,0,0,0,0,0)';
      PINUSE='POWER';
      NO_LOAD_CHECK='Both';
      NO_IO_CHECK='Both';
      NO_ASSERT_CHECK='TRUE';
      NO_DIR_CHECK='TRUE';
      ALLOW_CONNECT='TRUE';
    'VSS1517':
      PIN_NUMBER='(0,0,0,0,0,0,0,0,0,0,0,0,0,0,0,0,0,0,0,0,0,0,0,0,0,0,0,0,0,0,EN27,0,0,0,0,0,0,0,0,0,0,0)';
      PINUSE='POWER';
      NO_LOAD_CHECK='Both';
      NO_IO_CHECK='Both';
      NO_ASSERT_CHECK='TRUE';
      NO_DIR_CHECK='TRUE';
      ALLOW_CONNECT='TRUE';
    'VSS1515':
      PIN_NUMBER='(0,0,0,0,0,0,0,0,0,0,0,0,0,0,0,0,0,0,0,0,0,0,0,0,0,0,0,0,0,0,EN25,0,0,0,0,0,0,0,0,0,0,0)';
      PINUSE='POWER';
      NO_LOAD_CHECK='Both';
      NO_IO_CHECK='Both';
      NO_ASSERT_CHECK='TRUE';
      NO_DIR_CHECK='TRUE';
      ALLOW_CONNECT='TRUE';
    'VSS1513':
      PIN_NUMBER='(0,0,0,0,0,0,0,0,0,0,0,0,0,0,0,0,0,0,0,0,0,0,0,0,0,0,0,0,0,0,EN23,0,0,0,0,0,0,0,0,0,0,0)';
      PINUSE='POWER';
      NO_LOAD_CHECK='Both';
      NO_IO_CHECK='Both';
      NO_ASSERT_CHECK='TRUE';
      NO_DIR_CHECK='TRUE';
      ALLOW_CONNECT='TRUE';
    'VSS1512':
      PIN_NUMBER='(0,0,0,0,0,0,0,0,0,0,0,0,0,0,0,0,0,0,0,0,0,0,0,0,0,0,0,0,0,0,EN21,0,0,0,0,0,0,0,0,0,0,0)';
      PINUSE='POWER';
      NO_LOAD_CHECK='Both';
      NO_IO_CHECK='Both';
      NO_ASSERT_CHECK='TRUE';
      NO_DIR_CHECK='TRUE';
      ALLOW_CONNECT='TRUE';
    'VSS1506':
      PIN_NUMBER='(0,0,0,0,0,0,0,0,0,0,0,0,0,0,0,0,0,0,0,0,0,0,0,0,0,0,0,0,0,0,EN19,0,0,0,0,0,0,0,0,0,0,0)';
      PINUSE='POWER';
      NO_LOAD_CHECK='Both';
      NO_IO_CHECK='Both';
      NO_ASSERT_CHECK='TRUE';
      NO_DIR_CHECK='TRUE';
      ALLOW_CONNECT='TRUE';
    'VSS1505':
      PIN_NUMBER='(0,0,0,0,0,0,0,0,0,0,0,0,0,0,0,0,0,0,0,0,0,0,0,0,0,0,0,0,0,0,EN17,0,0,0,0,0,0,0,0,0,0,0)';
      PINUSE='POWER';
      NO_LOAD_CHECK='Both';
      NO_IO_CHECK='Both';
      NO_ASSERT_CHECK='TRUE';
      NO_DIR_CHECK='TRUE';
      ALLOW_CONNECT='TRUE';
    'VSS1503':
      PIN_NUMBER='(0,0,0,0,0,0,0,0,0,0,0,0,0,0,0,0,0,0,0,0,0,0,0,0,0,0,0,0,0,0,EN15,0,0,0,0,0,0,0,0,0,0,0)';
      PINUSE='POWER';
      NO_LOAD_CHECK='Both';
      NO_IO_CHECK='Both';
      NO_ASSERT_CHECK='TRUE';
      NO_DIR_CHECK='TRUE';
      ALLOW_CONNECT='TRUE';
    'VSS1501':
      PIN_NUMBER='(0,0,0,0,0,0,0,0,0,0,0,0,0,0,0,0,0,0,0,0,0,0,0,0,0,0,0,0,0,0,EN13,0,0,0,0,0,0,0,0,0,0,0)';
      PINUSE='POWER';
      NO_LOAD_CHECK='Both';
      NO_IO_CHECK='Both';
      NO_ASSERT_CHECK='TRUE';
      NO_DIR_CHECK='TRUE';
      ALLOW_CONNECT='TRUE';
    'VSS1500':
      PIN_NUMBER='(0,0,0,0,0,0,0,0,0,0,0,0,0,0,0,0,0,0,0,0,0,0,0,0,0,0,0,0,0,0,EN11,0,0,0,0,0,0,0,0,0,0,0)';
      PINUSE='POWER';
      NO_LOAD_CHECK='Both';
      NO_IO_CHECK='Both';
      NO_ASSERT_CHECK='TRUE';
      NO_DIR_CHECK='TRUE';
      ALLOW_CONNECT='TRUE';
    'VSS1499':
      PIN_NUMBER='(0,0,0,0,0,0,0,0,0,0,0,0,0,0,0,0,0,0,0,0,0,0,0,0,0,0,0,0,0,0,EM83,0,0,0,0,0,0,0,0,0,0,0)';
      PINUSE='POWER';
      NO_LOAD_CHECK='Both';
      NO_IO_CHECK='Both';
      NO_ASSERT_CHECK='TRUE';
      NO_DIR_CHECK='TRUE';
      ALLOW_CONNECT='TRUE';
    'VSS1498':
      PIN_NUMBER='(0,0,0,0,0,0,0,0,0,0,0,0,0,0,0,0,0,0,0,0,0,0,0,0,0,0,0,0,0,0,EM81,0,0,0,0,0,0,0,0,0,0,0)';
      PINUSE='POWER';
      NO_LOAD_CHECK='Both';
      NO_IO_CHECK='Both';
      NO_ASSERT_CHECK='TRUE';
      NO_DIR_CHECK='TRUE';
      ALLOW_CONNECT='TRUE';
    'VSS1497':
      PIN_NUMBER='(0,0,0,0,0,0,0,0,0,0,0,0,0,0,0,0,0,0,0,0,0,0,0,0,0,0,0,0,0,0,EM8,0,0,0,0,0,0,0,0,0,0,0)';
      PINUSE='POWER';
      NO_LOAD_CHECK='Both';
      NO_IO_CHECK='Both';
      NO_ASSERT_CHECK='TRUE';
      NO_DIR_CHECK='TRUE';
      ALLOW_CONNECT='TRUE';
    'VSS1496':
      PIN_NUMBER='(0,0,0,0,0,0,0,0,0,0,0,0,0,0,0,0,0,0,0,0,0,0,0,0,0,0,0,0,0,0,EM73,0,0,0,0,0,0,0,0,0,0,0)';
      PINUSE='POWER';
      NO_LOAD_CHECK='Both';
      NO_IO_CHECK='Both';
      NO_ASSERT_CHECK='TRUE';
      NO_DIR_CHECK='TRUE';
      ALLOW_CONNECT='TRUE';
    'VSS1493':
      PIN_NUMBER='(0,0,0,0,0,0,0,0,0,0,0,0,0,0,0,0,0,0,0,0,0,0,0,0,0,0,0,0,0,0,ET59,0,0,0,0,0,0,0,0,0,0,0)';
      PINUSE='POWER';
      NO_LOAD_CHECK='Both';
      NO_IO_CHECK='Both';
      NO_ASSERT_CHECK='TRUE';
      NO_DIR_CHECK='TRUE';
      ALLOW_CONNECT='TRUE';
    'VSS1492':
      PIN_NUMBER='(0,0,0,0,0,0,0,0,0,0,0,0,0,0,0,0,0,0,0,0,0,0,0,0,0,0,0,0,0,0,EM42,0,0,0,0,0,0,0,0,0,0,0)';
      PINUSE='POWER';
      NO_LOAD_CHECK='Both';
      NO_IO_CHECK='Both';
      NO_ASSERT_CHECK='TRUE';
      NO_DIR_CHECK='TRUE';
      ALLOW_CONNECT='TRUE';
    'VSS1491':
      PIN_NUMBER='(0,0,0,0,0,0,0,0,0,0,0,0,0,0,0,0,0,0,0,0,0,0,0,0,0,0,0,0,0,0,ET53,0,0,0,0,0,0,0,0,0,0,0)';
      PINUSE='POWER';
      NO_LOAD_CHECK='Both';
      NO_IO_CHECK='Both';
      NO_ASSERT_CHECK='TRUE';
      NO_DIR_CHECK='TRUE';
      ALLOW_CONNECT='TRUE';
    'VSS1489':
      PIN_NUMBER='(0,0,0,0,0,0,0,0,0,0,0,0,0,0,0,0,0,0,0,0,0,0,0,0,0,0,0,0,0,0,EL76,0,0,0,0,0,0,0,0,0,0,0)';
      PINUSE='POWER';
      NO_LOAD_CHECK='Both';
      NO_IO_CHECK='Both';
      NO_ASSERT_CHECK='TRUE';
      NO_DIR_CHECK='TRUE';
      ALLOW_CONNECT='TRUE';
    'VSS1488':
      PIN_NUMBER='(0,0,0,0,0,0,0,0,0,0,0,0,0,0,0,0,0,0,0,0,0,0,0,0,0,0,0,0,0,0,EL64,0,0,0,0,0,0,0,0,0,0,0)';
      PINUSE='POWER';
      NO_LOAD_CHECK='Both';
      NO_IO_CHECK='Both';
      NO_ASSERT_CHECK='TRUE';
      NO_DIR_CHECK='TRUE';
      ALLOW_CONNECT='TRUE';
    'VSS1486':
      PIN_NUMBER='(0,0,0,0,0,0,0,0,0,0,0,0,0,0,0,0,0,0,0,0,0,0,0,0,0,0,0,0,0,0,EL5,0,0,0,0,0,0,0,0,0,0,0)';
      PINUSE='POWER';
      NO_LOAD_CHECK='Both';
      NO_IO_CHECK='Both';
      NO_ASSERT_CHECK='TRUE';
      NO_DIR_CHECK='TRUE';
      ALLOW_CONNECT='TRUE';
    'VSS1485':
      PIN_NUMBER='(0,0,0,0,0,0,0,0,0,0,0,0,0,0,0,0,0,0,0,0,0,0,0,0,0,0,0,0,0,0,EL45,0,0,0,0,0,0,0,0,0,0,0)';
      PINUSE='POWER';
      NO_LOAD_CHECK='Both';
      NO_IO_CHECK='Both';
      NO_ASSERT_CHECK='TRUE';
      NO_DIR_CHECK='TRUE';
      ALLOW_CONNECT='TRUE';
    'VSS1484':
      PIN_NUMBER='(0,0,0,0,0,0,0,0,0,0,0,0,0,0,0,0,0,0,0,0,0,0,0,0,0,0,0,0,0,0,ET32,0,0,0,0,0,0,0,0,0,0,0)';
      PINUSE='POWER';
      NO_LOAD_CHECK='Both';
      NO_IO_CHECK='Both';
      NO_ASSERT_CHECK='TRUE';
      NO_DIR_CHECK='TRUE';
      ALLOW_CONNECT='TRUE';
    'VSS1483':
      PIN_NUMBER='(0,0,0,0,0,0,0,0,0,0,0,0,0,0,0,0,0,0,0,0,0,0,0,0,0,0,0,0,0,0,EL39,0,0,0,0,0,0,0,0,0,0,0)';
      PINUSE='POWER';
      NO_LOAD_CHECK='Both';
      NO_IO_CHECK='Both';
      NO_ASSERT_CHECK='TRUE';
      NO_DIR_CHECK='TRUE';
      ALLOW_CONNECT='TRUE';
    'VSS1482':
      PIN_NUMBER='(0,0,0,0,0,0,0,0,0,0,0,0,0,0,0,0,0,0,0,0,0,0,0,0,0,0,0,0,0,0,ET26,0,0,0,0,0,0,0,0,0,0,0)';
      PINUSE='POWER';
      NO_LOAD_CHECK='Both';
      NO_IO_CHECK='Both';
      NO_ASSERT_CHECK='TRUE';
      NO_DIR_CHECK='TRUE';
      ALLOW_CONNECT='TRUE';
    'VSS1481':
      PIN_NUMBER='(0,0,0,0,0,0,0,0,0,0,0,0,0,0,0,0,0,0,0,0,0,0,0,0,0,0,0,0,0,0,EL33,0,0,0,0,0,0,0,0,0,0,0)';
      PINUSE='POWER';
      NO_LOAD_CHECK='Both';
      NO_IO_CHECK='Both';
      NO_ASSERT_CHECK='TRUE';
      NO_DIR_CHECK='TRUE';
      ALLOW_CONNECT='TRUE';
    'VSS1480':
      PIN_NUMBER='(0,0,0,0,0,0,0,0,0,0,0,0,0,0,0,0,0,0,0,0,0,0,0,0,0,0,0,0,0,0,ET20,0,0,0,0,0,0,0,0,0,0,0)';
      PINUSE='POWER';
      NO_LOAD_CHECK='Both';
      NO_IO_CHECK='Both';
      NO_ASSERT_CHECK='TRUE';
      NO_DIR_CHECK='TRUE';
      ALLOW_CONNECT='TRUE';
    'VSS1479':
      PIN_NUMBER='(0,0,0,0,0,0,0,0,0,0,0,0,0,0,0,0,0,0,0,0,0,0,0,0,0,0,0,0,0,0,EL3,0,0,0,0,0,0,0,0,0,0,0)';
      PINUSE='POWER';
      NO_LOAD_CHECK='Both';
      NO_IO_CHECK='Both';
      NO_ASSERT_CHECK='TRUE';
      NO_DIR_CHECK='TRUE';
      ALLOW_CONNECT='TRUE';
    'VSS1478':
      PIN_NUMBER='(0,0,0,0,0,0,0,0,0,0,0,0,0,0,0,0,0,0,0,0,0,0,0,0,0,0,0,0,0,0,ET14,0,0,0,0,0,0,0,0,0,0,0)';
      PINUSE='POWER';
      NO_LOAD_CHECK='Both';
      NO_IO_CHECK='Both';
      NO_ASSERT_CHECK='TRUE';
      NO_DIR_CHECK='TRUE';
      ALLOW_CONNECT='TRUE';
    'VSS1477':
      PIN_NUMBER='(0,0,0,0,0,0,0,0,0,0,0,0,0,0,0,0,0,0,0,0,0,0,0,0,0,0,0,0,0,0,EL27,0,0,0,0,0,0,0,0,0,0,0)';
      PINUSE='POWER';
      NO_LOAD_CHECK='Both';
      NO_IO_CHECK='Both';
      NO_ASSERT_CHECK='TRUE';
      NO_DIR_CHECK='TRUE';
      ALLOW_CONNECT='TRUE';
    'VSS1476':
      PIN_NUMBER='(0,0,0,0,0,0,0,0,0,0,0,0,0,0,0,0,0,0,0,0,0,0,0,0,0,0,0,0,0,0,ER9,0,0,0,0,0,0,0,0,0,0,0)';
      PINUSE='POWER';
      NO_LOAD_CHECK='Both';
      NO_IO_CHECK='Both';
      NO_ASSERT_CHECK='TRUE';
      NO_DIR_CHECK='TRUE';
      ALLOW_CONNECT='TRUE';
    'VSS1475':
      PIN_NUMBER='(0,0,0,0,0,0,0,0,0,0,0,0,0,0,0,0,0,0,0,0,0,0,0,0,0,0,0,0,0,0,EL21,0,0,0,0,0,0,0,0,0,0,0)';
      PINUSE='POWER';
      NO_LOAD_CHECK='Both';
      NO_IO_CHECK='Both';
      NO_ASSERT_CHECK='TRUE';
      NO_DIR_CHECK='TRUE';
      ALLOW_CONNECT='TRUE';
    'VSS1474':
      PIN_NUMBER='(0,0,0,0,0,0,0,0,0,0,0,0,0,0,0,0,0,0,0,0,0,0,0,0,0,0,0,0,0,0,EK75,0,0,0,0,0,0,0,0,0,0,0)';
      PINUSE='POWER';
      NO_LOAD_CHECK='Both';
      NO_IO_CHECK='Both';
      NO_ASSERT_CHECK='TRUE';
      NO_DIR_CHECK='TRUE';
      ALLOW_CONNECT='TRUE';
    'VSS1473':
      PIN_NUMBER='(0,0,0,0,0,0,0,0,0,0,0,0,0,0,0,0,0,0,0,0,0,0,0,0,0,0,0,0,0,0,EK69,0,0,0,0,0,0,0,0,0,0,0)';
      PINUSE='POWER';
      NO_LOAD_CHECK='Both';
      NO_IO_CHECK='Both';
      NO_ASSERT_CHECK='TRUE';
      NO_DIR_CHECK='TRUE';
      ALLOW_CONNECT='TRUE';
    'VSS1472':
      PIN_NUMBER='(0,0,0,0,0,0,0,0,0,0,0,0,0,0,0,0,0,0,0,0,0,0,0,0,0,0,0,0,0,0,EK65,0,0,0,0,0,0,0,0,0,0,0)';
      PINUSE='POWER';
      NO_LOAD_CHECK='Both';
      NO_IO_CHECK='Both';
      NO_ASSERT_CHECK='TRUE';
      NO_DIR_CHECK='TRUE';
      ALLOW_CONNECT='TRUE';
    'VSS1471':
      PIN_NUMBER='(0,0,0,0,0,0,0,0,0,0,0,0,0,0,0,0,0,0,0,0,0,0,0,0,0,0,0,0,0,0,EK57,0,0,0,0,0,0,0,0,0,0,0)';
      PINUSE='POWER';
      NO_LOAD_CHECK='Both';
      NO_IO_CHECK='Both';
      NO_ASSERT_CHECK='TRUE';
      NO_DIR_CHECK='TRUE';
      ALLOW_CONNECT='TRUE';
    'VSS1470':
      PIN_NUMBER='(0,0,0,0,0,0,0,0,0,0,0,0,0,0,0,0,0,0,0,0,0,0,0,0,0,0,0,0,0,0,EK47,0,0,0,0,0,0,0,0,0,0,0)';
      PINUSE='POWER';
      NO_LOAD_CHECK='Both';
      NO_IO_CHECK='Both';
      NO_ASSERT_CHECK='TRUE';
      NO_DIR_CHECK='TRUE';
      ALLOW_CONNECT='TRUE';
    'VSS1469':
      PIN_NUMBER='(0,0,0,0,0,0,0,0,0,0,0,0,0,0,0,0,0,0,0,0,0,0,0,0,0,0,0,0,0,0,EK40,0,0,0,0,0,0,0,0,0,0,0)';
      PINUSE='POWER';
      NO_LOAD_CHECK='Both';
      NO_IO_CHECK='Both';
      NO_ASSERT_CHECK='TRUE';
      NO_DIR_CHECK='TRUE';
      ALLOW_CONNECT='TRUE';
    'VSS1468':
      PIN_NUMBER='(0,0,0,0,0,0,0,0,0,0,0,0,0,0,0,0,0,0,0,0,0,0,0,0,0,0,0,0,0,0,ER64,0,0,0,0,0,0,0,0,0,0,0)';
      PINUSE='POWER';
      NO_LOAD_CHECK='Both';
      NO_IO_CHECK='Both';
      NO_ASSERT_CHECK='TRUE';
      NO_DIR_CHECK='TRUE';
      ALLOW_CONNECT='TRUE';
    'VSS1467':
      PIN_NUMBER='(0,0,0,0,0,0,0,0,0,0,0,0,0,0,0,0,0,0,0,0,0,0,0,0,0,0,0,0,0,0,ER58,0,0,0,0,0,0,0,0,0,0,0)';
      PINUSE='POWER';
      NO_LOAD_CHECK='Both';
      NO_IO_CHECK='Both';
      NO_ASSERT_CHECK='TRUE';
      NO_DIR_CHECK='TRUE';
      ALLOW_CONNECT='TRUE';
    'VSS1466':
      PIN_NUMBER='(0,0,0,0,0,0,0,0,0,0,0,0,0,0,0,0,0,0,0,0,0,0,0,0,0,0,0,0,0,0,EK4,0,0,0,0,0,0,0,0,0,0,0)';
      PINUSE='POWER';
      NO_LOAD_CHECK='Both';
      NO_IO_CHECK='Both';
      NO_ASSERT_CHECK='TRUE';
      NO_DIR_CHECK='TRUE';
      ALLOW_CONNECT='TRUE';
    'VSS1465':
      PIN_NUMBER='(0,0,0,0,0,0,0,0,0,0,0,0,0,0,0,0,0,0,0,0,0,0,0,0,0,0,0,0,0,0,EK38,0,0,0,0,0,0,0,0,0,0,0)';
      PINUSE='POWER';
      NO_LOAD_CHECK='Both';
      NO_IO_CHECK='Both';
      NO_ASSERT_CHECK='TRUE';
      NO_DIR_CHECK='TRUE';
      ALLOW_CONNECT='TRUE';
    'VSS1464':
      PIN_NUMBER='(0,0,0,0,0,0,0,0,0,0,0,0,0,0,0,0,0,0,0,0,0,0,0,0,0,0,0,0,0,0,ER52,0,0,0,0,0,0,0,0,0,0,0)';
      PINUSE='POWER';
      NO_LOAD_CHECK='Both';
      NO_IO_CHECK='Both';
      NO_ASSERT_CHECK='TRUE';
      NO_DIR_CHECK='TRUE';
      ALLOW_CONNECT='TRUE';
    'VSS1463':
      PIN_NUMBER='(0,0,0,0,0,0,0,0,0,0,0,0,0,0,0,0,0,0,0,0,0,0,0,0,0,0,0,0,0,0,EK34,0,0,0,0,0,0,0,0,0,0,0)';
      PINUSE='POWER';
      NO_LOAD_CHECK='Both';
      NO_IO_CHECK='Both';
      NO_ASSERT_CHECK='TRUE';
      NO_DIR_CHECK='TRUE';
      ALLOW_CONNECT='TRUE';
    'VSS1462':
      PIN_NUMBER='(0,0,0,0,0,0,0,0,0,0,0,0,0,0,0,0,0,0,0,0,0,0,0,0,0,0,0,0,0,0,ER39,0,0,0,0,0,0,0,0,0,0,0)';
      PINUSE='POWER';
      NO_LOAD_CHECK='Both';
      NO_IO_CHECK='Both';
      NO_ASSERT_CHECK='TRUE';
      NO_DIR_CHECK='TRUE';
      ALLOW_CONNECT='TRUE';
    'VSS1461':
      PIN_NUMBER='(0,0,0,0,0,0,0,0,0,0,0,0,0,0,0,0,0,0,0,0,0,0,0,0,0,0,0,0,0,0,EK32,0,0,0,0,0,0,0,0,0,0,0)';
      PINUSE='POWER';
      NO_LOAD_CHECK='Both';
      NO_IO_CHECK='Both';
      NO_ASSERT_CHECK='TRUE';
      NO_DIR_CHECK='TRUE';
      ALLOW_CONNECT='TRUE';
    'VSS1460':
      PIN_NUMBER='(0,0,0,0,0,0,0,0,0,0,0,0,0,0,0,0,0,0,0,0,0,0,0,0,0,0,0,0,0,0,EK28,0,0,0,0,0,0,0,0,0,0,0)';
      PINUSE='POWER';
      NO_LOAD_CHECK='Both';
      NO_IO_CHECK='Both';
      NO_ASSERT_CHECK='TRUE';
      NO_DIR_CHECK='TRUE';
      ALLOW_CONNECT='TRUE';
    'VSS1459':
      PIN_NUMBER='(0,0,0,0,0,0,0,0,0,0,0,0,0,0,0,0,0,0,0,0,0,0,0,0,0,0,0,0,0,0,EK22,0,0,0,0,0,0,0,0,0,0,0)';
      PINUSE='POWER';
      NO_LOAD_CHECK='Both';
      NO_IO_CHECK='Both';
      NO_ASSERT_CHECK='TRUE';
      NO_DIR_CHECK='TRUE';
      ALLOW_CONNECT='TRUE';
    'VSS1458':
      PIN_NUMBER='(0,0,0,0,0,0,0,0,0,0,0,0,0,0,0,0,0,0,0,0,0,0,0,0,0,0,0,0,0,0,EK2,0,0,0,0,0,0,0,0,0,0,0)';
      PINUSE='POWER';
      NO_LOAD_CHECK='Both';
      NO_IO_CHECK='Both';
      NO_ASSERT_CHECK='TRUE';
      NO_DIR_CHECK='TRUE';
      ALLOW_CONNECT='TRUE';
    'VSS1457':
      PIN_NUMBER='(0,0,0,0,0,0,0,0,0,0,0,0,0,0,0,0,0,0,0,0,0,0,0,0,0,0,0,0,0,0,ER21,0,0,0,0,0,0,0,0,0,0,0)';
      PINUSE='POWER';
      NO_LOAD_CHECK='Both';
      NO_IO_CHECK='Both';
      NO_ASSERT_CHECK='TRUE';
      NO_DIR_CHECK='TRUE';
      ALLOW_CONNECT='TRUE';
    'VSS1456':
      PIN_NUMBER='(0,0,0,0,0,0,0,0,0,0,0,0,0,0,0,0,0,0,0,0,0,0,0,0,0,0,0,0,0,0,ER15,0,0,0,0,0,0,0,0,0,0,0)';
      PINUSE='POWER';
      NO_LOAD_CHECK='Both';
      NO_IO_CHECK='Both';
      NO_ASSERT_CHECK='TRUE';
      NO_DIR_CHECK='TRUE';
      ALLOW_CONNECT='TRUE';
    'VSS1455':
      PIN_NUMBER='(0,0,0,0,0,0,0,0,0,0,0,0,0,0,0,0,0,0,0,0,0,0,0,0,0,0,0,0,0,0,EK14,0,0,0,0,0,0,0,0,0,0,0)';
      PINUSE='POWER';
      NO_LOAD_CHECK='Both';
      NO_IO_CHECK='Both';
      NO_ASSERT_CHECK='TRUE';
      NO_DIR_CHECK='TRUE';
      ALLOW_CONNECT='TRUE';
    'VSS1454':
      PIN_NUMBER='(0,0,0,0,0,0,0,0,0,0,0,0,0,0,0,0,0,0,0,0,0,0,0,0,0,0,0,0,0,0,EP77,0,0,0,0,0,0,0,0,0,0,0)';
      PINUSE='POWER';
      NO_LOAD_CHECK='Both';
      NO_IO_CHECK='Both';
      NO_ASSERT_CHECK='TRUE';
      NO_DIR_CHECK='TRUE';
      ALLOW_CONNECT='TRUE';
    'VSS1453':
      PIN_NUMBER='(0,0,0,0,0,0,0,0,0,0,0,0,0,0,0,0,0,0,0,0,0,0,0,0,0,0,0,0,0,0,EP71,0,0,0,0,0,0,0,0,0,0,0)';
      PINUSE='POWER';
      NO_LOAD_CHECK='Both';
      NO_IO_CHECK='Both';
      NO_ASSERT_CHECK='TRUE';
      NO_DIR_CHECK='TRUE';
      ALLOW_CONNECT='TRUE';
    'VSS1452':
      PIN_NUMBER='(0,0,0,0,0,0,0,0,0,0,0,0,0,0,0,0,0,0,0,0,0,0,0,0,0,0,0,0,0,0,EP69,0,0,0,0,0,0,0,0,0,0,0)';
      PINUSE='POWER';
      NO_LOAD_CHECK='Both';
      NO_IO_CHECK='Both';
      NO_ASSERT_CHECK='TRUE';
      NO_DIR_CHECK='TRUE';
      ALLOW_CONNECT='TRUE';
    'VSS1451':
      PIN_NUMBER='(0,0,0,0,0,0,0,0,0,0,0,0,0,0,0,0,0,0,0,0,0,0,0,0,0,0,0,0,0,0,EK10,0,0,0,0,0,0,0,0,0,0,0)';
      PINUSE='POWER';
      NO_LOAD_CHECK='Both';
      NO_IO_CHECK='Both';
      NO_ASSERT_CHECK='TRUE';
      NO_DIR_CHECK='TRUE';
      ALLOW_CONNECT='TRUE';
    'VSS1450':
      PIN_NUMBER='(0,0,0,0,0,0,0,0,0,0,0,0,0,0,0,0,0,0,0,0,0,0,0,0,0,0,0,0,0,0,EJ9,0,0,0,0,0,0,0,0,0,0,0)';
      PINUSE='POWER';
      NO_LOAD_CHECK='Both';
      NO_IO_CHECK='Both';
      NO_ASSERT_CHECK='TRUE';
      NO_DIR_CHECK='TRUE';
      ALLOW_CONNECT='TRUE';
    'VSS1449':
      PIN_NUMBER='(0,0,0,0,0,0,0,0,0,0,0,0,0,0,0,0,0,0,0,0,0,0,0,0,0,0,0,0,0,0,EJ88,0,0,0,0,0,0,0,0,0,0,0)';
      PINUSE='POWER';
      NO_LOAD_CHECK='Both';
      NO_IO_CHECK='Both';
      NO_ASSERT_CHECK='TRUE';
      NO_DIR_CHECK='TRUE';
      ALLOW_CONNECT='TRUE';
    'VSS1448':
      PIN_NUMBER='(0,0,0,0,0,0,0,0,0,0,0,0,0,0,0,0,0,0,0,0,0,0,0,0,0,0,0,0,0,0,EJ78,0,0,0,0,0,0,0,0,0,0,0)';
      PINUSE='POWER';
      NO_LOAD_CHECK='Both';
      NO_IO_CHECK='Both';
      NO_ASSERT_CHECK='TRUE';
      NO_DIR_CHECK='TRUE';
      ALLOW_CONNECT='TRUE';
    'VSS1447':
      PIN_NUMBER='(0,0,0,0,0,0,0,0,0,0,0,0,0,0,0,0,0,0,0,0,0,0,0,0,0,0,0,0,0,0,EJ74,0,0,0,0,0,0,0,0,0,0,0)';
      PINUSE='POWER';
      NO_LOAD_CHECK='Both';
      NO_IO_CHECK='Both';
      NO_ASSERT_CHECK='TRUE';
      NO_DIR_CHECK='TRUE';
      ALLOW_CONNECT='TRUE';
    'VSS1446':
      PIN_NUMBER='(0,0,0,0,0,0,0,0,0,0,0,0,0,0,0,0,0,0,0,0,0,0,0,0,0,0,0,0,0,0,EN9,0,0,0,0,0,0,0,0,0,0,0)';
      PINUSE='POWER';
      NO_LOAD_CHECK='Both';
      NO_IO_CHECK='Both';
      NO_ASSERT_CHECK='TRUE';
      NO_DIR_CHECK='TRUE';
      ALLOW_CONNECT='TRUE';
    'VSS1445':
      PIN_NUMBER='(0,0,0,0,0,0,0,0,0,0,0,0,0,0,0,0,0,0,0,0,0,0,0,0,0,0,0,0,0,0,EN88,0,0,0,0,0,0,0,0,0,0,0)';
      PINUSE='POWER';
      NO_LOAD_CHECK='Both';
      NO_IO_CHECK='Both';
      NO_ASSERT_CHECK='TRUE';
      NO_DIR_CHECK='TRUE';
      ALLOW_CONNECT='TRUE';
    'VSS1444':
      PIN_NUMBER='(0,0,0,0,0,0,0,0,0,0,0,0,0,0,0,0,0,0,0,0,0,0,0,0,0,0,0,0,0,0,EJ7,0,0,0,0,0,0,0,0,0,0,0)';
      PINUSE='POWER';
      NO_LOAD_CHECK='Both';
      NO_IO_CHECK='Both';
      NO_ASSERT_CHECK='TRUE';
      NO_DIR_CHECK='TRUE';
      ALLOW_CONNECT='TRUE';
    'VSS1443':
      PIN_NUMBER='(0,0,0,0,0,0,0,0,0,0,0,0,0,0,0,0,0,0,0,0,0,0,0,0,0,0,0,0,0,0,EJ66,0,0,0,0,0,0,0,0,0,0,0)';
      PINUSE='POWER';
      NO_LOAD_CHECK='Both';
      NO_IO_CHECK='Both';
      NO_ASSERT_CHECK='TRUE';
      NO_DIR_CHECK='TRUE';
      ALLOW_CONNECT='TRUE';
    'VSS1442':
      PIN_NUMBER='(0,0,0,0,0,0,0,0,0,0,0,0,0,0,0,0,0,0,0,0,0,0,0,0,0,0,0,0,0,0,EJ60,0,0,0,0,0,0,0,0,0,0,0)';
      PINUSE='POWER';
      NO_LOAD_CHECK='Both';
      NO_IO_CHECK='Both';
      NO_ASSERT_CHECK='TRUE';
      NO_DIR_CHECK='TRUE';
      ALLOW_CONNECT='TRUE';
    'VSS1441':
      PIN_NUMBER='(0,0,0,0,0,0,0,0,0,0,0,0,0,0,0,0,0,0,0,0,0,0,0,0,0,0,0,0,0,0,EN72,0,0,0,0,0,0,0,0,0,0,0)';
      PINUSE='POWER';
      NO_LOAD_CHECK='Both';
      NO_IO_CHECK='Both';
      NO_ASSERT_CHECK='TRUE';
      NO_DIR_CHECK='TRUE';
      ALLOW_CONNECT='TRUE';
    'VSS1440':
      PIN_NUMBER='(0,0,0,0,0,0,0,0,0,0,0,0,0,0,0,0,0,0,0,0,0,0,0,0,0,0,0,0,0,0,EN66,0,0,0,0,0,0,0,0,0,0,0)';
      PINUSE='POWER';
      NO_LOAD_CHECK='Both';
      NO_IO_CHECK='Both';
      NO_ASSERT_CHECK='TRUE';
      NO_DIR_CHECK='TRUE';
      ALLOW_CONNECT='TRUE';
    'VSS1439':
      PIN_NUMBER='(0,0,0,0,0,0,0,0,0,0,0,0,0,0,0,0,0,0,0,0,0,0,0,0,0,0,0,0,0,0,EJ56,0,0,0,0,0,0,0,0,0,0,0)';
      PINUSE='POWER';
      NO_LOAD_CHECK='Both';
      NO_IO_CHECK='Both';
      NO_ASSERT_CHECK='TRUE';
      NO_DIR_CHECK='TRUE';
      ALLOW_CONNECT='TRUE';
    'VSS1438':
      PIN_NUMBER='(0,0,0,0,0,0,0,0,0,0,0,0,0,0,0,0,0,0,0,0,0,0,0,0,0,0,0,0,0,0,EN62,0,0,0,0,0,0,0,0,0,0,0)';
      PINUSE='POWER';
      NO_LOAD_CHECK='Both';
      NO_IO_CHECK='Both';
      NO_ASSERT_CHECK='TRUE';
      NO_DIR_CHECK='TRUE';
      ALLOW_CONNECT='TRUE';
    'VSS1437':
      PIN_NUMBER='(0,0,0,0,0,0,0,0,0,0,0,0,0,0,0,0,0,0,0,0,0,0,0,0,0,0,0,0,0,0,EN60,0,0,0,0,0,0,0,0,0,0,0)';
      PINUSE='POWER';
      NO_LOAD_CHECK='Both';
      NO_IO_CHECK='Both';
      NO_ASSERT_CHECK='TRUE';
      NO_DIR_CHECK='TRUE';
      ALLOW_CONNECT='TRUE';
    'VSS1436':
      PIN_NUMBER='(0,0,0,0,0,0,0,0,0,0,0,0,0,0,0,0,0,0,0,0,0,0,0,0,0,0,0,0,0,0,EN58,0,0,0,0,0,0,0,0,0,0,0)';
      PINUSE='POWER';
      NO_LOAD_CHECK='Both';
      NO_IO_CHECK='Both';
      NO_ASSERT_CHECK='TRUE';
      NO_DIR_CHECK='TRUE';
      ALLOW_CONNECT='TRUE';
    'VSS1435':
      PIN_NUMBER='(0,0,0,0,0,0,0,0,0,0,0,0,0,0,0,0,0,0,0,0,0,0,0,0,0,0,0,0,0,0,EJ50,0,0,0,0,0,0,0,0,0,0,0)';
      PINUSE='POWER';
      NO_LOAD_CHECK='Both';
      NO_IO_CHECK='Both';
      NO_ASSERT_CHECK='TRUE';
      NO_DIR_CHECK='TRUE';
      ALLOW_CONNECT='TRUE';
    'VSS1434':
      PIN_NUMBER='(0,0,0,0,0,0,0,0,0,0,0,0,0,0,0,0,0,0,0,0,0,0,0,0,0,0,0,0,0,0,EJ48,0,0,0,0,0,0,0,0,0,0,0)';
      PINUSE='POWER';
      NO_LOAD_CHECK='Both';
      NO_IO_CHECK='Both';
      NO_ASSERT_CHECK='TRUE';
      NO_DIR_CHECK='TRUE';
      ALLOW_CONNECT='TRUE';
    'VSS1433':
      PIN_NUMBER='(0,0,0,0,0,0,0,0,0,0,0,0,0,0,0,0,0,0,0,0,0,0,0,0,0,0,0,0,0,0,EJ43,0,0,0,0,0,0,0,0,0,0,0)';
      PINUSE='POWER';
      NO_LOAD_CHECK='Both';
      NO_IO_CHECK='Both';
      NO_ASSERT_CHECK='TRUE';
      NO_DIR_CHECK='TRUE';
      ALLOW_CONNECT='TRUE';
    'VSS1432':
      PIN_NUMBER='(0,0,0,0,0,0,0,0,0,0,0,0,0,0,0,0,0,0,0,0,0,0,0,0,0,0,0,0,0,0,EJ41,0,0,0,0,0,0,0,0,0,0,0)';
      PINUSE='POWER';
      NO_LOAD_CHECK='Both';
      NO_IO_CHECK='Both';
      NO_ASSERT_CHECK='TRUE';
      NO_DIR_CHECK='TRUE';
      ALLOW_CONNECT='TRUE';
    'VSS1431':
      PIN_NUMBER='(0,0,0,0,0,0,0,0,0,0,0,0,0,0,0,0,0,0,0,0,0,0,0,0,0,0,0,0,0,0,EJ37,0,0,0,0,0,0,0,0,0,0,0)';
      PINUSE='POWER';
      NO_LOAD_CHECK='Both';
      NO_IO_CHECK='Both';
      NO_ASSERT_CHECK='TRUE';
      NO_DIR_CHECK='TRUE';
      ALLOW_CONNECT='TRUE';
    'VSS1430':
      PIN_NUMBER='(0,0,0,0,0,0,0,0,0,0,0,0,0,0,0,0,0,0,0,0,0,0,0,0,0,0,0,0,0,0,EJ31,0,0,0,0,0,0,0,0,0,0,0)';
      PINUSE='POWER';
      NO_LOAD_CHECK='Both';
      NO_IO_CHECK='Both';
      NO_ASSERT_CHECK='TRUE';
      NO_DIR_CHECK='TRUE';
      ALLOW_CONNECT='TRUE';
    'VSS1429':
      PIN_NUMBER='(0,0,0,0,0,0,0,0,0,0,0,0,0,0,0,0,0,0,0,0,0,0,0,0,0,0,0,0,0,0,EJ29,0,0,0,0,0,0,0,0,0,0,0)';
      PINUSE='POWER';
      NO_LOAD_CHECK='Both';
      NO_IO_CHECK='Both';
      NO_ASSERT_CHECK='TRUE';
      NO_DIR_CHECK='TRUE';
      ALLOW_CONNECT='TRUE';
    'VSS1428':
      PIN_NUMBER='(0,0,0,0,0,0,0,0,0,0,0,0,0,0,0,0,0,0,0,0,0,0,0,0,0,0,0,0,0,0,EJ23,0,0,0,0,0,0,0,0,0,0,0)';
      PINUSE='POWER';
      NO_LOAD_CHECK='Both';
      NO_IO_CHECK='Both';
      NO_ASSERT_CHECK='TRUE';
      NO_DIR_CHECK='TRUE';
      ALLOW_CONNECT='TRUE';
    'VSS1427':
      PIN_NUMBER='(0,0,0,0,0,0,0,0,0,0,0,0,0,0,0,0,0,0,0,0,0,0,0,0,0,0,0,0,0,0,EN39,0,0,0,0,0,0,0,0,0,0,0)';
      PINUSE='POWER';
      NO_LOAD_CHECK='Both';
      NO_IO_CHECK='Both';
      NO_ASSERT_CHECK='TRUE';
      NO_DIR_CHECK='TRUE';
      ALLOW_CONNECT='TRUE';
    'VSS1426':
      PIN_NUMBER='(0,0,0,0,0,0,0,0,0,0,0,0,0,0,0,0,0,0,0,0,0,0,0,0,0,0,0,0,0,0,EJ19,0,0,0,0,0,0,0,0,0,0,0)';
      PINUSE='POWER';
      NO_LOAD_CHECK='Both';
      NO_IO_CHECK='Both';
      NO_ASSERT_CHECK='TRUE';
      NO_DIR_CHECK='TRUE';
      ALLOW_CONNECT='TRUE';
    'VSS1425':
      PIN_NUMBER='(0,0,0,0,0,0,0,0,0,0,0,0,0,0,0,0,0,0,0,0,0,0,0,0,0,0,0,0,0,0,EJ13,0,0,0,0,0,0,0,0,0,0,0)';
      PINUSE='POWER';
      NO_LOAD_CHECK='Both';
      NO_IO_CHECK='Both';
      NO_ASSERT_CHECK='TRUE';
      NO_DIR_CHECK='TRUE';
      ALLOW_CONNECT='TRUE';
    'VSS1424':
      PIN_NUMBER='(0,0,0,0,0,0,0,0,0,0,0,0,0,0,0,0,0,0,0,0,0,0,0,0,0,0,0,0,0,0,EH83,0,0,0,0,0,0,0,0,0,0,0)';
      PINUSE='POWER';
      NO_LOAD_CHECK='Both';
      NO_IO_CHECK='Both';
      NO_ASSERT_CHECK='TRUE';
      NO_DIR_CHECK='TRUE';
      ALLOW_CONNECT='TRUE';
    'VSS1423':
      PIN_NUMBER='(0,0,0,0,0,0,0,0,0,0,0,0,0,0,0,0,0,0,0,0,0,0,0,0,0,0,0,0,0,0,EH81,0,0,0,0,0,0,0,0,0,0,0)';
      PINUSE='POWER';
      NO_LOAD_CHECK='Both';
      NO_IO_CHECK='Both';
      NO_ASSERT_CHECK='TRUE';
      NO_DIR_CHECK='TRUE';
      ALLOW_CONNECT='TRUE';
    'VSS1422':
      PIN_NUMBER='(0,0,0,0,0,0,0,0,0,0,0,0,0,0,0,0,0,0,0,0,0,0,0,0,0,0,0,0,0,0,EH73,0,0,0,0,0,0,0,0,0,0,0)';
      PINUSE='POWER';
      NO_LOAD_CHECK='Both';
      NO_IO_CHECK='Both';
      NO_ASSERT_CHECK='TRUE';
      NO_DIR_CHECK='TRUE';
      ALLOW_CONNECT='TRUE';
    'VSS1421':
      PIN_NUMBER='(0,0,0,0,0,0,0,0,0,0,0,0,0,0,0,0,0,0,0,0,0,0,0,0,0,0,0,0,0,0,EH49,0,0,0,0,0,0,0,0,0,0,0)';
      PINUSE='POWER';
      NO_LOAD_CHECK='Both';
      NO_IO_CHECK='Both';
      NO_ASSERT_CHECK='TRUE';
      NO_DIR_CHECK='TRUE';
      ALLOW_CONNECT='TRUE';
    'VSS1419':
      PIN_NUMBER='(0,0,0,0,0,0,0,0,0,0,0,0,0,0,0,0,0,0,0,0,0,0,0,0,0,0,0,0,0,0,EH36,0,0,0,0,0,0,0,0,0,0,0)';
      PINUSE='POWER';
      NO_LOAD_CHECK='Both';
      NO_IO_CHECK='Both';
      NO_ASSERT_CHECK='TRUE';
      NO_DIR_CHECK='TRUE';
      ALLOW_CONNECT='TRUE';
    'VSS1409':
      PIN_NUMBER='(0,0,0,0,0,0,0,0,0,0,0,0,0,0,0,0,0,0,0,0,0,0,0,0,0,0,0,0,0,0,EM79,0,0,0,0,0,0,0,0,0,0,0)';
      PINUSE='POWER';
      NO_LOAD_CHECK='Both';
      NO_IO_CHECK='Both';
      NO_ASSERT_CHECK='TRUE';
      NO_DIR_CHECK='TRUE';
      ALLOW_CONNECT='TRUE';
    'VSS1405':
      PIN_NUMBER='(0,0,0,0,0,0,0,0,0,0,0,0,0,0,0,0,0,0,0,0,0,0,0,0,0,0,0,0,0,0,EM49,0,0,0,0,0,0,0,0,0,0,0)';
      PINUSE='POWER';
      NO_LOAD_CHECK='Both';
      NO_IO_CHECK='Both';
      NO_ASSERT_CHECK='TRUE';
      NO_DIR_CHECK='TRUE';
      ALLOW_CONNECT='TRUE';
    'VSS1401':
      PIN_NUMBER='(0,0,0,0,0,0,0,0,0,0,0,0,0,0,0,0,0,0,0,0,0,0,0,0,0,0,0,0,0,0,EL9,0,0,0,0,0,0,0,0,0,0,0)';
      PINUSE='POWER';
      NO_LOAD_CHECK='Both';
      NO_IO_CHECK='Both';
      NO_ASSERT_CHECK='TRUE';
      NO_DIR_CHECK='TRUE';
      ALLOW_CONNECT='TRUE';
    'VSS1400':
      PIN_NUMBER='(0,0,0,0,0,0,0,0,0,0,0,0,0,0,0,0,0,0,0,0,0,0,0,0,0,0,0,0,0,0,EL86,0,0,0,0,0,0,0,0,0,0,0)';
      PINUSE='POWER';
      NO_LOAD_CHECK='Both';
      NO_IO_CHECK='Both';
      NO_ASSERT_CHECK='TRUE';
      NO_DIR_CHECK='TRUE';
      ALLOW_CONNECT='TRUE';
    'VSS1398':
      PIN_NUMBER='(0,0,0,0,0,0,0,0,0,0,0,0,0,0,0,0,0,0,0,0,0,0,0,0,0,0,0,0,0,0,EL72,0,0,0,0,0,0,0,0,0,0,0)';
      PINUSE='POWER';
      NO_LOAD_CHECK='Both';
      NO_IO_CHECK='Both';
      NO_ASSERT_CHECK='TRUE';
      NO_DIR_CHECK='TRUE';
      ALLOW_CONNECT='TRUE';
    'VSS1397':
      PIN_NUMBER='(0,0,0,0,0,0,0,0,0,0,0,0,0,0,0,0,0,0,0,0,0,0,0,0,0,0,0,0,0,0,EL70,0,0,0,0,0,0,0,0,0,0,0)';
      PINUSE='POWER';
      NO_LOAD_CHECK='Both';
      NO_IO_CHECK='Both';
      NO_ASSERT_CHECK='TRUE';
      NO_DIR_CHECK='TRUE';
      ALLOW_CONNECT='TRUE';
    'VSS1396':
      PIN_NUMBER='(0,0,0,0,0,0,0,0,0,0,0,0,0,0,0,0,0,0,0,0,0,0,0,0,0,0,0,0,0,0,EL7,0,0,0,0,0,0,0,0,0,0,0)';
      PINUSE='POWER';
      NO_LOAD_CHECK='Both';
      NO_IO_CHECK='Both';
      NO_ASSERT_CHECK='TRUE';
      NO_DIR_CHECK='TRUE';
      ALLOW_CONNECT='TRUE';
    'VSS1394':
      PIN_NUMBER='(0,0,0,0,0,0,0,0,0,0,0,0,0,0,0,0,0,0,0,0,0,0,0,0,0,0,0,0,0,0,EL58,0,0,0,0,0,0,0,0,0,0,0)';
      PINUSE='POWER';
      NO_LOAD_CHECK='Both';
      NO_IO_CHECK='Both';
      NO_ASSERT_CHECK='TRUE';
      NO_DIR_CHECK='TRUE';
      ALLOW_CONNECT='TRUE';
    'VSS1391':
      PIN_NUMBER='(0,0,0,0,0,0,0,0,0,0,0,0,0,0,0,0,0,0,0,0,0,0,0,0,0,0,0,0,0,0,EL52,0,0,0,0,0,0,0,0,0,0,0)';
      PINUSE='POWER';
      NO_LOAD_CHECK='Both';
      NO_IO_CHECK='Both';
      NO_ASSERT_CHECK='TRUE';
      NO_DIR_CHECK='TRUE';
      ALLOW_CONNECT='TRUE';
    'VSS1381':
      PIN_NUMBER='(0,0,0,0,0,0,0,0,0,0,0,0,0,0,0,0,0,0,0,0,0,0,0,0,0,0,0,0,0,0,EL15,0,0,0,0,0,0,0,0,0,0,0)';
      PINUSE='POWER';
      NO_LOAD_CHECK='Both';
      NO_IO_CHECK='Both';
      NO_ASSERT_CHECK='TRUE';
      NO_DIR_CHECK='TRUE';
      ALLOW_CONNECT='TRUE';
    'VSS1380':
      PIN_NUMBER='(0,0,0,0,0,0,0,0,0,0,0,0,0,0,0,0,0,0,0,0,0,0,0,0,0,0,0,0,0,0,EK89,0,0,0,0,0,0,0,0,0,0,0)';
      PINUSE='POWER';
      NO_LOAD_CHECK='Both';
      NO_IO_CHECK='Both';
      NO_ASSERT_CHECK='TRUE';
      NO_DIR_CHECK='TRUE';
      ALLOW_CONNECT='TRUE';
    'VSS1379':
      PIN_NUMBER='(0,0,0,0,0,0,0,0,0,0,0,0,0,0,0,0,0,0,0,0,0,0,0,0,0,0,0,0,0,0,EK83,0,0,0,0,0,0,0,0,0,0,0)';
      PINUSE='POWER';
      NO_LOAD_CHECK='Both';
      NO_IO_CHECK='Both';
      NO_ASSERT_CHECK='TRUE';
      NO_DIR_CHECK='TRUE';
      ALLOW_CONNECT='TRUE';
    'VSS1378':
      PIN_NUMBER='(0,0,0,0,0,0,0,0,0,0,0,0,0,0,0,0,0,0,0,0,0,0,0,0,0,0,0,0,0,0,EK79,0,0,0,0,0,0,0,0,0,0,0)';
      PINUSE='POWER';
      NO_LOAD_CHECK='Both';
      NO_IO_CHECK='Both';
      NO_ASSERT_CHECK='TRUE';
      NO_DIR_CHECK='TRUE';
      ALLOW_CONNECT='TRUE';
    'VSS1377':
      PIN_NUMBER='(0,0,0,0,0,0,0,0,0,0,0,0,0,0,0,0,0,0,0,0,0,0,0,0,0,0,0,0,0,0,EK77,0,0,0,0,0,0,0,0,0,0,0)';
      PINUSE='POWER';
      NO_LOAD_CHECK='Both';
      NO_IO_CHECK='Both';
      NO_ASSERT_CHECK='TRUE';
      NO_DIR_CHECK='TRUE';
      ALLOW_CONNECT='TRUE';
    'VSS1375':
      PIN_NUMBER='(0,0,0,0,0,0,0,0,0,0,0,0,0,0,0,0,0,0,0,0,0,0,0,0,0,0,0,0,0,0,EK71,0,0,0,0,0,0,0,0,0,0,0)';
      PINUSE='POWER';
      NO_LOAD_CHECK='Both';
      NO_IO_CHECK='Both';
      NO_ASSERT_CHECK='TRUE';
      NO_DIR_CHECK='TRUE';
      ALLOW_CONNECT='TRUE';
    'VSS1372':
      PIN_NUMBER='(0,0,0,0,0,0,0,0,0,0,0,0,0,0,0,0,0,0,0,0,0,0,0,0,0,0,0,0,0,0,EK63,0,0,0,0,0,0,0,0,0,0,0)';
      PINUSE='POWER';
      NO_LOAD_CHECK='Both';
      NO_IO_CHECK='Both';
      NO_ASSERT_CHECK='TRUE';
      NO_DIR_CHECK='TRUE';
      ALLOW_CONNECT='TRUE';
    'VSS1371':
      PIN_NUMBER='(0,0,0,0,0,0,0,0,0,0,0,0,0,0,0,0,0,0,0,0,0,0,0,0,0,0,0,0,0,0,EK59,0,0,0,0,0,0,0,0,0,0,0)';
      PINUSE='POWER';
      NO_LOAD_CHECK='Both';
      NO_IO_CHECK='Both';
      NO_ASSERT_CHECK='TRUE';
      NO_DIR_CHECK='TRUE';
      ALLOW_CONNECT='TRUE';
    'VSS1369':
      PIN_NUMBER='(0,0,0,0,0,0,0,0,0,0,0,0,0,0,0,0,0,0,0,0,0,0,0,0,0,0,0,0,0,0,EK53,0,0,0,0,0,0,0,0,0,0,0)';
      PINUSE='POWER';
      NO_LOAD_CHECK='Both';
      NO_IO_CHECK='Both';
      NO_ASSERT_CHECK='TRUE';
      NO_DIR_CHECK='TRUE';
      ALLOW_CONNECT='TRUE';
    'VSS1368':
      PIN_NUMBER='(0,0,0,0,0,0,0,0,0,0,0,0,0,0,0,0,0,0,0,0,0,0,0,0,0,0,0,0,0,0,EK51,0,0,0,0,0,0,0,0,0,0,0)';
      PINUSE='POWER';
      NO_LOAD_CHECK='Both';
      NO_IO_CHECK='Both';
      NO_ASSERT_CHECK='TRUE';
      NO_DIR_CHECK='TRUE';
      ALLOW_CONNECT='TRUE';
    'VSS1366':
      PIN_NUMBER='(0,0,0,0,0,0,0,0,0,0,0,0,0,0,0,0,0,0,0,0,0,0,0,0,0,0,0,0,0,0,EK44,0,0,0,0,0,0,0,0,0,0,0)';
      PINUSE='POWER';
      NO_LOAD_CHECK='Both';
      NO_IO_CHECK='Both';
      NO_ASSERT_CHECK='TRUE';
      NO_DIR_CHECK='TRUE';
      ALLOW_CONNECT='TRUE';
    'VSS1359':
      PIN_NUMBER='(0,0,0,0,0,0,0,0,0,0,0,0,0,0,0,0,0,0,0,0,0,0,0,0,0,0,0,0,0,0,EK26,0,0,0,0,0,0,0,0,0,0,0)';
      PINUSE='POWER';
      NO_LOAD_CHECK='Both';
      NO_IO_CHECK='Both';
      NO_ASSERT_CHECK='TRUE';
      NO_DIR_CHECK='TRUE';
      ALLOW_CONNECT='TRUE';
    'VSS1357':
      PIN_NUMBER='(0,0,0,0,0,0,0,0,0,0,0,0,0,0,0,0,0,0,0,0,0,0,0,0,0,0,0,0,0,0,EK20,0,0,0,0,0,0,0,0,0,0,0)';
      PINUSE='POWER';
      NO_LOAD_CHECK='Both';
      NO_IO_CHECK='Both';
      NO_ASSERT_CHECK='TRUE';
      NO_DIR_CHECK='TRUE';
      ALLOW_CONNECT='TRUE';
    'VSS1355':
      PIN_NUMBER='(0,0,0,0,0,0,0,0,0,0,0,0,0,0,0,0,0,0,0,0,0,0,0,0,0,0,0,0,0,0,EK16,0,0,0,0,0,0,0,0,0,0,0)';
      PINUSE='POWER';
      NO_LOAD_CHECK='Both';
      NO_IO_CHECK='Both';
      NO_ASSERT_CHECK='TRUE';
      NO_DIR_CHECK='TRUE';
      ALLOW_CONNECT='TRUE';
    'VSS1347':
      PIN_NUMBER='(0,0,0,0,0,0,0,0,0,0,0,0,0,0,0,0,0,0,0,0,0,0,0,0,0,0,0,0,0,0,EJ72,0,0,0,0,0,0,0,0,0,0,0)';
      PINUSE='POWER';
      NO_LOAD_CHECK='Both';
      NO_IO_CHECK='Both';
      NO_ASSERT_CHECK='TRUE';
      NO_DIR_CHECK='TRUE';
      ALLOW_CONNECT='TRUE';
    'VSS1345':
      PIN_NUMBER='(0,0,0,0,0,0,0,0,0,0,0,0,0,0,0,0,0,0,0,0,0,0,0,0,0,0,0,0,0,0,EJ68,0,0,0,0,0,0,0,0,0,0,0)';
      PINUSE='POWER';
      NO_LOAD_CHECK='Both';
      NO_IO_CHECK='Both';
      NO_ASSERT_CHECK='TRUE';
      NO_DIR_CHECK='TRUE';
      ALLOW_CONNECT='TRUE';
    'VSS1343':
      PIN_NUMBER='(0,0,0,0,0,0,0,0,0,0,0,0,0,0,0,0,0,0,0,0,0,0,0,0,0,0,0,0,0,0,EJ62,0,0,0,0,0,0,0,0,0,0,0)';
      PINUSE='POWER';
      NO_LOAD_CHECK='Both';
      NO_IO_CHECK='Both';
      NO_ASSERT_CHECK='TRUE';
      NO_DIR_CHECK='TRUE';
      ALLOW_CONNECT='TRUE';
    'VSS1340':
      PIN_NUMBER='(0,0,0,0,0,0,0,0,0,0,0,0,0,0,0,0,0,0,0,0,0,0,0,0,0,0,0,0,0,0,EJ54,0,0,0,0,0,0,0,0,0,0,0)';
      PINUSE='POWER';
      NO_LOAD_CHECK='Both';
      NO_IO_CHECK='Both';
      NO_ASSERT_CHECK='TRUE';
      NO_DIR_CHECK='TRUE';
      ALLOW_CONNECT='TRUE';
    'VSS1334':
      PIN_NUMBER='(0,0,0,0,0,0,0,0,0,0,0,0,0,0,0,0,0,0,0,0,0,0,0,0,0,0,0,0,0,0,EJ35,0,0,0,0,0,0,0,0,0,0,0)';
      PINUSE='POWER';
      NO_LOAD_CHECK='Both';
      NO_IO_CHECK='Both';
      NO_ASSERT_CHECK='TRUE';
      NO_DIR_CHECK='TRUE';
      ALLOW_CONNECT='TRUE';
    'VSS1331':
      PIN_NUMBER='(0,0,0,0,0,0,0,0,0,0,0,0,0,0,0,0,0,0,0,0,0,0,0,0,0,0,0,0,0,0,EJ25,0,0,0,0,0,0,0,0,0,0,0)';
      PINUSE='POWER';
      NO_LOAD_CHECK='Both';
      NO_IO_CHECK='Both';
      NO_ASSERT_CHECK='TRUE';
      NO_DIR_CHECK='TRUE';
      ALLOW_CONNECT='TRUE';
    'VSS1328':
      PIN_NUMBER='(0,0,0,0,0,0,0,0,0,0,0,0,0,0,0,0,0,0,0,0,0,0,0,0,0,0,0,0,0,0,EJ17,0,0,0,0,0,0,0,0,0,0,0)';
      PINUSE='POWER';
      NO_LOAD_CHECK='Both';
      NO_IO_CHECK='Both';
      NO_ASSERT_CHECK='TRUE';
      NO_DIR_CHECK='TRUE';
      ALLOW_CONNECT='TRUE';
    'VSS1325':
      PIN_NUMBER='(0,0,0,0,0,0,0,0,0,0,0,0,0,0,0,0,0,0,0,0,0,0,0,0,0,0,0,0,0,0,EJ11,0,0,0,0,0,0,0,0,0,0,0)';
      PINUSE='POWER';
      NO_LOAD_CHECK='Both';
      NO_IO_CHECK='Both';
      NO_ASSERT_CHECK='TRUE';
      NO_DIR_CHECK='TRUE';
      ALLOW_CONNECT='TRUE';
    'VSS1322':
      PIN_NUMBER='(0,0,0,0,0,0,0,0,0,0,0,0,0,0,0,0,0,0,0,0,0,0,0,0,0,0,0,0,0,0,EH79,0,0,0,0,0,0,0,0,0,0,0)';
      PINUSE='POWER';
      NO_LOAD_CHECK='Both';
      NO_IO_CHECK='Both';
      NO_ASSERT_CHECK='TRUE';
      NO_DIR_CHECK='TRUE';
      ALLOW_CONNECT='TRUE';
    'VSS1320':
      PIN_NUMBER='(0,0,0,0,0,0,0,0,0,0,0,0,0,0,0,0,0,0,0,0,0,0,0,0,0,0,0,0,0,0,EH67,0,0,0,0,0,0,0,0,0,0,0)';
      PINUSE='POWER';
      NO_LOAD_CHECK='Both';
      NO_IO_CHECK='Both';
      NO_ASSERT_CHECK='TRUE';
      NO_DIR_CHECK='TRUE';
      ALLOW_CONNECT='TRUE';
    'VSS1319':
      PIN_NUMBER='(0,0,0,0,0,0,0,0,0,0,0,0,0,0,0,0,0,0,0,0,0,0,0,0,0,0,0,0,0,0,EH61,0,0,0,0,0,0,0,0,0,0,0)';
      PINUSE='POWER';
      NO_LOAD_CHECK='Both';
      NO_IO_CHECK='Both';
      NO_ASSERT_CHECK='TRUE';
      NO_DIR_CHECK='TRUE';
      ALLOW_CONNECT='TRUE';
    'VSS1315':
      PIN_NUMBER='(0,0,0,0,0,0,0,0,0,0,0,0,0,0,0,0,0,0,0,0,0,0,0,0,0,0,0,0,0,0,EH55,0,0,0,0,0,0,0,0,0,0,0)';
      PINUSE='POWER';
      NO_LOAD_CHECK='Both';
      NO_IO_CHECK='Both';
      NO_ASSERT_CHECK='TRUE';
      NO_DIR_CHECK='TRUE';
      ALLOW_CONNECT='TRUE';
    'VSS1312':
      PIN_NUMBER='(0,0,0,0,0,0,0,0,0,0,0,0,0,0,0,0,0,0,0,0,0,0,0,0,0,0,0,0,0,0,EH42,0,0,0,0,0,0,0,0,0,0,0)';
      PINUSE='POWER';
      NO_LOAD_CHECK='Both';
      NO_IO_CHECK='Both';
      NO_ASSERT_CHECK='TRUE';
      NO_DIR_CHECK='TRUE';
      ALLOW_CONNECT='TRUE';
    'VSS1420':
      PIN_NUMBER='(0,0,0,0,0,0,0,0,0,0,0,0,0,0,0,0,0,0,0,0,0,0,0,0,0,0,0,0,0,0,0,EH4,0,0,0,0,0,0,0,0,0,0)';
      PINUSE='POWER';
      NO_LOAD_CHECK='Both';
      NO_IO_CHECK='Both';
      NO_ASSERT_CHECK='TRUE';
      NO_DIR_CHECK='TRUE';
      ALLOW_CONNECT='TRUE';
    'VSS1418':
      PIN_NUMBER='(0,0,0,0,0,0,0,0,0,0,0,0,0,0,0,0,0,0,0,0,0,0,0,0,0,0,0,0,0,0,0,EH30,0,0,0,0,0,0,0,0,0,0)';
      PINUSE='POWER';
      NO_LOAD_CHECK='Both';
      NO_IO_CHECK='Both';
      NO_ASSERT_CHECK='TRUE';
      NO_DIR_CHECK='TRUE';
      ALLOW_CONNECT='TRUE';
    'VSS1417':
      PIN_NUMBER='(0,0,0,0,0,0,0,0,0,0,0,0,0,0,0,0,0,0,0,0,0,0,0,0,0,0,0,0,0,0,0,EH24,0,0,0,0,0,0,0,0,0,0)';
      PINUSE='POWER';
      NO_LOAD_CHECK='Both';
      NO_IO_CHECK='Both';
      NO_ASSERT_CHECK='TRUE';
      NO_DIR_CHECK='TRUE';
      ALLOW_CONNECT='TRUE';
    'VSS1416':
      PIN_NUMBER='(0,0,0,0,0,0,0,0,0,0,0,0,0,0,0,0,0,0,0,0,0,0,0,0,0,0,0,0,0,0,0,EH16,0,0,0,0,0,0,0,0,0,0)';
      PINUSE='POWER';
      NO_LOAD_CHECK='Both';
      NO_IO_CHECK='Both';
      NO_ASSERT_CHECK='TRUE';
      NO_DIR_CHECK='TRUE';
      ALLOW_CONNECT='TRUE';
    'VSS1415':
      PIN_NUMBER='(0,0,0,0,0,0,0,0,0,0,0,0,0,0,0,0,0,0,0,0,0,0,0,0,0,0,0,0,0,0,0,EG90,0,0,0,0,0,0,0,0,0,0)';
      PINUSE='POWER';
      NO_LOAD_CHECK='Both';
      NO_IO_CHECK='Both';
      NO_ASSERT_CHECK='TRUE';
      NO_DIR_CHECK='TRUE';
      ALLOW_CONNECT='TRUE';
    'VSS1414':
      PIN_NUMBER='(0,0,0,0,0,0,0,0,0,0,0,0,0,0,0,0,0,0,0,0,0,0,0,0,0,0,0,0,0,0,0,EG9,0,0,0,0,0,0,0,0,0,0)';
      PINUSE='POWER';
      NO_LOAD_CHECK='Both';
      NO_IO_CHECK='Both';
      NO_ASSERT_CHECK='TRUE';
      NO_DIR_CHECK='TRUE';
      ALLOW_CONNECT='TRUE';
    'VSS1413':
      PIN_NUMBER='(0,0,0,0,0,0,0,0,0,0,0,0,0,0,0,0,0,0,0,0,0,0,0,0,0,0,0,0,0,0,0,EG88,0,0,0,0,0,0,0,0,0,0)';
      PINUSE='POWER';
      NO_LOAD_CHECK='Both';
      NO_IO_CHECK='Both';
      NO_ASSERT_CHECK='TRUE';
      NO_DIR_CHECK='TRUE';
      ALLOW_CONNECT='TRUE';
    'VSS1412':
      PIN_NUMBER='(0,0,0,0,0,0,0,0,0,0,0,0,0,0,0,0,0,0,0,0,0,0,0,0,0,0,0,0,0,0,0,EG86,0,0,0,0,0,0,0,0,0,0)';
      PINUSE='POWER';
      NO_LOAD_CHECK='Both';
      NO_IO_CHECK='Both';
      NO_ASSERT_CHECK='TRUE';
      NO_DIR_CHECK='TRUE';
      ALLOW_CONNECT='TRUE';
    'VSS1411':
      PIN_NUMBER='(0,0,0,0,0,0,0,0,0,0,0,0,0,0,0,0,0,0,0,0,0,0,0,0,0,0,0,0,0,0,0,EG84,0,0,0,0,0,0,0,0,0,0)';
      PINUSE='POWER';
      NO_LOAD_CHECK='Both';
      NO_IO_CHECK='Both';
      NO_ASSERT_CHECK='TRUE';
      NO_DIR_CHECK='TRUE';
      ALLOW_CONNECT='TRUE';
    'VSS1410':
      PIN_NUMBER='(0,0,0,0,0,0,0,0,0,0,0,0,0,0,0,0,0,0,0,0,0,0,0,0,0,0,0,0,0,0,0,EG82,0,0,0,0,0,0,0,0,0,0)';
      PINUSE='POWER';
      NO_LOAD_CHECK='Both';
      NO_IO_CHECK='Both';
      NO_ASSERT_CHECK='TRUE';
      NO_DIR_CHECK='TRUE';
      ALLOW_CONNECT='TRUE';
    'VSS1408':
      PIN_NUMBER='(0,0,0,0,0,0,0,0,0,0,0,0,0,0,0,0,0,0,0,0,0,0,0,0,0,0,0,0,0,0,0,EG39,0,0,0,0,0,0,0,0,0,0)';
      PINUSE='POWER';
      NO_LOAD_CHECK='Both';
      NO_IO_CHECK='Both';
      NO_ASSERT_CHECK='TRUE';
      NO_DIR_CHECK='TRUE';
      ALLOW_CONNECT='TRUE';
    'VSS1407':
      PIN_NUMBER='(0,0,0,0,0,0,0,0,0,0,0,0,0,0,0,0,0,0,0,0,0,0,0,0,0,0,0,0,0,0,0,EF87,0,0,0,0,0,0,0,0,0,0)';
      PINUSE='POWER';
      NO_LOAD_CHECK='Both';
      NO_IO_CHECK='Both';
      NO_ASSERT_CHECK='TRUE';
      NO_DIR_CHECK='TRUE';
      ALLOW_CONNECT='TRUE';
    'VSS1406':
      PIN_NUMBER='(0,0,0,0,0,0,0,0,0,0,0,0,0,0,0,0,0,0,0,0,0,0,0,0,0,0,0,0,0,0,0,EF85,0,0,0,0,0,0,0,0,0,0)';
      PINUSE='POWER';
      NO_LOAD_CHECK='Both';
      NO_IO_CHECK='Both';
      NO_ASSERT_CHECK='TRUE';
      NO_DIR_CHECK='TRUE';
      ALLOW_CONNECT='TRUE';
    'VSS1404':
      PIN_NUMBER='(0,0,0,0,0,0,0,0,0,0,0,0,0,0,0,0,0,0,0,0,0,0,0,0,0,0,0,0,0,0,0,EF8,0,0,0,0,0,0,0,0,0,0)';
      PINUSE='POWER';
      NO_LOAD_CHECK='Both';
      NO_IO_CHECK='Both';
      NO_ASSERT_CHECK='TRUE';
      NO_DIR_CHECK='TRUE';
      ALLOW_CONNECT='TRUE';
    'VSS1403':
      PIN_NUMBER='(0,0,0,0,0,0,0,0,0,0,0,0,0,0,0,0,0,0,0,0,0,0,0,0,0,0,0,0,0,0,0,EF77,0,0,0,0,0,0,0,0,0,0)';
      PINUSE='POWER';
      NO_LOAD_CHECK='Both';
      NO_IO_CHECK='Both';
      NO_ASSERT_CHECK='TRUE';
      NO_DIR_CHECK='TRUE';
      ALLOW_CONNECT='TRUE';
    'VSS1402':
      PIN_NUMBER='(0,0,0,0,0,0,0,0,0,0,0,0,0,0,0,0,0,0,0,0,0,0,0,0,0,0,0,0,0,0,0,EF71,0,0,0,0,0,0,0,0,0,0)';
      PINUSE='POWER';
      NO_LOAD_CHECK='Both';
      NO_IO_CHECK='Both';
      NO_ASSERT_CHECK='TRUE';
      NO_DIR_CHECK='TRUE';
      ALLOW_CONNECT='TRUE';
    'VSS1399':
      PIN_NUMBER='(0,0,0,0,0,0,0,0,0,0,0,0,0,0,0,0,0,0,0,0,0,0,0,0,0,0,0,0,0,0,0,EF69,0,0,0,0,0,0,0,0,0,0)';
      PINUSE='POWER';
      NO_LOAD_CHECK='Both';
      NO_IO_CHECK='Both';
      NO_ASSERT_CHECK='TRUE';
      NO_DIR_CHECK='TRUE';
      ALLOW_CONNECT='TRUE';
    'VSS1395':
      PIN_NUMBER='(0,0,0,0,0,0,0,0,0,0,0,0,0,0,0,0,0,0,0,0,0,0,0,0,0,0,0,0,0,0,0,EF67,0,0,0,0,0,0,0,0,0,0)';
      PINUSE='POWER';
      NO_LOAD_CHECK='Both';
      NO_IO_CHECK='Both';
      NO_ASSERT_CHECK='TRUE';
      NO_DIR_CHECK='TRUE';
      ALLOW_CONNECT='TRUE';
    'VSS1393':
      PIN_NUMBER='(0,0,0,0,0,0,0,0,0,0,0,0,0,0,0,0,0,0,0,0,0,0,0,0,0,0,0,0,0,0,0,EF65,0,0,0,0,0,0,0,0,0,0)';
      PINUSE='POWER';
      NO_LOAD_CHECK='Both';
      NO_IO_CHECK='Both';
      NO_ASSERT_CHECK='TRUE';
      NO_DIR_CHECK='TRUE';
      ALLOW_CONNECT='TRUE';
    'VSS1392':
      PIN_NUMBER='(0,0,0,0,0,0,0,0,0,0,0,0,0,0,0,0,0,0,0,0,0,0,0,0,0,0,0,0,0,0,0,EF63,0,0,0,0,0,0,0,0,0,0)';
      PINUSE='POWER';
      NO_LOAD_CHECK='Both';
      NO_IO_CHECK='Both';
      NO_ASSERT_CHECK='TRUE';
      NO_DIR_CHECK='TRUE';
      ALLOW_CONNECT='TRUE';
    'VSS1390':
      PIN_NUMBER='(0,0,0,0,0,0,0,0,0,0,0,0,0,0,0,0,0,0,0,0,0,0,0,0,0,0,0,0,0,0,0,EF61,0,0,0,0,0,0,0,0,0,0)';
      PINUSE='POWER';
      NO_LOAD_CHECK='Both';
      NO_IO_CHECK='Both';
      NO_ASSERT_CHECK='TRUE';
      NO_DIR_CHECK='TRUE';
      ALLOW_CONNECT='TRUE';
    'VSS1389':
      PIN_NUMBER='(0,0,0,0,0,0,0,0,0,0,0,0,0,0,0,0,0,0,0,0,0,0,0,0,0,0,0,0,0,0,0,EF59,0,0,0,0,0,0,0,0,0,0)';
      PINUSE='POWER';
      NO_LOAD_CHECK='Both';
      NO_IO_CHECK='Both';
      NO_ASSERT_CHECK='TRUE';
      NO_DIR_CHECK='TRUE';
      ALLOW_CONNECT='TRUE';
    'VSS1388':
      PIN_NUMBER='(0,0,0,0,0,0,0,0,0,0,0,0,0,0,0,0,0,0,0,0,0,0,0,0,0,0,0,0,0,0,0,EF57,0,0,0,0,0,0,0,0,0,0)';
      PINUSE='POWER';
      NO_LOAD_CHECK='Both';
      NO_IO_CHECK='Both';
      NO_ASSERT_CHECK='TRUE';
      NO_DIR_CHECK='TRUE';
      ALLOW_CONNECT='TRUE';
    'VSS1387':
      PIN_NUMBER='(0,0,0,0,0,0,0,0,0,0,0,0,0,0,0,0,0,0,0,0,0,0,0,0,0,0,0,0,0,0,0,EF55,0,0,0,0,0,0,0,0,0,0)';
      PINUSE='POWER';
      NO_LOAD_CHECK='Both';
      NO_IO_CHECK='Both';
      NO_ASSERT_CHECK='TRUE';
      NO_DIR_CHECK='TRUE';
      ALLOW_CONNECT='TRUE';
    'VSS1386':
      PIN_NUMBER='(0,0,0,0,0,0,0,0,0,0,0,0,0,0,0,0,0,0,0,0,0,0,0,0,0,0,0,0,0,0,0,EF53,0,0,0,0,0,0,0,0,0,0)';
      PINUSE='POWER';
      NO_LOAD_CHECK='Both';
      NO_IO_CHECK='Both';
      NO_ASSERT_CHECK='TRUE';
      NO_DIR_CHECK='TRUE';
      ALLOW_CONNECT='TRUE';
    'VSS1385':
      PIN_NUMBER='(0,0,0,0,0,0,0,0,0,0,0,0,0,0,0,0,0,0,0,0,0,0,0,0,0,0,0,0,0,0,0,EF49,0,0,0,0,0,0,0,0,0,0)';
      PINUSE='POWER';
      NO_LOAD_CHECK='Both';
      NO_IO_CHECK='Both';
      NO_ASSERT_CHECK='TRUE';
      NO_DIR_CHECK='TRUE';
      ALLOW_CONNECT='TRUE';
    'VSS1384':
      PIN_NUMBER='(0,0,0,0,0,0,0,0,0,0,0,0,0,0,0,0,0,0,0,0,0,0,0,0,0,0,0,0,0,0,0,EF47,0,0,0,0,0,0,0,0,0,0)';
      PINUSE='POWER';
      NO_LOAD_CHECK='Both';
      NO_IO_CHECK='Both';
      NO_ASSERT_CHECK='TRUE';
      NO_DIR_CHECK='TRUE';
      ALLOW_CONNECT='TRUE';
    'VSS1383':
      PIN_NUMBER='(0,0,0,0,0,0,0,0,0,0,0,0,0,0,0,0,0,0,0,0,0,0,0,0,0,0,0,0,0,0,0,EF44,0,0,0,0,0,0,0,0,0,0)';
      PINUSE='POWER';
      NO_LOAD_CHECK='Both';
      NO_IO_CHECK='Both';
      NO_ASSERT_CHECK='TRUE';
      NO_DIR_CHECK='TRUE';
      ALLOW_CONNECT='TRUE';
    'VSS1382':
      PIN_NUMBER='(0,0,0,0,0,0,0,0,0,0,0,0,0,0,0,0,0,0,0,0,0,0,0,0,0,0,0,0,0,0,0,EF42,0,0,0,0,0,0,0,0,0,0)';
      PINUSE='POWER';
      NO_LOAD_CHECK='Both';
      NO_IO_CHECK='Both';
      NO_ASSERT_CHECK='TRUE';
      NO_DIR_CHECK='TRUE';
      ALLOW_CONNECT='TRUE';
    'VSS1376':
      PIN_NUMBER='(0,0,0,0,0,0,0,0,0,0,0,0,0,0,0,0,0,0,0,0,0,0,0,0,0,0,0,0,0,0,0,EF40,0,0,0,0,0,0,0,0,0,0)';
      PINUSE='POWER';
      NO_LOAD_CHECK='Both';
      NO_IO_CHECK='Both';
      NO_ASSERT_CHECK='TRUE';
      NO_DIR_CHECK='TRUE';
      ALLOW_CONNECT='TRUE';
    'VSS1374':
      PIN_NUMBER='(0,0,0,0,0,0,0,0,0,0,0,0,0,0,0,0,0,0,0,0,0,0,0,0,0,0,0,0,0,0,0,EF4,0,0,0,0,0,0,0,0,0,0)';
      PINUSE='POWER';
      NO_LOAD_CHECK='Both';
      NO_IO_CHECK='Both';
      NO_ASSERT_CHECK='TRUE';
      NO_DIR_CHECK='TRUE';
      ALLOW_CONNECT='TRUE';
    'VSS1373':
      PIN_NUMBER='(0,0,0,0,0,0,0,0,0,0,0,0,0,0,0,0,0,0,0,0,0,0,0,0,0,0,0,0,0,0,0,EF38,0,0,0,0,0,0,0,0,0,0)';
      PINUSE='POWER';
      NO_LOAD_CHECK='Both';
      NO_IO_CHECK='Both';
      NO_ASSERT_CHECK='TRUE';
      NO_DIR_CHECK='TRUE';
      ALLOW_CONNECT='TRUE';
    'VSS1370':
      PIN_NUMBER='(0,0,0,0,0,0,0,0,0,0,0,0,0,0,0,0,0,0,0,0,0,0,0,0,0,0,0,0,0,0,0,EF36,0,0,0,0,0,0,0,0,0,0)';
      PINUSE='POWER';
      NO_LOAD_CHECK='Both';
      NO_IO_CHECK='Both';
      NO_ASSERT_CHECK='TRUE';
      NO_DIR_CHECK='TRUE';
      ALLOW_CONNECT='TRUE';
    'VSS1367':
      PIN_NUMBER='(0,0,0,0,0,0,0,0,0,0,0,0,0,0,0,0,0,0,0,0,0,0,0,0,0,0,0,0,0,0,0,EF34,0,0,0,0,0,0,0,0,0,0)';
      PINUSE='POWER';
      NO_LOAD_CHECK='Both';
      NO_IO_CHECK='Both';
      NO_ASSERT_CHECK='TRUE';
      NO_DIR_CHECK='TRUE';
      ALLOW_CONNECT='TRUE';
    'VSS1365':
      PIN_NUMBER='(0,0,0,0,0,0,0,0,0,0,0,0,0,0,0,0,0,0,0,0,0,0,0,0,0,0,0,0,0,0,0,EF32,0,0,0,0,0,0,0,0,0,0)';
      PINUSE='POWER';
      NO_LOAD_CHECK='Both';
      NO_IO_CHECK='Both';
      NO_ASSERT_CHECK='TRUE';
      NO_DIR_CHECK='TRUE';
      ALLOW_CONNECT='TRUE';
    'VSS1364':
      PIN_NUMBER='(0,0,0,0,0,0,0,0,0,0,0,0,0,0,0,0,0,0,0,0,0,0,0,0,0,0,0,0,0,0,0,EF30,0,0,0,0,0,0,0,0,0,0)';
      PINUSE='POWER';
      NO_LOAD_CHECK='Both';
      NO_IO_CHECK='Both';
      NO_ASSERT_CHECK='TRUE';
      NO_DIR_CHECK='TRUE';
      ALLOW_CONNECT='TRUE';
    'VSS1363':
      PIN_NUMBER='(0,0,0,0,0,0,0,0,0,0,0,0,0,0,0,0,0,0,0,0,0,0,0,0,0,0,0,0,0,0,0,EF28,0,0,0,0,0,0,0,0,0,0)';
      PINUSE='POWER';
      NO_LOAD_CHECK='Both';
      NO_IO_CHECK='Both';
      NO_ASSERT_CHECK='TRUE';
      NO_DIR_CHECK='TRUE';
      ALLOW_CONNECT='TRUE';
    'VSS1362':
      PIN_NUMBER='(0,0,0,0,0,0,0,0,0,0,0,0,0,0,0,0,0,0,0,0,0,0,0,0,0,0,0,0,0,0,0,EF26,0,0,0,0,0,0,0,0,0,0)';
      PINUSE='POWER';
      NO_LOAD_CHECK='Both';
      NO_IO_CHECK='Both';
      NO_ASSERT_CHECK='TRUE';
      NO_DIR_CHECK='TRUE';
      ALLOW_CONNECT='TRUE';
    'VSS1361':
      PIN_NUMBER='(0,0,0,0,0,0,0,0,0,0,0,0,0,0,0,0,0,0,0,0,0,0,0,0,0,0,0,0,0,0,0,EF24,0,0,0,0,0,0,0,0,0,0)';
      PINUSE='POWER';
      NO_LOAD_CHECK='Both';
      NO_IO_CHECK='Both';
      NO_ASSERT_CHECK='TRUE';
      NO_DIR_CHECK='TRUE';
      ALLOW_CONNECT='TRUE';
    'VSS1360':
      PIN_NUMBER='(0,0,0,0,0,0,0,0,0,0,0,0,0,0,0,0,0,0,0,0,0,0,0,0,0,0,0,0,0,0,0,EF22,0,0,0,0,0,0,0,0,0,0)';
      PINUSE='POWER';
      NO_LOAD_CHECK='Both';
      NO_IO_CHECK='Both';
      NO_ASSERT_CHECK='TRUE';
      NO_DIR_CHECK='TRUE';
      ALLOW_CONNECT='TRUE';
    'VSS1358':
      PIN_NUMBER='(0,0,0,0,0,0,0,0,0,0,0,0,0,0,0,0,0,0,0,0,0,0,0,0,0,0,0,0,0,0,0,EF20,0,0,0,0,0,0,0,0,0,0)';
      PINUSE='POWER';
      NO_LOAD_CHECK='Both';
      NO_IO_CHECK='Both';
      NO_ASSERT_CHECK='TRUE';
      NO_DIR_CHECK='TRUE';
      ALLOW_CONNECT='TRUE';
    'VSS1356':
      PIN_NUMBER='(0,0,0,0,0,0,0,0,0,0,0,0,0,0,0,0,0,0,0,0,0,0,0,0,0,0,0,0,0,0,0,EF2,0,0,0,0,0,0,0,0,0,0)';
      PINUSE='POWER';
      NO_LOAD_CHECK='Both';
      NO_IO_CHECK='Both';
      NO_ASSERT_CHECK='TRUE';
      NO_DIR_CHECK='TRUE';
      ALLOW_CONNECT='TRUE';
    'VSS1354':
      PIN_NUMBER='(0,0,0,0,0,0,0,0,0,0,0,0,0,0,0,0,0,0,0,0,0,0,0,0,0,0,0,0,0,0,0,EF18,0,0,0,0,0,0,0,0,0,0)';
      PINUSE='POWER';
      NO_LOAD_CHECK='Both';
      NO_IO_CHECK='Both';
      NO_ASSERT_CHECK='TRUE';
      NO_DIR_CHECK='TRUE';
      ALLOW_CONNECT='TRUE';
    'VSS1353':
      PIN_NUMBER='(0,0,0,0,0,0,0,0,0,0,0,0,0,0,0,0,0,0,0,0,0,0,0,0,0,0,0,0,0,0,0,EF16,0,0,0,0,0,0,0,0,0,0)';
      PINUSE='POWER';
      NO_LOAD_CHECK='Both';
      NO_IO_CHECK='Both';
      NO_ASSERT_CHECK='TRUE';
      NO_DIR_CHECK='TRUE';
      ALLOW_CONNECT='TRUE';
    'VSS1352':
      PIN_NUMBER='(0,0,0,0,0,0,0,0,0,0,0,0,0,0,0,0,0,0,0,0,0,0,0,0,0,0,0,0,0,0,0,EF12,0,0,0,0,0,0,0,0,0,0)';
      PINUSE='POWER';
      NO_LOAD_CHECK='Both';
      NO_IO_CHECK='Both';
      NO_ASSERT_CHECK='TRUE';
      NO_DIR_CHECK='TRUE';
      ALLOW_CONNECT='TRUE';
    'VSS1351':
      PIN_NUMBER='(0,0,0,0,0,0,0,0,0,0,0,0,0,0,0,0,0,0,0,0,0,0,0,0,0,0,0,0,0,0,0,EE88,0,0,0,0,0,0,0,0,0,0)';
      PINUSE='POWER';
      NO_LOAD_CHECK='Both';
      NO_IO_CHECK='Both';
      NO_ASSERT_CHECK='TRUE';
      NO_DIR_CHECK='TRUE';
      ALLOW_CONNECT='TRUE';
    'VSS1350':
      PIN_NUMBER='(0,0,0,0,0,0,0,0,0,0,0,0,0,0,0,0,0,0,0,0,0,0,0,0,0,0,0,0,0,0,0,EE80,0,0,0,0,0,0,0,0,0,0)';
      PINUSE='POWER';
      NO_LOAD_CHECK='Both';
      NO_IO_CHECK='Both';
      NO_ASSERT_CHECK='TRUE';
      NO_DIR_CHECK='TRUE';
      ALLOW_CONNECT='TRUE';
    'VSS1349':
      PIN_NUMBER='(0,0,0,0,0,0,0,0,0,0,0,0,0,0,0,0,0,0,0,0,0,0,0,0,0,0,0,0,0,0,0,EE78,0,0,0,0,0,0,0,0,0,0)';
      PINUSE='POWER';
      NO_LOAD_CHECK='Both';
      NO_IO_CHECK='Both';
      NO_ASSERT_CHECK='TRUE';
      NO_DIR_CHECK='TRUE';
      ALLOW_CONNECT='TRUE';
    'VSS1348':
      PIN_NUMBER='(0,0,0,0,0,0,0,0,0,0,0,0,0,0,0,0,0,0,0,0,0,0,0,0,0,0,0,0,0,0,0,ED8,0,0,0,0,0,0,0,0,0,0)';
      PINUSE='POWER';
      NO_LOAD_CHECK='Both';
      NO_IO_CHECK='Both';
      NO_ASSERT_CHECK='TRUE';
      NO_DIR_CHECK='TRUE';
      ALLOW_CONNECT='TRUE';
    'VSS1346':
      PIN_NUMBER='(0,0,0,0,0,0,0,0,0,0,0,0,0,0,0,0,0,0,0,0,0,0,0,0,0,0,0,0,0,0,0,ED49,0,0,0,0,0,0,0,0,0,0)';
      PINUSE='POWER';
      NO_LOAD_CHECK='Both';
      NO_IO_CHECK='Both';
      NO_ASSERT_CHECK='TRUE';
      NO_DIR_CHECK='TRUE';
      ALLOW_CONNECT='TRUE';
    'VSS1344':
      PIN_NUMBER='(0,0,0,0,0,0,0,0,0,0,0,0,0,0,0,0,0,0,0,0,0,0,0,0,0,0,0,0,0,0,0,ED4,0,0,0,0,0,0,0,0,0,0)';
      PINUSE='POWER';
      NO_LOAD_CHECK='Both';
      NO_IO_CHECK='Both';
      NO_ASSERT_CHECK='TRUE';
      NO_DIR_CHECK='TRUE';
      ALLOW_CONNECT='TRUE';
    'VSS1342':
      PIN_NUMBER='(0,0,0,0,0,0,0,0,0,0,0,0,0,0,0,0,0,0,0,0,0,0,0,0,0,0,0,0,0,0,0,ED36,0,0,0,0,0,0,0,0,0,0)';
      PINUSE='POWER';
      NO_LOAD_CHECK='Both';
      NO_IO_CHECK='Both';
      NO_ASSERT_CHECK='TRUE';
      NO_DIR_CHECK='TRUE';
      ALLOW_CONNECT='TRUE';
    'VSS1341':
      PIN_NUMBER='(0,0,0,0,0,0,0,0,0,0,0,0,0,0,0,0,0,0,0,0,0,0,0,0,0,0,0,0,0,0,0,ED30,0,0,0,0,0,0,0,0,0,0)';
      PINUSE='POWER';
      NO_LOAD_CHECK='Both';
      NO_IO_CHECK='Both';
      NO_ASSERT_CHECK='TRUE';
      NO_DIR_CHECK='TRUE';
      ALLOW_CONNECT='TRUE';
    'VSS1339':
      PIN_NUMBER='(0,0,0,0,0,0,0,0,0,0,0,0,0,0,0,0,0,0,0,0,0,0,0,0,0,0,0,0,0,0,0,ED24,0,0,0,0,0,0,0,0,0,0)';
      PINUSE='POWER';
      NO_LOAD_CHECK='Both';
      NO_IO_CHECK='Both';
      NO_ASSERT_CHECK='TRUE';
      NO_DIR_CHECK='TRUE';
      ALLOW_CONNECT='TRUE';
    'VSS1338':
      PIN_NUMBER='(0,0,0,0,0,0,0,0,0,0,0,0,0,0,0,0,0,0,0,0,0,0,0,0,0,0,0,0,0,0,0,ED16,0,0,0,0,0,0,0,0,0,0)';
      PINUSE='POWER';
      NO_LOAD_CHECK='Both';
      NO_IO_CHECK='Both';
      NO_ASSERT_CHECK='TRUE';
      NO_DIR_CHECK='TRUE';
      ALLOW_CONNECT='TRUE';
    'VSS1337':
      PIN_NUMBER='(0,0,0,0,0,0,0,0,0,0,0,0,0,0,0,0,0,0,0,0,0,0,0,0,0,0,0,0,0,0,0,EC9,0,0,0,0,0,0,0,0,0,0)';
      PINUSE='POWER';
      NO_LOAD_CHECK='Both';
      NO_IO_CHECK='Both';
      NO_ASSERT_CHECK='TRUE';
      NO_DIR_CHECK='TRUE';
      ALLOW_CONNECT='TRUE';
    'VSS1336':
      PIN_NUMBER='(0,0,0,0,0,0,0,0,0,0,0,0,0,0,0,0,0,0,0,0,0,0,0,0,0,0,0,0,0,0,0,EC88,0,0,0,0,0,0,0,0,0,0)';
      PINUSE='POWER';
      NO_LOAD_CHECK='Both';
      NO_IO_CHECK='Both';
      NO_ASSERT_CHECK='TRUE';
      NO_DIR_CHECK='TRUE';
      ALLOW_CONNECT='TRUE';
    'VSS1335':
      PIN_NUMBER='(0,0,0,0,0,0,0,0,0,0,0,0,0,0,0,0,0,0,0,0,0,0,0,0,0,0,0,0,0,0,0,EC84,0,0,0,0,0,0,0,0,0,0)';
      PINUSE='POWER';
      NO_LOAD_CHECK='Both';
      NO_IO_CHECK='Both';
      NO_ASSERT_CHECK='TRUE';
      NO_DIR_CHECK='TRUE';
      ALLOW_CONNECT='TRUE';
    'VSS1333':
      PIN_NUMBER='(0,0,0,0,0,0,0,0,0,0,0,0,0,0,0,0,0,0,0,0,0,0,0,0,0,0,0,0,0,0,0,EC82,0,0,0,0,0,0,0,0,0,0)';
      PINUSE='POWER';
      NO_LOAD_CHECK='Both';
      NO_IO_CHECK='Both';
      NO_ASSERT_CHECK='TRUE';
      NO_DIR_CHECK='TRUE';
      ALLOW_CONNECT='TRUE';
    'VSS1332':
      PIN_NUMBER='(0,0,0,0,0,0,0,0,0,0,0,0,0,0,0,0,0,0,0,0,0,0,0,0,0,0,0,0,0,0,0,EC74,0,0,0,0,0,0,0,0,0,0)';
      PINUSE='POWER';
      NO_LOAD_CHECK='Both';
      NO_IO_CHECK='Both';
      NO_ASSERT_CHECK='TRUE';
      NO_DIR_CHECK='TRUE';
      ALLOW_CONNECT='TRUE';
    'VSS1330':
      PIN_NUMBER='(0,0,0,0,0,0,0,0,0,0,0,0,0,0,0,0,0,0,0,0,0,0,0,0,0,0,0,0,0,0,0,EC72,0,0,0,0,0,0,0,0,0,0)';
      PINUSE='POWER';
      NO_LOAD_CHECK='Both';
      NO_IO_CHECK='Both';
      NO_ASSERT_CHECK='TRUE';
      NO_DIR_CHECK='TRUE';
      ALLOW_CONNECT='TRUE';
    'VSS1329':
      PIN_NUMBER='(0,0,0,0,0,0,0,0,0,0,0,0,0,0,0,0,0,0,0,0,0,0,0,0,0,0,0,0,0,0,0,EC66,0,0,0,0,0,0,0,0,0,0)';
      PINUSE='POWER';
      NO_LOAD_CHECK='Both';
      NO_IO_CHECK='Both';
      NO_ASSERT_CHECK='TRUE';
      NO_DIR_CHECK='TRUE';
      ALLOW_CONNECT='TRUE';
    'VSS1327':
      PIN_NUMBER='(0,0,0,0,0,0,0,0,0,0,0,0,0,0,0,0,0,0,0,0,0,0,0,0,0,0,0,0,0,0,0,EC56,0,0,0,0,0,0,0,0,0,0)';
      PINUSE='POWER';
      NO_LOAD_CHECK='Both';
      NO_IO_CHECK='Both';
      NO_ASSERT_CHECK='TRUE';
      NO_DIR_CHECK='TRUE';
      ALLOW_CONNECT='TRUE';
    'VSS1326':
      PIN_NUMBER='(0,0,0,0,0,0,0,0,0,0,0,0,0,0,0,0,0,0,0,0,0,0,0,0,0,0,0,0,0,0,0,EC50,0,0,0,0,0,0,0,0,0,0)';
      PINUSE='POWER';
      NO_LOAD_CHECK='Both';
      NO_IO_CHECK='Both';
      NO_ASSERT_CHECK='TRUE';
      NO_DIR_CHECK='TRUE';
      ALLOW_CONNECT='TRUE';
    'VSS1324':
      PIN_NUMBER='(0,0,0,0,0,0,0,0,0,0,0,0,0,0,0,0,0,0,0,0,0,0,0,0,0,0,0,0,0,0,0,EC48,0,0,0,0,0,0,0,0,0,0)';
      PINUSE='POWER';
      NO_LOAD_CHECK='Both';
      NO_IO_CHECK='Both';
      NO_ASSERT_CHECK='TRUE';
      NO_DIR_CHECK='TRUE';
      ALLOW_CONNECT='TRUE';
    'VSS1323':
      PIN_NUMBER='(0,0,0,0,0,0,0,0,0,0,0,0,0,0,0,0,0,0,0,0,0,0,0,0,0,0,0,0,0,0,0,EC43,0,0,0,0,0,0,0,0,0,0)';
      PINUSE='POWER';
      NO_LOAD_CHECK='Both';
      NO_IO_CHECK='Both';
      NO_ASSERT_CHECK='TRUE';
      NO_DIR_CHECK='TRUE';
      ALLOW_CONNECT='TRUE';
    'VSS1321':
      PIN_NUMBER='(0,0,0,0,0,0,0,0,0,0,0,0,0,0,0,0,0,0,0,0,0,0,0,0,0,0,0,0,0,0,0,EC41,0,0,0,0,0,0,0,0,0,0)';
      PINUSE='POWER';
      NO_LOAD_CHECK='Both';
      NO_IO_CHECK='Both';
      NO_ASSERT_CHECK='TRUE';
      NO_DIR_CHECK='TRUE';
      ALLOW_CONNECT='TRUE';
    'VSS1318':
      PIN_NUMBER='(0,0,0,0,0,0,0,0,0,0,0,0,0,0,0,0,0,0,0,0,0,0,0,0,0,0,0,0,0,0,0,EH6,0,0,0,0,0,0,0,0,0,0)';
      PINUSE='POWER';
      NO_LOAD_CHECK='Both';
      NO_IO_CHECK='Both';
      NO_ASSERT_CHECK='TRUE';
      NO_DIR_CHECK='TRUE';
      ALLOW_CONNECT='TRUE';
    'VSS1317':
      PIN_NUMBER='(0,0,0,0,0,0,0,0,0,0,0,0,0,0,0,0,0,0,0,0,0,0,0,0,0,0,0,0,0,0,0,EC37,0,0,0,0,0,0,0,0,0,0)';
      PINUSE='POWER';
      NO_LOAD_CHECK='Both';
      NO_IO_CHECK='Both';
      NO_ASSERT_CHECK='TRUE';
      NO_DIR_CHECK='TRUE';
      ALLOW_CONNECT='TRUE';
    'VSS1316':
      PIN_NUMBER='(0,0,0,0,0,0,0,0,0,0,0,0,0,0,0,0,0,0,0,0,0,0,0,0,0,0,0,0,0,0,0,EC31,0,0,0,0,0,0,0,0,0,0)';
      PINUSE='POWER';
      NO_LOAD_CHECK='Both';
      NO_IO_CHECK='Both';
      NO_ASSERT_CHECK='TRUE';
      NO_DIR_CHECK='TRUE';
      ALLOW_CONNECT='TRUE';
    'VSS1314':
      PIN_NUMBER='(0,0,0,0,0,0,0,0,0,0,0,0,0,0,0,0,0,0,0,0,0,0,0,0,0,0,0,0,0,0,0,EC29,0,0,0,0,0,0,0,0,0,0)';
      PINUSE='POWER';
      NO_LOAD_CHECK='Both';
      NO_IO_CHECK='Both';
      NO_ASSERT_CHECK='TRUE';
      NO_DIR_CHECK='TRUE';
      ALLOW_CONNECT='TRUE';
    'VSS1313':
      PIN_NUMBER='(0,0,0,0,0,0,0,0,0,0,0,0,0,0,0,0,0,0,0,0,0,0,0,0,0,0,0,0,0,0,0,EC23,0,0,0,0,0,0,0,0,0,0)';
      PINUSE='POWER';
      NO_LOAD_CHECK='Both';
      NO_IO_CHECK='Both';
      NO_ASSERT_CHECK='TRUE';
      NO_DIR_CHECK='TRUE';
      ALLOW_CONNECT='TRUE';
    'VSS1311':
      PIN_NUMBER='(0,0,0,0,0,0,0,0,0,0,0,0,0,0,0,0,0,0,0,0,0,0,0,0,0,0,0,0,0,0,0,EC19,0,0,0,0,0,0,0,0,0,0)';
      PINUSE='POWER';
      NO_LOAD_CHECK='Both';
      NO_IO_CHECK='Both';
      NO_ASSERT_CHECK='TRUE';
      NO_DIR_CHECK='TRUE';
      ALLOW_CONNECT='TRUE';
    'VSS1310':
      PIN_NUMBER='(0,0,0,0,0,0,0,0,0,0,0,0,0,0,0,0,0,0,0,0,0,0,0,0,0,0,0,0,0,0,0,EC13,0,0,0,0,0,0,0,0,0,0)';
      PINUSE='POWER';
      NO_LOAD_CHECK='Both';
      NO_IO_CHECK='Both';
      NO_ASSERT_CHECK='TRUE';
      NO_DIR_CHECK='TRUE';
      ALLOW_CONNECT='TRUE';
    'VSS1309':
      PIN_NUMBER='(0,0,0,0,0,0,0,0,0,0,0,0,0,0,0,0,0,0,0,0,0,0,0,0,0,0,0,0,0,0,0,EC1,0,0,0,0,0,0,0,0,0,0)';
      PINUSE='POWER';
      NO_LOAD_CHECK='Both';
      NO_IO_CHECK='Both';
      NO_ASSERT_CHECK='TRUE';
      NO_DIR_CHECK='TRUE';
      ALLOW_CONNECT='TRUE';
    'VSS1308':
      PIN_NUMBER='(0,0,0,0,0,0,0,0,0,0,0,0,0,0,0,0,0,0,0,0,0,0,0,0,0,0,0,0,0,0,0,EB87,0,0,0,0,0,0,0,0,0,0)';
      PINUSE='POWER';
      NO_LOAD_CHECK='Both';
      NO_IO_CHECK='Both';
      NO_ASSERT_CHECK='TRUE';
      NO_DIR_CHECK='TRUE';
      ALLOW_CONNECT='TRUE';
    'VSS1307':
      PIN_NUMBER='(0,0,0,0,0,0,0,0,0,0,0,0,0,0,0,0,0,0,0,0,0,0,0,0,0,0,0,0,0,0,0,EB83,0,0,0,0,0,0,0,0,0,0)';
      PINUSE='POWER';
      NO_LOAD_CHECK='Both';
      NO_IO_CHECK='Both';
      NO_ASSERT_CHECK='TRUE';
      NO_DIR_CHECK='TRUE';
      ALLOW_CONNECT='TRUE';
    'VSS1306':
      PIN_NUMBER='(0,0,0,0,0,0,0,0,0,0,0,0,0,0,0,0,0,0,0,0,0,0,0,0,0,0,0,0,0,0,0,EB8,0,0,0,0,0,0,0,0,0,0)';
      PINUSE='POWER';
      NO_LOAD_CHECK='Both';
      NO_IO_CHECK='Both';
      NO_ASSERT_CHECK='TRUE';
      NO_DIR_CHECK='TRUE';
      ALLOW_CONNECT='TRUE';
    'VSS1305':
      PIN_NUMBER='(0,0,0,0,0,0,0,0,0,0,0,0,0,0,0,0,0,0,0,0,0,0,0,0,0,0,0,0,0,0,0,EH18,0,0,0,0,0,0,0,0,0,0)';
      PINUSE='POWER';
      NO_LOAD_CHECK='Both';
      NO_IO_CHECK='Both';
      NO_ASSERT_CHECK='TRUE';
      NO_DIR_CHECK='TRUE';
      ALLOW_CONNECT='TRUE';
    'VSS1304':
      PIN_NUMBER='(0,0,0,0,0,0,0,0,0,0,0,0,0,0,0,0,0,0,0,0,0,0,0,0,0,0,0,0,0,0,0,EB79,0,0,0,0,0,0,0,0,0,0)';
      PINUSE='POWER';
      NO_LOAD_CHECK='Both';
      NO_IO_CHECK='Both';
      NO_ASSERT_CHECK='TRUE';
      NO_DIR_CHECK='TRUE';
      ALLOW_CONNECT='TRUE';
    'VSS1303':
      PIN_NUMBER='(0,0,0,0,0,0,0,0,0,0,0,0,0,0,0,0,0,0,0,0,0,0,0,0,0,0,0,0,0,0,0,EH14,0,0,0,0,0,0,0,0,0,0)';
      PINUSE='POWER';
      NO_LOAD_CHECK='Both';
      NO_IO_CHECK='Both';
      NO_ASSERT_CHECK='TRUE';
      NO_DIR_CHECK='TRUE';
      ALLOW_CONNECT='TRUE';
    'VSS1302':
      PIN_NUMBER='(0,0,0,0,0,0,0,0,0,0,0,0,0,0,0,0,0,0,0,0,0,0,0,0,0,0,0,0,0,0,0,EH12,0,0,0,0,0,0,0,0,0,0)';
      PINUSE='POWER';
      NO_LOAD_CHECK='Both';
      NO_IO_CHECK='Both';
      NO_ASSERT_CHECK='TRUE';
      NO_DIR_CHECK='TRUE';
      ALLOW_CONNECT='TRUE';
    'VSS1301':
      PIN_NUMBER='(0,0,0,0,0,0,0,0,0,0,0,0,0,0,0,0,0,0,0,0,0,0,0,0,0,0,0,0,0,0,0,EB75,0,0,0,0,0,0,0,0,0,0)';
      PINUSE='POWER';
      NO_LOAD_CHECK='Both';
      NO_IO_CHECK='Both';
      NO_ASSERT_CHECK='TRUE';
      NO_DIR_CHECK='TRUE';
      ALLOW_CONNECT='TRUE';
    'VSS1300':
      PIN_NUMBER='(0,0,0,0,0,0,0,0,0,0,0,0,0,0,0,0,0,0,0,0,0,0,0,0,0,0,0,0,0,0,0,EB71,0,0,0,0,0,0,0,0,0,0)';
      PINUSE='POWER';
      NO_LOAD_CHECK='Both';
      NO_IO_CHECK='Both';
      NO_ASSERT_CHECK='TRUE';
      NO_DIR_CHECK='TRUE';
      ALLOW_CONNECT='TRUE';
    'VSS1299':
      PIN_NUMBER='(0,0,0,0,0,0,0,0,0,0,0,0,0,0,0,0,0,0,0,0,0,0,0,0,0,0,0,0,0,0,0,EB69,0,0,0,0,0,0,0,0,0,0)';
      PINUSE='POWER';
      NO_LOAD_CHECK='Both';
      NO_IO_CHECK='Both';
      NO_ASSERT_CHECK='TRUE';
      NO_DIR_CHECK='TRUE';
      ALLOW_CONNECT='TRUE';
    'VSS1298':
      PIN_NUMBER='(0,0,0,0,0,0,0,0,0,0,0,0,0,0,0,0,0,0,0,0,0,0,0,0,0,0,0,0,0,0,0,EB65,0,0,0,0,0,0,0,0,0,0)';
      PINUSE='POWER';
      NO_LOAD_CHECK='Both';
      NO_IO_CHECK='Both';
      NO_ASSERT_CHECK='TRUE';
      NO_DIR_CHECK='TRUE';
      ALLOW_CONNECT='TRUE';
    'VSS1297':
      PIN_NUMBER='(0,0,0,0,0,0,0,0,0,0,0,0,0,0,0,0,0,0,0,0,0,0,0,0,0,0,0,0,0,0,0,EB57,0,0,0,0,0,0,0,0,0,0)';
      PINUSE='POWER';
      NO_LOAD_CHECK='Both';
      NO_IO_CHECK='Both';
      NO_ASSERT_CHECK='TRUE';
      NO_DIR_CHECK='TRUE';
      ALLOW_CONNECT='TRUE';
    'VSS1296':
      PIN_NUMBER='(0,0,0,0,0,0,0,0,0,0,0,0,0,0,0,0,0,0,0,0,0,0,0,0,0,0,0,0,0,0,0,EB47,0,0,0,0,0,0,0,0,0,0)';
      PINUSE='POWER';
      NO_LOAD_CHECK='Both';
      NO_IO_CHECK='Both';
      NO_ASSERT_CHECK='TRUE';
      NO_DIR_CHECK='TRUE';
      ALLOW_CONNECT='TRUE';
    'VSS1295':
      PIN_NUMBER='(0,0,0,0,0,0,0,0,0,0,0,0,0,0,0,0,0,0,0,0,0,0,0,0,0,0,0,0,0,0,0,EB40,0,0,0,0,0,0,0,0,0,0)';
      PINUSE='POWER';
      NO_LOAD_CHECK='Both';
      NO_IO_CHECK='Both';
      NO_ASSERT_CHECK='TRUE';
      NO_DIR_CHECK='TRUE';
      ALLOW_CONNECT='TRUE';
    'VSS1294':
      PIN_NUMBER='(0,0,0,0,0,0,0,0,0,0,0,0,0,0,0,0,0,0,0,0,0,0,0,0,0,0,0,0,0,0,0,EG7,0,0,0,0,0,0,0,0,0,0)';
      PINUSE='POWER';
      NO_LOAD_CHECK='Both';
      NO_IO_CHECK='Both';
      NO_ASSERT_CHECK='TRUE';
      NO_DIR_CHECK='TRUE';
      ALLOW_CONNECT='TRUE';
    'VSS1293':
      PIN_NUMBER='(0,0,0,0,0,0,0,0,0,0,0,0,0,0,0,0,0,0,0,0,0,0,0,0,0,0,0,0,0,0,0,EB38,0,0,0,0,0,0,0,0,0,0)';
      PINUSE='POWER';
      NO_LOAD_CHECK='Both';
      NO_IO_CHECK='Both';
      NO_ASSERT_CHECK='TRUE';
      NO_DIR_CHECK='TRUE';
      ALLOW_CONNECT='TRUE';
    'VSS1292':
      PIN_NUMBER='(0,0,0,0,0,0,0,0,0,0,0,0,0,0,0,0,0,0,0,0,0,0,0,0,0,0,0,0,0,0,0,EB32,0,0,0,0,0,0,0,0,0,0)';
      PINUSE='POWER';
      NO_LOAD_CHECK='Both';
      NO_IO_CHECK='Both';
      NO_ASSERT_CHECK='TRUE';
      NO_DIR_CHECK='TRUE';
      ALLOW_CONNECT='TRUE';
    'VSS1291':
      PIN_NUMBER='(0,0,0,0,0,0,0,0,0,0,0,0,0,0,0,0,0,0,0,0,0,0,0,0,0,0,0,0,0,0,0,EG52,0,0,0,0,0,0,0,0,0,0)';
      PINUSE='POWER';
      NO_LOAD_CHECK='Both';
      NO_IO_CHECK='Both';
      NO_ASSERT_CHECK='TRUE';
      NO_DIR_CHECK='TRUE';
      ALLOW_CONNECT='TRUE';
    'VSS1290':
      PIN_NUMBER='(0,0,0,0,0,0,0,0,0,0,0,0,0,0,0,0,0,0,0,0,0,0,0,0,0,0,0,0,0,0,0,EG5,0,0,0,0,0,0,0,0,0,0)';
      PINUSE='POWER';
      NO_LOAD_CHECK='Both';
      NO_IO_CHECK='Both';
      NO_ASSERT_CHECK='TRUE';
      NO_DIR_CHECK='TRUE';
      ALLOW_CONNECT='TRUE';
    'VSS1289':
      PIN_NUMBER='(0,0,0,0,0,0,0,0,0,0,0,0,0,0,0,0,0,0,0,0,0,0,0,0,0,0,0,0,0,0,0,EB28,0,0,0,0,0,0,0,0,0,0)';
      PINUSE='POWER';
      NO_LOAD_CHECK='Both';
      NO_IO_CHECK='Both';
      NO_ASSERT_CHECK='TRUE';
      NO_DIR_CHECK='TRUE';
      ALLOW_CONNECT='TRUE';
    'VSS1288':
      PIN_NUMBER='(0,0,0,0,0,0,0,0,0,0,0,0,0,0,0,0,0,0,0,0,0,0,0,0,0,0,0,0,0,0,0,EB22,0,0,0,0,0,0,0,0,0,0)';
      PINUSE='POWER';
      NO_LOAD_CHECK='Both';
      NO_IO_CHECK='Both';
      NO_ASSERT_CHECK='TRUE';
      NO_DIR_CHECK='TRUE';
      ALLOW_CONNECT='TRUE';
    'VSS1287':
      PIN_NUMBER='(0,0,0,0,0,0,0,0,0,0,0,0,0,0,0,0,0,0,0,0,0,0,0,0,0,0,0,0,0,0,0,EB12,0,0,0,0,0,0,0,0,0,0)';
      PINUSE='POWER';
      NO_LOAD_CHECK='Both';
      NO_IO_CHECK='Both';
      NO_ASSERT_CHECK='TRUE';
      NO_DIR_CHECK='TRUE';
      ALLOW_CONNECT='TRUE';
    'VSS1286':
      PIN_NUMBER='(0,0,0,0,0,0,0,0,0,0,0,0,0,0,0,0,0,0,0,0,0,0,0,0,0,0,0,0,0,0,0,EA88,0,0,0,0,0,0,0,0,0,0)';
      PINUSE='POWER';
      NO_LOAD_CHECK='Both';
      NO_IO_CHECK='Both';
      NO_ASSERT_CHECK='TRUE';
      NO_DIR_CHECK='TRUE';
      ALLOW_CONNECT='TRUE';
    'VSS1285':
      PIN_NUMBER='(0,0,0,0,0,0,0,0,0,0,0,0,0,0,0,0,0,0,0,0,0,0,0,0,0,0,0,0,0,0,0,EA84,0,0,0,0,0,0,0,0,0,0)';
      PINUSE='POWER';
      NO_LOAD_CHECK='Both';
      NO_IO_CHECK='Both';
      NO_ASSERT_CHECK='TRUE';
      NO_DIR_CHECK='TRUE';
      ALLOW_CONNECT='TRUE';
    'VSS1284':
      PIN_NUMBER='(0,0,0,0,0,0,0,0,0,0,0,0,0,0,0,0,0,0,0,0,0,0,0,0,0,0,0,0,0,0,0,EG13,0,0,0,0,0,0,0,0,0,0)';
      PINUSE='POWER';
      NO_LOAD_CHECK='Both';
      NO_IO_CHECK='Both';
      NO_ASSERT_CHECK='TRUE';
      NO_DIR_CHECK='TRUE';
      ALLOW_CONNECT='TRUE';
    'VSS1283':
      PIN_NUMBER='(0,0,0,0,0,0,0,0,0,0,0,0,0,0,0,0,0,0,0,0,0,0,0,0,0,0,0,0,0,0,0,EF89,0,0,0,0,0,0,0,0,0,0)';
      PINUSE='POWER';
      NO_LOAD_CHECK='Both';
      NO_IO_CHECK='Both';
      NO_ASSERT_CHECK='TRUE';
      NO_DIR_CHECK='TRUE';
      ALLOW_CONNECT='TRUE';
    'VSS1282':
      PIN_NUMBER='(0,0,0,0,0,0,0,0,0,0,0,0,0,0,0,0,0,0,0,0,0,0,0,0,0,0,0,0,0,0,0,EA80,0,0,0,0,0,0,0,0,0,0)';
      PINUSE='POWER';
      NO_LOAD_CHECK='Both';
      NO_IO_CHECK='Both';
      NO_ASSERT_CHECK='TRUE';
      NO_DIR_CHECK='TRUE';
      ALLOW_CONNECT='TRUE';
    'VSS1281':
      PIN_NUMBER='(0,0,0,0,0,0,0,0,0,0,0,0,0,0,0,0,0,0,0,0,0,0,0,0,0,0,0,0,0,0,0,EA78,0,0,0,0,0,0,0,0,0,0)';
      PINUSE='POWER';
      NO_LOAD_CHECK='Both';
      NO_IO_CHECK='Both';
      NO_ASSERT_CHECK='TRUE';
      NO_DIR_CHECK='TRUE';
      ALLOW_CONNECT='TRUE';
    'VSS1280':
      PIN_NUMBER='(0,0,0,0,0,0,0,0,0,0,0,0,0,0,0,0,0,0,0,0,0,0,0,0,0,0,0,0,0,0,0,EA76,0,0,0,0,0,0,0,0,0,0)';
      PINUSE='POWER';
      NO_LOAD_CHECK='Both';
      NO_IO_CHECK='Both';
      NO_ASSERT_CHECK='TRUE';
      NO_DIR_CHECK='TRUE';
      ALLOW_CONNECT='TRUE';
    'VSS1279':
      PIN_NUMBER='(0,0,0,0,0,0,0,0,0,0,0,0,0,0,0,0,0,0,0,0,0,0,0,0,0,0,0,0,0,0,0,EA70,0,0,0,0,0,0,0,0,0,0)';
      PINUSE='POWER';
      NO_LOAD_CHECK='Both';
      NO_IO_CHECK='Both';
      NO_ASSERT_CHECK='TRUE';
      NO_DIR_CHECK='TRUE';
      ALLOW_CONNECT='TRUE';
    'VSS1278':
      PIN_NUMBER='(0,0,0,0,0,0,0,0,0,0,0,0,0,0,0,0,0,0,0,0,0,0,0,0,0,0,0,0,0,0,0,EA33,0,0,0,0,0,0,0,0,0,0)';
      PINUSE='POWER';
      NO_LOAD_CHECK='Both';
      NO_IO_CHECK='Both';
      NO_ASSERT_CHECK='TRUE';
      NO_DIR_CHECK='TRUE';
      ALLOW_CONNECT='TRUE';
    'VSS1277':
      PIN_NUMBER='(0,0,0,0,0,0,0,0,0,0,0,0,0,0,0,0,0,0,0,0,0,0,0,0,0,0,0,0,0,0,0,EF75,0,0,0,0,0,0,0,0,0,0)';
      PINUSE='POWER';
      NO_LOAD_CHECK='Both';
      NO_IO_CHECK='Both';
      NO_ASSERT_CHECK='TRUE';
      NO_DIR_CHECK='TRUE';
      ALLOW_CONNECT='TRUE';
    'VSS1276':
      PIN_NUMBER='(0,0,0,0,0,0,0,0,0,0,0,0,0,0,0,0,0,0,0,0,0,0,0,0,0,0,0,0,0,0,0,EF73,0,0,0,0,0,0,0,0,0,0)';
      PINUSE='POWER';
      NO_LOAD_CHECK='Both';
      NO_IO_CHECK='Both';
      NO_ASSERT_CHECK='TRUE';
      NO_DIR_CHECK='TRUE';
      ALLOW_CONNECT='TRUE';
    'VSS1275':
      PIN_NUMBER='(0,0,0,0,0,0,0,0,0,0,0,0,0,0,0,0,0,0,0,0,0,0,0,0,0,0,0,0,0,0,0,EA27,0,0,0,0,0,0,0,0,0,0)';
      PINUSE='POWER';
      NO_LOAD_CHECK='Both';
      NO_IO_CHECK='Both';
      NO_ASSERT_CHECK='TRUE';
      NO_DIR_CHECK='TRUE';
      ALLOW_CONNECT='TRUE';
    'VSS1274':
      PIN_NUMBER='(0,0,0,0,0,0,0,0,0,0,0,0,0,0,0,0,0,0,0,0,0,0,0,0,0,0,0,0,0,0,0,EA21,0,0,0,0,0,0,0,0,0,0)';
      PINUSE='POWER';
      NO_LOAD_CHECK='Both';
      NO_IO_CHECK='Both';
      NO_ASSERT_CHECK='TRUE';
      NO_DIR_CHECK='TRUE';
      ALLOW_CONNECT='TRUE';
    'VSS1270':
      PIN_NUMBER='(0,0,0,0,0,0,0,0,0,0,0,0,0,0,0,0,0,0,0,0,0,0,0,0,0,0,0,0,0,0,0,DY8,0,0,0,0,0,0,0,0,0,0)';
      PINUSE='POWER';
      NO_LOAD_CHECK='Both';
      NO_IO_CHECK='Both';
      NO_ASSERT_CHECK='TRUE';
      NO_DIR_CHECK='TRUE';
      ALLOW_CONNECT='TRUE';
    'VSS1269':
      PIN_NUMBER='(0,0,0,0,0,0,0,0,0,0,0,0,0,0,0,0,0,0,0,0,0,0,0,0,0,0,0,0,0,0,0,DY77,0,0,0,0,0,0,0,0,0,0)';
      PINUSE='POWER';
      NO_LOAD_CHECK='Both';
      NO_IO_CHECK='Both';
      NO_ASSERT_CHECK='TRUE';
      NO_DIR_CHECK='TRUE';
      ALLOW_CONNECT='TRUE';
    'VSS1267':
      PIN_NUMBER='(0,0,0,0,0,0,0,0,0,0,0,0,0,0,0,0,0,0,0,0,0,0,0,0,0,0,0,0,0,0,0,DW88,0,0,0,0,0,0,0,0,0,0)';
      PINUSE='POWER';
      NO_LOAD_CHECK='Both';
      NO_IO_CHECK='Both';
      NO_ASSERT_CHECK='TRUE';
      NO_DIR_CHECK='TRUE';
      ALLOW_CONNECT='TRUE';
    'VSS1266':
      PIN_NUMBER='(0,0,0,0,0,0,0,0,0,0,0,0,0,0,0,0,0,0,0,0,0,0,0,0,0,0,0,0,0,0,0,DW84,0,0,0,0,0,0,0,0,0,0)';
      PINUSE='POWER';
      NO_LOAD_CHECK='Both';
      NO_IO_CHECK='Both';
      NO_ASSERT_CHECK='TRUE';
      NO_DIR_CHECK='TRUE';
      ALLOW_CONNECT='TRUE';
    'VSS1265':
      PIN_NUMBER='(0,0,0,0,0,0,0,0,0,0,0,0,0,0,0,0,0,0,0,0,0,0,0,0,0,0,0,0,0,0,0,EF51,0,0,0,0,0,0,0,0,0,0)';
      PINUSE='POWER';
      NO_LOAD_CHECK='Both';
      NO_IO_CHECK='Both';
      NO_ASSERT_CHECK='TRUE';
      NO_DIR_CHECK='TRUE';
      ALLOW_CONNECT='TRUE';
    'VSS1264':
      PIN_NUMBER='(0,0,0,0,0,0,0,0,0,0,0,0,0,0,0,0,0,0,0,0,0,0,0,0,0,0,0,0,0,0,0,DW82,0,0,0,0,0,0,0,0,0,0)';
      PINUSE='POWER';
      NO_LOAD_CHECK='Both';
      NO_IO_CHECK='Both';
      NO_ASSERT_CHECK='TRUE';
      NO_DIR_CHECK='TRUE';
      ALLOW_CONNECT='TRUE';
    'VSS1263':
      PIN_NUMBER='(0,0,0,0,0,0,0,0,0,0,0,0,0,0,0,0,0,0,0,0,0,0,0,0,0,0,0,0,0,0,0,DW80,0,0,0,0,0,0,0,0,0,0)';
      PINUSE='POWER';
      NO_LOAD_CHECK='Both';
      NO_IO_CHECK='Both';
      NO_ASSERT_CHECK='TRUE';
      NO_DIR_CHECK='TRUE';
      ALLOW_CONNECT='TRUE';
    'VSS1262':
      PIN_NUMBER='(0,0,0,0,0,0,0,0,0,0,0,0,0,0,0,0,0,0,0,0,0,0,0,0,0,0,0,0,0,0,0,DW76,0,0,0,0,0,0,0,0,0,0)';
      PINUSE='POWER';
      NO_LOAD_CHECK='Both';
      NO_IO_CHECK='Both';
      NO_ASSERT_CHECK='TRUE';
      NO_DIR_CHECK='TRUE';
      ALLOW_CONNECT='TRUE';
    'VSS1261':
      PIN_NUMBER='(0,0,0,0,0,0,0,0,0,0,0,0,0,0,0,0,0,0,0,0,0,0,0,0,0,0,0,0,0,0,0,DW74,0,0,0,0,0,0,0,0,0,0)';
      PINUSE='POWER';
      NO_LOAD_CHECK='Both';
      NO_IO_CHECK='Both';
      NO_ASSERT_CHECK='TRUE';
      NO_DIR_CHECK='TRUE';
      ALLOW_CONNECT='TRUE';
    'VSS1260':
      PIN_NUMBER='(0,0,0,0,0,0,0,0,0,0,0,0,0,0,0,0,0,0,0,0,0,0,0,0,0,0,0,0,0,0,0,DW72,0,0,0,0,0,0,0,0,0,0)';
      PINUSE='POWER';
      NO_LOAD_CHECK='Both';
      NO_IO_CHECK='Both';
      NO_ASSERT_CHECK='TRUE';
      NO_DIR_CHECK='TRUE';
      ALLOW_CONNECT='TRUE';
    'VSS1259':
      PIN_NUMBER='(0,0,0,0,0,0,0,0,0,0,0,0,0,0,0,0,0,0,0,0,0,0,0,0,0,0,0,0,0,0,0,DW70,0,0,0,0,0,0,0,0,0,0)';
      PINUSE='POWER';
      NO_LOAD_CHECK='Both';
      NO_IO_CHECK='Both';
      NO_ASSERT_CHECK='TRUE';
      NO_DIR_CHECK='TRUE';
      ALLOW_CONNECT='TRUE';
    'VSS1258':
      PIN_NUMBER='(0,0,0,0,0,0,0,0,0,0,0,0,0,0,0,0,0,0,0,0,0,0,0,0,0,0,0,0,0,0,0,DW68,0,0,0,0,0,0,0,0,0,0)';
      PINUSE='POWER';
      NO_LOAD_CHECK='Both';
      NO_IO_CHECK='Both';
      NO_ASSERT_CHECK='TRUE';
      NO_DIR_CHECK='TRUE';
      ALLOW_CONNECT='TRUE';
    'VSS1257':
      PIN_NUMBER='(0,0,0,0,0,0,0,0,0,0,0,0,0,0,0,0,0,0,0,0,0,0,0,0,0,0,0,0,0,0,0,DW66,0,0,0,0,0,0,0,0,0,0)';
      PINUSE='POWER';
      NO_LOAD_CHECK='Both';
      NO_IO_CHECK='Both';
      NO_ASSERT_CHECK='TRUE';
      NO_DIR_CHECK='TRUE';
      ALLOW_CONNECT='TRUE';
    'VSS1237':
      PIN_NUMBER='(0,0,0,0,0,0,0,0,0,0,0,0,0,0,0,0,0,0,0,0,0,0,0,0,0,0,0,0,0,0,0,EE52,0,0,0,0,0,0,0,0,0,0)';
      PINUSE='POWER';
      NO_LOAD_CHECK='Both';
      NO_IO_CHECK='Both';
      NO_ASSERT_CHECK='TRUE';
      NO_DIR_CHECK='TRUE';
      ALLOW_CONNECT='TRUE';
    'VSS1235':
      PIN_NUMBER='(0,0,0,0,0,0,0,0,0,0,0,0,0,0,0,0,0,0,0,0,0,0,0,0,0,0,0,0,0,0,0,EE39,0,0,0,0,0,0,0,0,0,0)';
      PINUSE='POWER';
      NO_LOAD_CHECK='Both';
      NO_IO_CHECK='Both';
      NO_ASSERT_CHECK='TRUE';
      NO_DIR_CHECK='TRUE';
      ALLOW_CONNECT='TRUE';
    'VSS1232':
      PIN_NUMBER='(0,0,0,0,0,0,0,0,0,0,0,0,0,0,0,0,0,0,0,0,0,0,0,0,0,0,0,0,0,0,0,EE17,0,0,0,0,0,0,0,0,0,0)';
      PINUSE='POWER';
      NO_LOAD_CHECK='Both';
      NO_IO_CHECK='Both';
      NO_ASSERT_CHECK='TRUE';
      NO_DIR_CHECK='TRUE';
      ALLOW_CONNECT='TRUE';
    'VSS1225':
      PIN_NUMBER='(0,0,0,0,0,0,0,0,0,0,0,0,0,0,0,0,0,0,0,0,0,0,0,0,0,0,0,0,0,0,0,ED73,0,0,0,0,0,0,0,0,0,0)';
      PINUSE='POWER';
      NO_LOAD_CHECK='Both';
      NO_IO_CHECK='Both';
      NO_ASSERT_CHECK='TRUE';
      NO_DIR_CHECK='TRUE';
      ALLOW_CONNECT='TRUE';
    'VSS1224':
      PIN_NUMBER='(0,0,0,0,0,0,0,0,0,0,0,0,0,0,0,0,0,0,0,0,0,0,0,0,0,0,0,0,0,0,0,ED67,0,0,0,0,0,0,0,0,0,0)';
      PINUSE='POWER';
      NO_LOAD_CHECK='Both';
      NO_IO_CHECK='Both';
      NO_ASSERT_CHECK='TRUE';
      NO_DIR_CHECK='TRUE';
      ALLOW_CONNECT='TRUE';
    'VSS1223':
      PIN_NUMBER='(0,0,0,0,0,0,0,0,0,0,0,0,0,0,0,0,0,0,0,0,0,0,0,0,0,0,0,0,0,0,0,ED61,0,0,0,0,0,0,0,0,0,0)';
      PINUSE='POWER';
      NO_LOAD_CHECK='Both';
      NO_IO_CHECK='Both';
      NO_ASSERT_CHECK='TRUE';
      NO_DIR_CHECK='TRUE';
      ALLOW_CONNECT='TRUE';
    'VSS1220':
      PIN_NUMBER='(0,0,0,0,0,0,0,0,0,0,0,0,0,0,0,0,0,0,0,0,0,0,0,0,0,0,0,0,0,0,0,ED55,0,0,0,0,0,0,0,0,0,0)';
      PINUSE='POWER';
      NO_LOAD_CHECK='Both';
      NO_IO_CHECK='Both';
      NO_ASSERT_CHECK='TRUE';
      NO_DIR_CHECK='TRUE';
      ALLOW_CONNECT='TRUE';
    'VSS1217':
      PIN_NUMBER='(0,0,0,0,0,0,0,0,0,0,0,0,0,0,0,0,0,0,0,0,0,0,0,0,0,0,0,0,0,0,0,ED42,0,0,0,0,0,0,0,0,0,0)';
      PINUSE='POWER';
      NO_LOAD_CHECK='Both';
      NO_IO_CHECK='Both';
      NO_ASSERT_CHECK='TRUE';
      NO_DIR_CHECK='TRUE';
      ALLOW_CONNECT='TRUE';
    'VSS1210':
      PIN_NUMBER='(0,0,0,0,0,0,0,0,0,0,0,0,0,0,0,0,0,0,0,0,0,0,0,0,0,0,0,0,0,0,0,ED18,0,0,0,0,0,0,0,0,0,0)';
      PINUSE='POWER';
      NO_LOAD_CHECK='Both';
      NO_IO_CHECK='Both';
      NO_ASSERT_CHECK='TRUE';
      NO_DIR_CHECK='TRUE';
      ALLOW_CONNECT='TRUE';
    'VSS1208':
      PIN_NUMBER='(0,0,0,0,0,0,0,0,0,0,0,0,0,0,0,0,0,0,0,0,0,0,0,0,0,0,0,0,0,0,0,ED12,0,0,0,0,0,0,0,0,0,0)';
      PINUSE='POWER';
      NO_LOAD_CHECK='Both';
      NO_IO_CHECK='Both';
      NO_ASSERT_CHECK='TRUE';
      NO_DIR_CHECK='TRUE';
      ALLOW_CONNECT='TRUE';
    'VSS1200':
      PIN_NUMBER='(0,0,0,0,0,0,0,0,0,0,0,0,0,0,0,0,0,0,0,0,0,0,0,0,0,0,0,0,0,0,0,EC68,0,0,0,0,0,0,0,0,0,0)';
      PINUSE='POWER';
      NO_LOAD_CHECK='Both';
      NO_IO_CHECK='Both';
      NO_ASSERT_CHECK='TRUE';
      NO_DIR_CHECK='TRUE';
      ALLOW_CONNECT='TRUE';
    'VSS1198':
      PIN_NUMBER='(0,0,0,0,0,0,0,0,0,0,0,0,0,0,0,0,0,0,0,0,0,0,0,0,0,0,0,0,0,0,0,EC62,0,0,0,0,0,0,0,0,0,0)';
      PINUSE='POWER';
      NO_LOAD_CHECK='Both';
      NO_IO_CHECK='Both';
      NO_ASSERT_CHECK='TRUE';
      NO_DIR_CHECK='TRUE';
      ALLOW_CONNECT='TRUE';
    'VSS1197':
      PIN_NUMBER='(0,0,0,0,0,0,0,0,0,0,0,0,0,0,0,0,0,0,0,0,0,0,0,0,0,0,0,0,0,0,0,EC60,0,0,0,0,0,0,0,0,0,0)';
      PINUSE='POWER';
      NO_LOAD_CHECK='Both';
      NO_IO_CHECK='Both';
      NO_ASSERT_CHECK='TRUE';
      NO_DIR_CHECK='TRUE';
      ALLOW_CONNECT='TRUE';
    'VSS1195':
      PIN_NUMBER='(0,0,0,0,0,0,0,0,0,0,0,0,0,0,0,0,0,0,0,0,0,0,0,0,0,0,0,0,0,0,0,EC54,0,0,0,0,0,0,0,0,0,0)';
      PINUSE='POWER';
      NO_LOAD_CHECK='Both';
      NO_IO_CHECK='Both';
      NO_ASSERT_CHECK='TRUE';
      NO_DIR_CHECK='TRUE';
      ALLOW_CONNECT='TRUE';
    'VSS1193':
      PIN_NUMBER='(0,0,0,0,0,0,0,0,0,0,0,0,0,0,0,0,0,0,0,0,0,0,0,0,0,0,0,0,0,0,0,EC5,0,0,0,0,0,0,0,0,0,0)';
      PINUSE='POWER';
      NO_LOAD_CHECK='Both';
      NO_IO_CHECK='Both';
      NO_ASSERT_CHECK='TRUE';
      NO_DIR_CHECK='TRUE';
      ALLOW_CONNECT='TRUE';
    'VSS1188':
      PIN_NUMBER='(0,0,0,0,0,0,0,0,0,0,0,0,0,0,0,0,0,0,0,0,0,0,0,0,0,0,0,0,0,0,0,EC35,0,0,0,0,0,0,0,0,0,0)';
      PINUSE='POWER';
      NO_LOAD_CHECK='Both';
      NO_IO_CHECK='Both';
      NO_ASSERT_CHECK='TRUE';
      NO_DIR_CHECK='TRUE';
      ALLOW_CONNECT='TRUE';
    'VSS1185':
      PIN_NUMBER='(0,0,0,0,0,0,0,0,0,0,0,0,0,0,0,0,0,0,0,0,0,0,0,0,0,0,0,0,0,0,0,EC25,0,0,0,0,0,0,0,0,0,0)';
      PINUSE='POWER';
      NO_LOAD_CHECK='Both';
      NO_IO_CHECK='Both';
      NO_ASSERT_CHECK='TRUE';
      NO_DIR_CHECK='TRUE';
      ALLOW_CONNECT='TRUE';
    'VSS1180':
      PIN_NUMBER='(0,0,0,0,0,0,0,0,0,0,0,0,0,0,0,0,0,0,0,0,0,0,0,0,0,0,0,0,0,0,0,EB91,0,0,0,0,0,0,0,0,0,0)';
      PINUSE='POWER';
      NO_LOAD_CHECK='Both';
      NO_IO_CHECK='Both';
      NO_ASSERT_CHECK='TRUE';
      NO_DIR_CHECK='TRUE';
      ALLOW_CONNECT='TRUE';
    'VSS1171':
      PIN_NUMBER='(0,0,0,0,0,0,0,0,0,0,0,0,0,0,0,0,0,0,0,0,0,0,0,0,0,0,0,0,0,0,0,EB63,0,0,0,0,0,0,0,0,0,0)';
      PINUSE='POWER';
      NO_LOAD_CHECK='Both';
      NO_IO_CHECK='Both';
      NO_ASSERT_CHECK='TRUE';
      NO_DIR_CHECK='TRUE';
      ALLOW_CONNECT='TRUE';
    'VSS1170':
      PIN_NUMBER='(0,0,0,0,0,0,0,0,0,0,0,0,0,0,0,0,0,0,0,0,0,0,0,0,0,0,0,0,0,0,0,EB59,0,0,0,0,0,0,0,0,0,0)';
      PINUSE='POWER';
      NO_LOAD_CHECK='Both';
      NO_IO_CHECK='Both';
      NO_ASSERT_CHECK='TRUE';
      NO_DIR_CHECK='TRUE';
      ALLOW_CONNECT='TRUE';
    'VSS1168':
      PIN_NUMBER='(0,0,0,0,0,0,0,0,0,0,0,0,0,0,0,0,0,0,0,0,0,0,0,0,0,0,0,0,0,0,0,EB53,0,0,0,0,0,0,0,0,0,0)';
      PINUSE='POWER';
      NO_LOAD_CHECK='Both';
      NO_IO_CHECK='Both';
      NO_ASSERT_CHECK='TRUE';
      NO_DIR_CHECK='TRUE';
      ALLOW_CONNECT='TRUE';
    'VSS1167':
      PIN_NUMBER='(0,0,0,0,0,0,0,0,0,0,0,0,0,0,0,0,0,0,0,0,0,0,0,0,0,0,0,0,0,0,0,EB51,0,0,0,0,0,0,0,0,0,0)';
      PINUSE='POWER';
      NO_LOAD_CHECK='Both';
      NO_IO_CHECK='Both';
      NO_ASSERT_CHECK='TRUE';
      NO_DIR_CHECK='TRUE';
      ALLOW_CONNECT='TRUE';
    'VSS1165':
      PIN_NUMBER='(0,0,0,0,0,0,0,0,0,0,0,0,0,0,0,0,0,0,0,0,0,0,0,0,0,0,0,0,0,0,0,EB44,0,0,0,0,0,0,0,0,0,0)';
      PINUSE='POWER';
      NO_LOAD_CHECK='Both';
      NO_IO_CHECK='Both';
      NO_ASSERT_CHECK='TRUE';
      NO_DIR_CHECK='TRUE';
      ALLOW_CONNECT='TRUE';
    'VSS1163':
      PIN_NUMBER='(0,0,0,0,0,0,0,0,0,0,0,0,0,0,0,0,0,0,0,0,0,0,0,0,0,0,0,0,0,0,0,EB4,0,0,0,0,0,0,0,0,0,0)';
      PINUSE='POWER';
      NO_LOAD_CHECK='Both';
      NO_IO_CHECK='Both';
      NO_ASSERT_CHECK='TRUE';
      NO_DIR_CHECK='TRUE';
      ALLOW_CONNECT='TRUE';
    'VSS1161':
      PIN_NUMBER='(0,0,0,0,0,0,0,0,0,0,0,0,0,0,0,0,0,0,0,0,0,0,0,0,0,0,0,0,0,0,0,EB34,0,0,0,0,0,0,0,0,0,0)';
      PINUSE='POWER';
      NO_LOAD_CHECK='Both';
      NO_IO_CHECK='Both';
      NO_ASSERT_CHECK='TRUE';
      NO_DIR_CHECK='TRUE';
      ALLOW_CONNECT='TRUE';
    'VSS1158':
      PIN_NUMBER='(0,0,0,0,0,0,0,0,0,0,0,0,0,0,0,0,0,0,0,0,0,0,0,0,0,0,0,0,0,0,0,EB26,0,0,0,0,0,0,0,0,0,0)';
      PINUSE='POWER';
      NO_LOAD_CHECK='Both';
      NO_IO_CHECK='Both';
      NO_ASSERT_CHECK='TRUE';
      NO_DIR_CHECK='TRUE';
      ALLOW_CONNECT='TRUE';
    'VSS1156':
      PIN_NUMBER='(0,0,0,0,0,0,0,0,0,0,0,0,0,0,0,0,0,0,0,0,0,0,0,0,0,0,0,0,0,0,0,EB20,0,0,0,0,0,0,0,0,0,0)';
      PINUSE='POWER';
      NO_LOAD_CHECK='Both';
      NO_IO_CHECK='Both';
      NO_ASSERT_CHECK='TRUE';
      NO_DIR_CHECK='TRUE';
      ALLOW_CONNECT='TRUE';
    'VSS1155':
      PIN_NUMBER='(0,0,0,0,0,0,0,0,0,0,0,0,0,0,0,0,0,0,0,0,0,0,0,0,0,0,0,0,0,0,0,EB16,0,0,0,0,0,0,0,0,0,0)';
      PINUSE='POWER';
      NO_LOAD_CHECK='Both';
      NO_IO_CHECK='Both';
      NO_ASSERT_CHECK='TRUE';
      NO_DIR_CHECK='TRUE';
      ALLOW_CONNECT='TRUE';
    'VSS1146':
      PIN_NUMBER='(0,0,0,0,0,0,0,0,0,0,0,0,0,0,0,0,0,0,0,0,0,0,0,0,0,0,0,0,0,0,0,EA64,0,0,0,0,0,0,0,0,0,0)';
      PINUSE='POWER';
      NO_LOAD_CHECK='Both';
      NO_IO_CHECK='Both';
      NO_ASSERT_CHECK='TRUE';
      NO_DIR_CHECK='TRUE';
      ALLOW_CONNECT='TRUE';
    'VSS1145':
      PIN_NUMBER='(0,0,0,0,0,0,0,0,0,0,0,0,0,0,0,0,0,0,0,0,0,0,0,0,0,0,0,0,0,0,0,EA58,0,0,0,0,0,0,0,0,0,0)';
      PINUSE='POWER';
      NO_LOAD_CHECK='Both';
      NO_IO_CHECK='Both';
      NO_ASSERT_CHECK='TRUE';
      NO_DIR_CHECK='TRUE';
      ALLOW_CONNECT='TRUE';
    'VSS1144':
      PIN_NUMBER='(0,0,0,0,0,0,0,0,0,0,0,0,0,0,0,0,0,0,0,0,0,0,0,0,0,0,0,0,0,0,0,EA52,0,0,0,0,0,0,0,0,0,0)';
      PINUSE='POWER';
      NO_LOAD_CHECK='Both';
      NO_IO_CHECK='Both';
      NO_ASSERT_CHECK='TRUE';
      NO_DIR_CHECK='TRUE';
      ALLOW_CONNECT='TRUE';
    'VSS1142':
      PIN_NUMBER='(0,0,0,0,0,0,0,0,0,0,0,0,0,0,0,0,0,0,0,0,0,0,0,0,0,0,0,0,0,0,0,EA45,0,0,0,0,0,0,0,0,0,0)';
      PINUSE='POWER';
      NO_LOAD_CHECK='Both';
      NO_IO_CHECK='Both';
      NO_ASSERT_CHECK='TRUE';
      NO_DIR_CHECK='TRUE';
      ALLOW_CONNECT='TRUE';
    'VSS1141':
      PIN_NUMBER='(0,0,0,0,0,0,0,0,0,0,0,0,0,0,0,0,0,0,0,0,0,0,0,0,0,0,0,0,0,0,0,EA39,0,0,0,0,0,0,0,0,0,0)';
      PINUSE='POWER';
      NO_LOAD_CHECK='Both';
      NO_IO_CHECK='Both';
      NO_ASSERT_CHECK='TRUE';
      NO_DIR_CHECK='TRUE';
      ALLOW_CONNECT='TRUE';
    'VSS1116':
      PIN_NUMBER='(0,0,0,0,0,0,0,0,0,0,0,0,0,0,0,0,0,0,0,0,0,0,0,0,0,0,0,0,0,0,0,DY42,0,0,0,0,0,0,0,0,0,0)';
      PINUSE='POWER';
      NO_LOAD_CHECK='Both';
      NO_IO_CHECK='Both';
      NO_ASSERT_CHECK='TRUE';
      NO_DIR_CHECK='TRUE';
      ALLOW_CONNECT='TRUE';
    'VSS1115':
      PIN_NUMBER='(0,0,0,0,0,0,0,0,0,0,0,0,0,0,0,0,0,0,0,0,0,0,0,0,0,0,0,0,0,0,0,DY4,0,0,0,0,0,0,0,0,0,0)';
      PINUSE='POWER';
      NO_LOAD_CHECK='Both';
      NO_IO_CHECK='Both';
      NO_ASSERT_CHECK='TRUE';
      NO_DIR_CHECK='TRUE';
      ALLOW_CONNECT='TRUE';
    'VSS1112':
      PIN_NUMBER='(0,0,0,0,0,0,0,0,0,0,0,0,0,0,0,0,0,0,0,0,0,0,0,0,0,0,0,0,0,0,0,DY16,0,0,0,0,0,0,0,0,0,0)';
      PINUSE='POWER';
      NO_LOAD_CHECK='Both';
      NO_IO_CHECK='Both';
      NO_ASSERT_CHECK='TRUE';
      NO_DIR_CHECK='TRUE';
      ALLOW_CONNECT='TRUE';
    'VSS1111':
      PIN_NUMBER='(0,0,0,0,0,0,0,0,0,0,0,0,0,0,0,0,0,0,0,0,0,0,0,0,0,0,0,0,0,0,0,DY12,0,0,0,0,0,0,0,0,0,0)';
      PINUSE='POWER';
      NO_LOAD_CHECK='Both';
      NO_IO_CHECK='Both';
      NO_ASSERT_CHECK='TRUE';
      NO_DIR_CHECK='TRUE';
      ALLOW_CONNECT='TRUE';
    'VSS1268':
      PIN_NUMBER='(0,0,0,0,0,0,0,0,0,0,0,0,0,0,0,0,0,0,0,0,0,0,0,0,0,0,0,0,0,0,0,0,DW9,0,0,0,0,0,0,0,0,0)';
      PINUSE='POWER';
      NO_LOAD_CHECK='Both';
      NO_IO_CHECK='Both';
      NO_ASSERT_CHECK='TRUE';
      NO_DIR_CHECK='TRUE';
      ALLOW_CONNECT='TRUE';
    'VSS1256':
      PIN_NUMBER='(0,0,0,0,0,0,0,0,0,0,0,0,0,0,0,0,0,0,0,0,0,0,0,0,0,0,0,0,0,0,0,0,DW64,0,0,0,0,0,0,0,0,0)';
      PINUSE='POWER';
      NO_LOAD_CHECK='Both';
      NO_IO_CHECK='Both';
      NO_ASSERT_CHECK='TRUE';
      NO_DIR_CHECK='TRUE';
      ALLOW_CONNECT='TRUE';
    'VSS1255':
      PIN_NUMBER='(0,0,0,0,0,0,0,0,0,0,0,0,0,0,0,0,0,0,0,0,0,0,0,0,0,0,0,0,0,0,0,0,DW62,0,0,0,0,0,0,0,0,0)';
      PINUSE='POWER';
      NO_LOAD_CHECK='Both';
      NO_IO_CHECK='Both';
      NO_ASSERT_CHECK='TRUE';
      NO_DIR_CHECK='TRUE';
      ALLOW_CONNECT='TRUE';
    'VSS1254':
      PIN_NUMBER='(0,0,0,0,0,0,0,0,0,0,0,0,0,0,0,0,0,0,0,0,0,0,0,0,0,0,0,0,0,0,0,0,DW58,0,0,0,0,0,0,0,0,0)';
      PINUSE='POWER';
      NO_LOAD_CHECK='Both';
      NO_IO_CHECK='Both';
      NO_ASSERT_CHECK='TRUE';
      NO_DIR_CHECK='TRUE';
      ALLOW_CONNECT='TRUE';
    'VSS1253':
      PIN_NUMBER='(0,0,0,0,0,0,0,0,0,0,0,0,0,0,0,0,0,0,0,0,0,0,0,0,0,0,0,0,0,0,0,0,DW56,0,0,0,0,0,0,0,0,0)';
      PINUSE='POWER';
      NO_LOAD_CHECK='Both';
      NO_IO_CHECK='Both';
      NO_ASSERT_CHECK='TRUE';
      NO_DIR_CHECK='TRUE';
      ALLOW_CONNECT='TRUE';
    'VSS1252':
      PIN_NUMBER='(0,0,0,0,0,0,0,0,0,0,0,0,0,0,0,0,0,0,0,0,0,0,0,0,0,0,0,0,0,0,0,0,DW54,0,0,0,0,0,0,0,0,0)';
      PINUSE='POWER';
      NO_LOAD_CHECK='Both';
      NO_IO_CHECK='Both';
      NO_ASSERT_CHECK='TRUE';
      NO_DIR_CHECK='TRUE';
      ALLOW_CONNECT='TRUE';
    'VSS1251':
      PIN_NUMBER='(0,0,0,0,0,0,0,0,0,0,0,0,0,0,0,0,0,0,0,0,0,0,0,0,0,0,0,0,0,0,0,0,DW52,0,0,0,0,0,0,0,0,0)';
      PINUSE='POWER';
      NO_LOAD_CHECK='Both';
      NO_IO_CHECK='Both';
      NO_ASSERT_CHECK='TRUE';
      NO_DIR_CHECK='TRUE';
      ALLOW_CONNECT='TRUE';
    'VSS1250':
      PIN_NUMBER='(0,0,0,0,0,0,0,0,0,0,0,0,0,0,0,0,0,0,0,0,0,0,0,0,0,0,0,0,0,0,0,0,DW50,0,0,0,0,0,0,0,0,0)';
      PINUSE='POWER';
      NO_LOAD_CHECK='Both';
      NO_IO_CHECK='Both';
      NO_ASSERT_CHECK='TRUE';
      NO_DIR_CHECK='TRUE';
      ALLOW_CONNECT='TRUE';
    'VSS1249':
      PIN_NUMBER='(0,0,0,0,0,0,0,0,0,0,0,0,0,0,0,0,0,0,0,0,0,0,0,0,0,0,0,0,0,0,0,0,DW5,0,0,0,0,0,0,0,0,0)';
      PINUSE='POWER';
      NO_LOAD_CHECK='Both';
      NO_IO_CHECK='Both';
      NO_ASSERT_CHECK='TRUE';
      NO_DIR_CHECK='TRUE';
      ALLOW_CONNECT='TRUE';
    'VSS1248':
      PIN_NUMBER='(0,0,0,0,0,0,0,0,0,0,0,0,0,0,0,0,0,0,0,0,0,0,0,0,0,0,0,0,0,0,0,0,DW48,0,0,0,0,0,0,0,0,0)';
      PINUSE='POWER';
      NO_LOAD_CHECK='Both';
      NO_IO_CHECK='Both';
      NO_ASSERT_CHECK='TRUE';
      NO_DIR_CHECK='TRUE';
      ALLOW_CONNECT='TRUE';
    'VSS1247':
      PIN_NUMBER='(0,0,0,0,0,0,0,0,0,0,0,0,0,0,0,0,0,0,0,0,0,0,0,0,0,0,0,0,0,0,0,0,DW45,0,0,0,0,0,0,0,0,0)';
      PINUSE='POWER';
      NO_LOAD_CHECK='Both';
      NO_IO_CHECK='Both';
      NO_ASSERT_CHECK='TRUE';
      NO_DIR_CHECK='TRUE';
      ALLOW_CONNECT='TRUE';
    'VSS1246':
      PIN_NUMBER='(0,0,0,0,0,0,0,0,0,0,0,0,0,0,0,0,0,0,0,0,0,0,0,0,0,0,0,0,0,0,0,0,DW43,0,0,0,0,0,0,0,0,0)';
      PINUSE='POWER';
      NO_LOAD_CHECK='Both';
      NO_IO_CHECK='Both';
      NO_ASSERT_CHECK='TRUE';
      NO_DIR_CHECK='TRUE';
      ALLOW_CONNECT='TRUE';
    'VSS1245':
      PIN_NUMBER='(0,0,0,0,0,0,0,0,0,0,0,0,0,0,0,0,0,0,0,0,0,0,0,0,0,0,0,0,0,0,0,0,DW41,0,0,0,0,0,0,0,0,0)';
      PINUSE='POWER';
      NO_LOAD_CHECK='Both';
      NO_IO_CHECK='Both';
      NO_ASSERT_CHECK='TRUE';
      NO_DIR_CHECK='TRUE';
      ALLOW_CONNECT='TRUE';
    'VSS1244':
      PIN_NUMBER='(0,0,0,0,0,0,0,0,0,0,0,0,0,0,0,0,0,0,0,0,0,0,0,0,0,0,0,0,0,0,0,0,DW39,0,0,0,0,0,0,0,0,0)';
      PINUSE='POWER';
      NO_LOAD_CHECK='Both';
      NO_IO_CHECK='Both';
      NO_ASSERT_CHECK='TRUE';
      NO_DIR_CHECK='TRUE';
      ALLOW_CONNECT='TRUE';
    'VSS1243':
      PIN_NUMBER='(0,0,0,0,0,0,0,0,0,0,0,0,0,0,0,0,0,0,0,0,0,0,0,0,0,0,0,0,0,0,0,0,DW37,0,0,0,0,0,0,0,0,0)';
      PINUSE='POWER';
      NO_LOAD_CHECK='Both';
      NO_IO_CHECK='Both';
      NO_ASSERT_CHECK='TRUE';
      NO_DIR_CHECK='TRUE';
      ALLOW_CONNECT='TRUE';
    'VSS1242':
      PIN_NUMBER='(0,0,0,0,0,0,0,0,0,0,0,0,0,0,0,0,0,0,0,0,0,0,0,0,0,0,0,0,0,0,0,0,DW35,0,0,0,0,0,0,0,0,0)';
      PINUSE='POWER';
      NO_LOAD_CHECK='Both';
      NO_IO_CHECK='Both';
      NO_ASSERT_CHECK='TRUE';
      NO_DIR_CHECK='TRUE';
      ALLOW_CONNECT='TRUE';
    'VSS1241':
      PIN_NUMBER='(0,0,0,0,0,0,0,0,0,0,0,0,0,0,0,0,0,0,0,0,0,0,0,0,0,0,0,0,0,0,0,0,DW33,0,0,0,0,0,0,0,0,0)';
      PINUSE='POWER';
      NO_LOAD_CHECK='Both';
      NO_IO_CHECK='Both';
      NO_ASSERT_CHECK='TRUE';
      NO_DIR_CHECK='TRUE';
      ALLOW_CONNECT='TRUE';
    'VSS1240':
      PIN_NUMBER='(0,0,0,0,0,0,0,0,0,0,0,0,0,0,0,0,0,0,0,0,0,0,0,0,0,0,0,0,0,0,0,0,DW31,0,0,0,0,0,0,0,0,0)';
      PINUSE='POWER';
      NO_LOAD_CHECK='Both';
      NO_IO_CHECK='Both';
      NO_ASSERT_CHECK='TRUE';
      NO_DIR_CHECK='TRUE';
      ALLOW_CONNECT='TRUE';
    'VSS1239':
      PIN_NUMBER='(0,0,0,0,0,0,0,0,0,0,0,0,0,0,0,0,0,0,0,0,0,0,0,0,0,0,0,0,0,0,0,0,DW29,0,0,0,0,0,0,0,0,0)';
      PINUSE='POWER';
      NO_LOAD_CHECK='Both';
      NO_IO_CHECK='Both';
      NO_ASSERT_CHECK='TRUE';
      NO_DIR_CHECK='TRUE';
      ALLOW_CONNECT='TRUE';
    'VSS1238':
      PIN_NUMBER='(0,0,0,0,0,0,0,0,0,0,0,0,0,0,0,0,0,0,0,0,0,0,0,0,0,0,0,0,0,0,0,0,DW27,0,0,0,0,0,0,0,0,0)';
      PINUSE='POWER';
      NO_LOAD_CHECK='Both';
      NO_IO_CHECK='Both';
      NO_ASSERT_CHECK='TRUE';
      NO_DIR_CHECK='TRUE';
      ALLOW_CONNECT='TRUE';
    'VSS1236':
      PIN_NUMBER='(0,0,0,0,0,0,0,0,0,0,0,0,0,0,0,0,0,0,0,0,0,0,0,0,0,0,0,0,0,0,0,0,DW25,0,0,0,0,0,0,0,0,0)';
      PINUSE='POWER';
      NO_LOAD_CHECK='Both';
      NO_IO_CHECK='Both';
      NO_ASSERT_CHECK='TRUE';
      NO_DIR_CHECK='TRUE';
      ALLOW_CONNECT='TRUE';
    'VSS1234':
      PIN_NUMBER='(0,0,0,0,0,0,0,0,0,0,0,0,0,0,0,0,0,0,0,0,0,0,0,0,0,0,0,0,0,0,0,0,DW23,0,0,0,0,0,0,0,0,0)';
      PINUSE='POWER';
      NO_LOAD_CHECK='Both';
      NO_IO_CHECK='Both';
      NO_ASSERT_CHECK='TRUE';
      NO_DIR_CHECK='TRUE';
      ALLOW_CONNECT='TRUE';
    'VSS1233':
      PIN_NUMBER='(0,0,0,0,0,0,0,0,0,0,0,0,0,0,0,0,0,0,0,0,0,0,0,0,0,0,0,0,0,0,0,0,DW19,0,0,0,0,0,0,0,0,0)';
      PINUSE='POWER';
      NO_LOAD_CHECK='Both';
      NO_IO_CHECK='Both';
      NO_ASSERT_CHECK='TRUE';
      NO_DIR_CHECK='TRUE';
      ALLOW_CONNECT='TRUE';
    'VSS1231':
      PIN_NUMBER='(0,0,0,0,0,0,0,0,0,0,0,0,0,0,0,0,0,0,0,0,0,0,0,0,0,0,0,0,0,0,0,0,DW17,0,0,0,0,0,0,0,0,0)';
      PINUSE='POWER';
      NO_LOAD_CHECK='Both';
      NO_IO_CHECK='Both';
      NO_ASSERT_CHECK='TRUE';
      NO_DIR_CHECK='TRUE';
      ALLOW_CONNECT='TRUE';
    'VSS1230':
      PIN_NUMBER='(0,0,0,0,0,0,0,0,0,0,0,0,0,0,0,0,0,0,0,0,0,0,0,0,0,0,0,0,0,0,0,0,DW13,0,0,0,0,0,0,0,0,0)';
      PINUSE='POWER';
      NO_LOAD_CHECK='Both';
      NO_IO_CHECK='Both';
      NO_ASSERT_CHECK='TRUE';
      NO_DIR_CHECK='TRUE';
      ALLOW_CONNECT='TRUE';
    'VSS1229':
      PIN_NUMBER='(0,0,0,0,0,0,0,0,0,0,0,0,0,0,0,0,0,0,0,0,0,0,0,0,0,0,0,0,0,0,0,0,DW1,0,0,0,0,0,0,0,0,0)';
      PINUSE='POWER';
      NO_LOAD_CHECK='Both';
      NO_IO_CHECK='Both';
      NO_ASSERT_CHECK='TRUE';
      NO_DIR_CHECK='TRUE';
      ALLOW_CONNECT='TRUE';
    'VSS1228':
      PIN_NUMBER='(0,0,0,0,0,0,0,0,0,0,0,0,0,0,0,0,0,0,0,0,0,0,0,0,0,0,0,0,0,0,0,0,DV91,0,0,0,0,0,0,0,0,0)';
      PINUSE='POWER';
      NO_LOAD_CHECK='Both';
      NO_IO_CHECK='Both';
      NO_ASSERT_CHECK='TRUE';
      NO_DIR_CHECK='TRUE';
      ALLOW_CONNECT='TRUE';
    'VSS1227':
      PIN_NUMBER='(0,0,0,0,0,0,0,0,0,0,0,0,0,0,0,0,0,0,0,0,0,0,0,0,0,0,0,0,0,0,0,0,DV87,0,0,0,0,0,0,0,0,0)';
      PINUSE='POWER';
      NO_LOAD_CHECK='Both';
      NO_IO_CHECK='Both';
      NO_ASSERT_CHECK='TRUE';
      NO_DIR_CHECK='TRUE';
      ALLOW_CONNECT='TRUE';
    'VSS1226':
      PIN_NUMBER='(0,0,0,0,0,0,0,0,0,0,0,0,0,0,0,0,0,0,0,0,0,0,0,0,0,0,0,0,0,0,0,0,DV83,0,0,0,0,0,0,0,0,0)';
      PINUSE='POWER';
      NO_LOAD_CHECK='Both';
      NO_IO_CHECK='Both';
      NO_ASSERT_CHECK='TRUE';
      NO_DIR_CHECK='TRUE';
      ALLOW_CONNECT='TRUE';
    'VSS1222':
      PIN_NUMBER='(0,0,0,0,0,0,0,0,0,0,0,0,0,0,0,0,0,0,0,0,0,0,0,0,0,0,0,0,0,0,0,0,DV81,0,0,0,0,0,0,0,0,0)';
      PINUSE='POWER';
      NO_LOAD_CHECK='Both';
      NO_IO_CHECK='Both';
      NO_ASSERT_CHECK='TRUE';
      NO_DIR_CHECK='TRUE';
      ALLOW_CONNECT='TRUE';
    'VSS1221':
      PIN_NUMBER='(0,0,0,0,0,0,0,0,0,0,0,0,0,0,0,0,0,0,0,0,0,0,0,0,0,0,0,0,0,0,0,0,DV8,0,0,0,0,0,0,0,0,0)';
      PINUSE='POWER';
      NO_LOAD_CHECK='Both';
      NO_IO_CHECK='Both';
      NO_ASSERT_CHECK='TRUE';
      NO_DIR_CHECK='TRUE';
      ALLOW_CONNECT='TRUE';
    'VSS1219':
      PIN_NUMBER='(0,0,0,0,0,0,0,0,0,0,0,0,0,0,0,0,0,0,0,0,0,0,0,0,0,0,0,0,0,0,0,0,DV79,0,0,0,0,0,0,0,0,0)';
      PINUSE='POWER';
      NO_LOAD_CHECK='Both';
      NO_IO_CHECK='Both';
      NO_ASSERT_CHECK='TRUE';
      NO_DIR_CHECK='TRUE';
      ALLOW_CONNECT='TRUE';
    'VSS1218':
      PIN_NUMBER='(0,0,0,0,0,0,0,0,0,0,0,0,0,0,0,0,0,0,0,0,0,0,0,0,0,0,0,0,0,0,0,0,DV77,0,0,0,0,0,0,0,0,0)';
      PINUSE='POWER';
      NO_LOAD_CHECK='Both';
      NO_IO_CHECK='Both';
      NO_ASSERT_CHECK='TRUE';
      NO_DIR_CHECK='TRUE';
      ALLOW_CONNECT='TRUE';
    'VSS1216':
      PIN_NUMBER='(0,0,0,0,0,0,0,0,0,0,0,0,0,0,0,0,0,0,0,0,0,0,0,0,0,0,0,0,0,0,0,0,DU88,0,0,0,0,0,0,0,0,0)';
      PINUSE='POWER';
      NO_LOAD_CHECK='Both';
      NO_IO_CHECK='Both';
      NO_ASSERT_CHECK='TRUE';
      NO_DIR_CHECK='TRUE';
      ALLOW_CONNECT='TRUE';
    'VSS1215':
      PIN_NUMBER='(0,0,0,0,0,0,0,0,0,0,0,0,0,0,0,0,0,0,0,0,0,0,0,0,0,0,0,0,0,0,0,0,DU84,0,0,0,0,0,0,0,0,0)';
      PINUSE='POWER';
      NO_LOAD_CHECK='Both';
      NO_IO_CHECK='Both';
      NO_ASSERT_CHECK='TRUE';
      NO_DIR_CHECK='TRUE';
      ALLOW_CONNECT='TRUE';
    'VSS1214':
      PIN_NUMBER='(0,0,0,0,0,0,0,0,0,0,0,0,0,0,0,0,0,0,0,0,0,0,0,0,0,0,0,0,0,0,0,0,DU78,0,0,0,0,0,0,0,0,0)';
      PINUSE='POWER';
      NO_LOAD_CHECK='Both';
      NO_IO_CHECK='Both';
      NO_ASSERT_CHECK='TRUE';
      NO_DIR_CHECK='TRUE';
      ALLOW_CONNECT='TRUE';
    'VSS1213':
      PIN_NUMBER='(0,0,0,0,0,0,0,0,0,0,0,0,0,0,0,0,0,0,0,0,0,0,0,0,0,0,0,0,0,0,0,0,DU76,0,0,0,0,0,0,0,0,0)';
      PINUSE='POWER';
      NO_LOAD_CHECK='Both';
      NO_IO_CHECK='Both';
      NO_ASSERT_CHECK='TRUE';
      NO_DIR_CHECK='TRUE';
      ALLOW_CONNECT='TRUE';
    'VSS1212':
      PIN_NUMBER='(0,0,0,0,0,0,0,0,0,0,0,0,0,0,0,0,0,0,0,0,0,0,0,0,0,0,0,0,0,0,0,0,DU33,0,0,0,0,0,0,0,0,0)';
      PINUSE='POWER';
      NO_LOAD_CHECK='Both';
      NO_IO_CHECK='Both';
      NO_ASSERT_CHECK='TRUE';
      NO_DIR_CHECK='TRUE';
      ALLOW_CONNECT='TRUE';
    'VSS1211':
      PIN_NUMBER='(0,0,0,0,0,0,0,0,0,0,0,0,0,0,0,0,0,0,0,0,0,0,0,0,0,0,0,0,0,0,0,0,DU27,0,0,0,0,0,0,0,0,0)';
      PINUSE='POWER';
      NO_LOAD_CHECK='Both';
      NO_IO_CHECK='Both';
      NO_ASSERT_CHECK='TRUE';
      NO_DIR_CHECK='TRUE';
      ALLOW_CONNECT='TRUE';
    'VSS1209':
      PIN_NUMBER='(0,0,0,0,0,0,0,0,0,0,0,0,0,0,0,0,0,0,0,0,0,0,0,0,0,0,0,0,0,0,0,0,DU21,0,0,0,0,0,0,0,0,0)';
      PINUSE='POWER';
      NO_LOAD_CHECK='Both';
      NO_IO_CHECK='Both';
      NO_ASSERT_CHECK='TRUE';
      NO_DIR_CHECK='TRUE';
      ALLOW_CONNECT='TRUE';
    'VSS1207':
      PIN_NUMBER='(0,0,0,0,0,0,0,0,0,0,0,0,0,0,0,0,0,0,0,0,0,0,0,0,0,0,0,0,0,0,0,0,DT8,0,0,0,0,0,0,0,0,0)';
      PINUSE='POWER';
      NO_LOAD_CHECK='Both';
      NO_IO_CHECK='Both';
      NO_ASSERT_CHECK='TRUE';
      NO_DIR_CHECK='TRUE';
      ALLOW_CONNECT='TRUE';
    'VSS1206':
      PIN_NUMBER='(0,0,0,0,0,0,0,0,0,0,0,0,0,0,0,0,0,0,0,0,0,0,0,0,0,0,0,0,0,0,0,0,DT75,0,0,0,0,0,0,0,0,0)';
      PINUSE='POWER';
      NO_LOAD_CHECK='Both';
      NO_IO_CHECK='Both';
      NO_ASSERT_CHECK='TRUE';
      NO_DIR_CHECK='TRUE';
      ALLOW_CONNECT='TRUE';
    'VSS1205':
      PIN_NUMBER='(0,0,0,0,0,0,0,0,0,0,0,0,0,0,0,0,0,0,0,0,0,0,0,0,0,0,0,0,0,0,0,0,DT71,0,0,0,0,0,0,0,0,0)';
      PINUSE='POWER';
      NO_LOAD_CHECK='Both';
      NO_IO_CHECK='Both';
      NO_ASSERT_CHECK='TRUE';
      NO_DIR_CHECK='TRUE';
      ALLOW_CONNECT='TRUE';
    'VSS1204':
      PIN_NUMBER='(0,0,0,0,0,0,0,0,0,0,0,0,0,0,0,0,0,0,0,0,0,0,0,0,0,0,0,0,0,0,0,0,DT69,0,0,0,0,0,0,0,0,0)';
      PINUSE='POWER';
      NO_LOAD_CHECK='Both';
      NO_IO_CHECK='Both';
      NO_ASSERT_CHECK='TRUE';
      NO_DIR_CHECK='TRUE';
      ALLOW_CONNECT='TRUE';
    'VSS1203':
      PIN_NUMBER='(0,0,0,0,0,0,0,0,0,0,0,0,0,0,0,0,0,0,0,0,0,0,0,0,0,0,0,0,0,0,0,0,DT65,0,0,0,0,0,0,0,0,0)';
      PINUSE='POWER';
      NO_LOAD_CHECK='Both';
      NO_IO_CHECK='Both';
      NO_ASSERT_CHECK='TRUE';
      NO_DIR_CHECK='TRUE';
      ALLOW_CONNECT='TRUE';
    'VSS1202':
      PIN_NUMBER='(0,0,0,0,0,0,0,0,0,0,0,0,0,0,0,0,0,0,0,0,0,0,0,0,0,0,0,0,0,0,0,0,DT57,0,0,0,0,0,0,0,0,0)';
      PINUSE='POWER';
      NO_LOAD_CHECK='Both';
      NO_IO_CHECK='Both';
      NO_ASSERT_CHECK='TRUE';
      NO_DIR_CHECK='TRUE';
      ALLOW_CONNECT='TRUE';
    'VSS1201':
      PIN_NUMBER='(0,0,0,0,0,0,0,0,0,0,0,0,0,0,0,0,0,0,0,0,0,0,0,0,0,0,0,0,0,0,0,0,DT47,0,0,0,0,0,0,0,0,0)';
      PINUSE='POWER';
      NO_LOAD_CHECK='Both';
      NO_IO_CHECK='Both';
      NO_ASSERT_CHECK='TRUE';
      NO_DIR_CHECK='TRUE';
      ALLOW_CONNECT='TRUE';
    'VSS1199':
      PIN_NUMBER='(0,0,0,0,0,0,0,0,0,0,0,0,0,0,0,0,0,0,0,0,0,0,0,0,0,0,0,0,0,0,0,0,DT40,0,0,0,0,0,0,0,0,0)';
      PINUSE='POWER';
      NO_LOAD_CHECK='Both';
      NO_IO_CHECK='Both';
      NO_ASSERT_CHECK='TRUE';
      NO_DIR_CHECK='TRUE';
      ALLOW_CONNECT='TRUE';
    'VSS1196':
      PIN_NUMBER='(0,0,0,0,0,0,0,0,0,0,0,0,0,0,0,0,0,0,0,0,0,0,0,0,0,0,0,0,0,0,0,0,DT38,0,0,0,0,0,0,0,0,0)';
      PINUSE='POWER';
      NO_LOAD_CHECK='Both';
      NO_IO_CHECK='Both';
      NO_ASSERT_CHECK='TRUE';
      NO_DIR_CHECK='TRUE';
      ALLOW_CONNECT='TRUE';
    'VSS1194':
      PIN_NUMBER='(0,0,0,0,0,0,0,0,0,0,0,0,0,0,0,0,0,0,0,0,0,0,0,0,0,0,0,0,0,0,0,0,DT34,0,0,0,0,0,0,0,0,0)';
      PINUSE='POWER';
      NO_LOAD_CHECK='Both';
      NO_IO_CHECK='Both';
      NO_ASSERT_CHECK='TRUE';
      NO_DIR_CHECK='TRUE';
      ALLOW_CONNECT='TRUE';
    'VSS1192':
      PIN_NUMBER='(0,0,0,0,0,0,0,0,0,0,0,0,0,0,0,0,0,0,0,0,0,0,0,0,0,0,0,0,0,0,0,0,DT32,0,0,0,0,0,0,0,0,0)';
      PINUSE='POWER';
      NO_LOAD_CHECK='Both';
      NO_IO_CHECK='Both';
      NO_ASSERT_CHECK='TRUE';
      NO_DIR_CHECK='TRUE';
      ALLOW_CONNECT='TRUE';
    'VSS1191':
      PIN_NUMBER='(0,0,0,0,0,0,0,0,0,0,0,0,0,0,0,0,0,0,0,0,0,0,0,0,0,0,0,0,0,0,0,0,DT28,0,0,0,0,0,0,0,0,0)';
      PINUSE='POWER';
      NO_LOAD_CHECK='Both';
      NO_IO_CHECK='Both';
      NO_ASSERT_CHECK='TRUE';
      NO_DIR_CHECK='TRUE';
      ALLOW_CONNECT='TRUE';
    'VSS1190':
      PIN_NUMBER='(0,0,0,0,0,0,0,0,0,0,0,0,0,0,0,0,0,0,0,0,0,0,0,0,0,0,0,0,0,0,0,0,DT22,0,0,0,0,0,0,0,0,0)';
      PINUSE='POWER';
      NO_LOAD_CHECK='Both';
      NO_IO_CHECK='Both';
      NO_ASSERT_CHECK='TRUE';
      NO_DIR_CHECK='TRUE';
      ALLOW_CONNECT='TRUE';
    'VSS1189':
      PIN_NUMBER='(0,0,0,0,0,0,0,0,0,0,0,0,0,0,0,0,0,0,0,0,0,0,0,0,0,0,0,0,0,0,0,0,DT12,0,0,0,0,0,0,0,0,0)';
      PINUSE='POWER';
      NO_LOAD_CHECK='Both';
      NO_IO_CHECK='Both';
      NO_ASSERT_CHECK='TRUE';
      NO_DIR_CHECK='TRUE';
      ALLOW_CONNECT='TRUE';
    'VSS1187':
      PIN_NUMBER='(0,0,0,0,0,0,0,0,0,0,0,0,0,0,0,0,0,0,0,0,0,0,0,0,0,0,0,0,0,0,0,0,DR9,0,0,0,0,0,0,0,0,0)';
      PINUSE='POWER';
      NO_LOAD_CHECK='Both';
      NO_IO_CHECK='Both';
      NO_ASSERT_CHECK='TRUE';
      NO_DIR_CHECK='TRUE';
      ALLOW_CONNECT='TRUE';
    'VSS1186':
      PIN_NUMBER='(0,0,0,0,0,0,0,0,0,0,0,0,0,0,0,0,0,0,0,0,0,0,0,0,0,0,0,0,0,0,0,0,DR88,0,0,0,0,0,0,0,0,0)';
      PINUSE='POWER';
      NO_LOAD_CHECK='Both';
      NO_IO_CHECK='Both';
      NO_ASSERT_CHECK='TRUE';
      NO_DIR_CHECK='TRUE';
      ALLOW_CONNECT='TRUE';
    'VSS1184':
      PIN_NUMBER='(0,0,0,0,0,0,0,0,0,0,0,0,0,0,0,0,0,0,0,0,0,0,0,0,0,0,0,0,0,0,0,0,DR84,0,0,0,0,0,0,0,0,0)';
      PINUSE='POWER';
      NO_LOAD_CHECK='Both';
      NO_IO_CHECK='Both';
      NO_ASSERT_CHECK='TRUE';
      NO_DIR_CHECK='TRUE';
      ALLOW_CONNECT='TRUE';
    'VSS1183':
      PIN_NUMBER='(0,0,0,0,0,0,0,0,0,0,0,0,0,0,0,0,0,0,0,0,0,0,0,0,0,0,0,0,0,0,0,0,DR78,0,0,0,0,0,0,0,0,0)';
      PINUSE='POWER';
      NO_LOAD_CHECK='Both';
      NO_IO_CHECK='Both';
      NO_ASSERT_CHECK='TRUE';
      NO_DIR_CHECK='TRUE';
      ALLOW_CONNECT='TRUE';
    'VSS1182':
      PIN_NUMBER='(0,0,0,0,0,0,0,0,0,0,0,0,0,0,0,0,0,0,0,0,0,0,0,0,0,0,0,0,0,0,0,0,DR74,0,0,0,0,0,0,0,0,0)';
      PINUSE='POWER';
      NO_LOAD_CHECK='Both';
      NO_IO_CHECK='Both';
      NO_ASSERT_CHECK='TRUE';
      NO_DIR_CHECK='TRUE';
      ALLOW_CONNECT='TRUE';
    'VSS1181':
      PIN_NUMBER='(0,0,0,0,0,0,0,0,0,0,0,0,0,0,0,0,0,0,0,0,0,0,0,0,0,0,0,0,0,0,0,0,DR66,0,0,0,0,0,0,0,0,0)';
      PINUSE='POWER';
      NO_LOAD_CHECK='Both';
      NO_IO_CHECK='Both';
      NO_ASSERT_CHECK='TRUE';
      NO_DIR_CHECK='TRUE';
      ALLOW_CONNECT='TRUE';
    'VSS1179':
      PIN_NUMBER='(0,0,0,0,0,0,0,0,0,0,0,0,0,0,0,0,0,0,0,0,0,0,0,0,0,0,0,0,0,0,0,0,DR56,0,0,0,0,0,0,0,0,0)';
      PINUSE='POWER';
      NO_LOAD_CHECK='Both';
      NO_IO_CHECK='Both';
      NO_ASSERT_CHECK='TRUE';
      NO_DIR_CHECK='TRUE';
      ALLOW_CONNECT='TRUE';
    'VSS1178':
      PIN_NUMBER='(0,0,0,0,0,0,0,0,0,0,0,0,0,0,0,0,0,0,0,0,0,0,0,0,0,0,0,0,0,0,0,0,DR50,0,0,0,0,0,0,0,0,0)';
      PINUSE='POWER';
      NO_LOAD_CHECK='Both';
      NO_IO_CHECK='Both';
      NO_ASSERT_CHECK='TRUE';
      NO_DIR_CHECK='TRUE';
      ALLOW_CONNECT='TRUE';
    'VSS1177':
      PIN_NUMBER='(0,0,0,0,0,0,0,0,0,0,0,0,0,0,0,0,0,0,0,0,0,0,0,0,0,0,0,0,0,0,0,0,DR48,0,0,0,0,0,0,0,0,0)';
      PINUSE='POWER';
      NO_LOAD_CHECK='Both';
      NO_IO_CHECK='Both';
      NO_ASSERT_CHECK='TRUE';
      NO_DIR_CHECK='TRUE';
      ALLOW_CONNECT='TRUE';
    'VSS1176':
      PIN_NUMBER='(0,0,0,0,0,0,0,0,0,0,0,0,0,0,0,0,0,0,0,0,0,0,0,0,0,0,0,0,0,0,0,0,DR43,0,0,0,0,0,0,0,0,0)';
      PINUSE='POWER';
      NO_LOAD_CHECK='Both';
      NO_IO_CHECK='Both';
      NO_ASSERT_CHECK='TRUE';
      NO_DIR_CHECK='TRUE';
      ALLOW_CONNECT='TRUE';
    'VSS1175':
      PIN_NUMBER='(0,0,0,0,0,0,0,0,0,0,0,0,0,0,0,0,0,0,0,0,0,0,0,0,0,0,0,0,0,0,0,0,DR41,0,0,0,0,0,0,0,0,0)';
      PINUSE='POWER';
      NO_LOAD_CHECK='Both';
      NO_IO_CHECK='Both';
      NO_ASSERT_CHECK='TRUE';
      NO_DIR_CHECK='TRUE';
      ALLOW_CONNECT='TRUE';
    'VSS1174':
      PIN_NUMBER='(0,0,0,0,0,0,0,0,0,0,0,0,0,0,0,0,0,0,0,0,0,0,0,0,0,0,0,0,0,0,0,0,DR37,0,0,0,0,0,0,0,0,0)';
      PINUSE='POWER';
      NO_LOAD_CHECK='Both';
      NO_IO_CHECK='Both';
      NO_ASSERT_CHECK='TRUE';
      NO_DIR_CHECK='TRUE';
      ALLOW_CONNECT='TRUE';
    'VSS1173':
      PIN_NUMBER='(0,0,0,0,0,0,0,0,0,0,0,0,0,0,0,0,0,0,0,0,0,0,0,0,0,0,0,0,0,0,0,0,DR31,0,0,0,0,0,0,0,0,0)';
      PINUSE='POWER';
      NO_LOAD_CHECK='Both';
      NO_IO_CHECK='Both';
      NO_ASSERT_CHECK='TRUE';
      NO_DIR_CHECK='TRUE';
      ALLOW_CONNECT='TRUE';
    'VSS1172':
      PIN_NUMBER='(0,0,0,0,0,0,0,0,0,0,0,0,0,0,0,0,0,0,0,0,0,0,0,0,0,0,0,0,0,0,0,0,DR29,0,0,0,0,0,0,0,0,0)';
      PINUSE='POWER';
      NO_LOAD_CHECK='Both';
      NO_IO_CHECK='Both';
      NO_ASSERT_CHECK='TRUE';
      NO_DIR_CHECK='TRUE';
      ALLOW_CONNECT='TRUE';
    'VSS1169':
      PIN_NUMBER='(0,0,0,0,0,0,0,0,0,0,0,0,0,0,0,0,0,0,0,0,0,0,0,0,0,0,0,0,0,0,0,0,DR23,0,0,0,0,0,0,0,0,0)';
      PINUSE='POWER';
      NO_LOAD_CHECK='Both';
      NO_IO_CHECK='Both';
      NO_ASSERT_CHECK='TRUE';
      NO_DIR_CHECK='TRUE';
      ALLOW_CONNECT='TRUE';
    'VSS1166':
      PIN_NUMBER='(0,0,0,0,0,0,0,0,0,0,0,0,0,0,0,0,0,0,0,0,0,0,0,0,0,0,0,0,0,0,0,0,DR19,0,0,0,0,0,0,0,0,0)';
      PINUSE='POWER';
      NO_LOAD_CHECK='Both';
      NO_IO_CHECK='Both';
      NO_ASSERT_CHECK='TRUE';
      NO_DIR_CHECK='TRUE';
      ALLOW_CONNECT='TRUE';
    'VSS1164':
      PIN_NUMBER='(0,0,0,0,0,0,0,0,0,0,0,0,0,0,0,0,0,0,0,0,0,0,0,0,0,0,0,0,0,0,0,0,DR13,0,0,0,0,0,0,0,0,0)';
      PINUSE='POWER';
      NO_LOAD_CHECK='Both';
      NO_IO_CHECK='Both';
      NO_ASSERT_CHECK='TRUE';
      NO_DIR_CHECK='TRUE';
      ALLOW_CONNECT='TRUE';
    'VSS1162':
      PIN_NUMBER='(0,0,0,0,0,0,0,0,0,0,0,0,0,0,0,0,0,0,0,0,0,0,0,0,0,0,0,0,0,0,0,0,DR1,0,0,0,0,0,0,0,0,0)';
      PINUSE='POWER';
      NO_LOAD_CHECK='Both';
      NO_IO_CHECK='Both';
      NO_ASSERT_CHECK='TRUE';
      NO_DIR_CHECK='TRUE';
      ALLOW_CONNECT='TRUE';
    'VSS1160':
      PIN_NUMBER='(0,0,0,0,0,0,0,0,0,0,0,0,0,0,0,0,0,0,0,0,0,0,0,0,0,0,0,0,0,0,0,0,DP87,0,0,0,0,0,0,0,0,0)';
      PINUSE='POWER';
      NO_LOAD_CHECK='Both';
      NO_IO_CHECK='Both';
      NO_ASSERT_CHECK='TRUE';
      NO_DIR_CHECK='TRUE';
      ALLOW_CONNECT='TRUE';
    'VSS1159':
      PIN_NUMBER='(0,0,0,0,0,0,0,0,0,0,0,0,0,0,0,0,0,0,0,0,0,0,0,0,0,0,0,0,0,0,0,0,DP81,0,0,0,0,0,0,0,0,0)';
      PINUSE='POWER';
      NO_LOAD_CHECK='Both';
      NO_IO_CHECK='Both';
      NO_ASSERT_CHECK='TRUE';
      NO_DIR_CHECK='TRUE';
      ALLOW_CONNECT='TRUE';
    'VSS1157':
      PIN_NUMBER='(0,0,0,0,0,0,0,0,0,0,0,0,0,0,0,0,0,0,0,0,0,0,0,0,0,0,0,0,0,0,0,0,DP8,0,0,0,0,0,0,0,0,0)';
      PINUSE='POWER';
      NO_LOAD_CHECK='Both';
      NO_IO_CHECK='Both';
      NO_ASSERT_CHECK='TRUE';
      NO_DIR_CHECK='TRUE';
      ALLOW_CONNECT='TRUE';
    'VSS1154':
      PIN_NUMBER='(0,0,0,0,0,0,0,0,0,0,0,0,0,0,0,0,0,0,0,0,0,0,0,0,0,0,0,0,0,0,0,0,DP73,0,0,0,0,0,0,0,0,0)';
      PINUSE='POWER';
      NO_LOAD_CHECK='Both';
      NO_IO_CHECK='Both';
      NO_ASSERT_CHECK='TRUE';
      NO_DIR_CHECK='TRUE';
      ALLOW_CONNECT='TRUE';
    'VSS1153':
      PIN_NUMBER='(0,0,0,0,0,0,0,0,0,0,0,0,0,0,0,0,0,0,0,0,0,0,0,0,0,0,0,0,0,0,0,0,DP49,0,0,0,0,0,0,0,0,0)';
      PINUSE='POWER';
      NO_LOAD_CHECK='Both';
      NO_IO_CHECK='Both';
      NO_ASSERT_CHECK='TRUE';
      NO_DIR_CHECK='TRUE';
      ALLOW_CONNECT='TRUE';
    'VSS1152':
      PIN_NUMBER='(0,0,0,0,0,0,0,0,0,0,0,0,0,0,0,0,0,0,0,0,0,0,0,0,0,0,0,0,0,0,0,0,DP4,0,0,0,0,0,0,0,0,0)';
      PINUSE='POWER';
      NO_LOAD_CHECK='Both';
      NO_IO_CHECK='Both';
      NO_ASSERT_CHECK='TRUE';
      NO_DIR_CHECK='TRUE';
      ALLOW_CONNECT='TRUE';
    'VSS1151':
      PIN_NUMBER='(0,0,0,0,0,0,0,0,0,0,0,0,0,0,0,0,0,0,0,0,0,0,0,0,0,0,0,0,0,0,0,0,DP36,0,0,0,0,0,0,0,0,0)';
      PINUSE='POWER';
      NO_LOAD_CHECK='Both';
      NO_IO_CHECK='Both';
      NO_ASSERT_CHECK='TRUE';
      NO_DIR_CHECK='TRUE';
      ALLOW_CONNECT='TRUE';
    'VSS1150':
      PIN_NUMBER='(0,0,0,0,0,0,0,0,0,0,0,0,0,0,0,0,0,0,0,0,0,0,0,0,0,0,0,0,0,0,0,0,DP30,0,0,0,0,0,0,0,0,0)';
      PINUSE='POWER';
      NO_LOAD_CHECK='Both';
      NO_IO_CHECK='Both';
      NO_ASSERT_CHECK='TRUE';
      NO_DIR_CHECK='TRUE';
      ALLOW_CONNECT='TRUE';
    'VSS1149':
      PIN_NUMBER='(0,0,0,0,0,0,0,0,0,0,0,0,0,0,0,0,0,0,0,0,0,0,0,0,0,0,0,0,0,0,0,0,DP16,0,0,0,0,0,0,0,0,0)';
      PINUSE='POWER';
      NO_LOAD_CHECK='Both';
      NO_IO_CHECK='Both';
      NO_ASSERT_CHECK='TRUE';
      NO_DIR_CHECK='TRUE';
      ALLOW_CONNECT='TRUE';
    'VSS1148':
      PIN_NUMBER='(0,0,0,0,0,0,0,0,0,0,0,0,0,0,0,0,0,0,0,0,0,0,0,0,0,0,0,0,0,0,0,0,DN88,0,0,0,0,0,0,0,0,0)';
      PINUSE='POWER';
      NO_LOAD_CHECK='Both';
      NO_IO_CHECK='Both';
      NO_ASSERT_CHECK='TRUE';
      NO_DIR_CHECK='TRUE';
      ALLOW_CONNECT='TRUE';
    'VSS1147':
      PIN_NUMBER='(0,0,0,0,0,0,0,0,0,0,0,0,0,0,0,0,0,0,0,0,0,0,0,0,0,0,0,0,0,0,0,0,DN84,0,0,0,0,0,0,0,0,0)';
      PINUSE='POWER';
      NO_LOAD_CHECK='Both';
      NO_IO_CHECK='Both';
      NO_ASSERT_CHECK='TRUE';
      NO_DIR_CHECK='TRUE';
      ALLOW_CONNECT='TRUE';
    'VSS1143':
      PIN_NUMBER='(0,0,0,0,0,0,0,0,0,0,0,0,0,0,0,0,0,0,0,0,0,0,0,0,0,0,0,0,0,0,0,0,DN78,0,0,0,0,0,0,0,0,0)';
      PINUSE='POWER';
      NO_LOAD_CHECK='Both';
      NO_IO_CHECK='Both';
      NO_ASSERT_CHECK='TRUE';
      NO_DIR_CHECK='TRUE';
      ALLOW_CONNECT='TRUE';
    'VSS1140':
      PIN_NUMBER='(0,0,0,0,0,0,0,0,0,0,0,0,0,0,0,0,0,0,0,0,0,0,0,0,0,0,0,0,0,0,0,0,DM8,0,0,0,0,0,0,0,0,0)';
      PINUSE='POWER';
      NO_LOAD_CHECK='Both';
      NO_IO_CHECK='Both';
      NO_ASSERT_CHECK='TRUE';
      NO_DIR_CHECK='TRUE';
      ALLOW_CONNECT='TRUE';
    'VSS1139':
      PIN_NUMBER='(0,0,0,0,0,0,0,0,0,0,0,0,0,0,0,0,0,0,0,0,0,0,0,0,0,0,0,0,0,0,0,0,DM79,0,0,0,0,0,0,0,0,0)';
      PINUSE='POWER';
      NO_LOAD_CHECK='Both';
      NO_IO_CHECK='Both';
      NO_ASSERT_CHECK='TRUE';
      NO_DIR_CHECK='TRUE';
      ALLOW_CONNECT='TRUE';
    'VSS1138':
      PIN_NUMBER='(0,0,0,0,0,0,0,0,0,0,0,0,0,0,0,0,0,0,0,0,0,0,0,0,0,0,0,0,0,0,0,0,DM77,0,0,0,0,0,0,0,0,0)';
      PINUSE='POWER';
      NO_LOAD_CHECK='Both';
      NO_IO_CHECK='Both';
      NO_ASSERT_CHECK='TRUE';
      NO_DIR_CHECK='TRUE';
      ALLOW_CONNECT='TRUE';
    'VSS1137':
      PIN_NUMBER='(0,0,0,0,0,0,0,0,0,0,0,0,0,0,0,0,0,0,0,0,0,0,0,0,0,0,0,0,0,0,0,0,DM75,0,0,0,0,0,0,0,0,0)';
      PINUSE='POWER';
      NO_LOAD_CHECK='Both';
      NO_IO_CHECK='Both';
      NO_ASSERT_CHECK='TRUE';
      NO_DIR_CHECK='TRUE';
      ALLOW_CONNECT='TRUE';
    'VSS1136':
      PIN_NUMBER='(0,0,0,0,0,0,0,0,0,0,0,0,0,0,0,0,0,0,0,0,0,0,0,0,0,0,0,0,0,0,0,0,DM71,0,0,0,0,0,0,0,0,0)';
      PINUSE='POWER';
      NO_LOAD_CHECK='Both';
      NO_IO_CHECK='Both';
      NO_ASSERT_CHECK='TRUE';
      NO_DIR_CHECK='TRUE';
      ALLOW_CONNECT='TRUE';
    'VSS1135':
      PIN_NUMBER='(0,0,0,0,0,0,0,0,0,0,0,0,0,0,0,0,0,0,0,0,0,0,0,0,0,0,0,0,0,0,0,0,DM69,0,0,0,0,0,0,0,0,0)';
      PINUSE='POWER';
      NO_LOAD_CHECK='Both';
      NO_IO_CHECK='Both';
      NO_ASSERT_CHECK='TRUE';
      NO_DIR_CHECK='TRUE';
      ALLOW_CONNECT='TRUE';
    'VSS1134':
      PIN_NUMBER='(0,0,0,0,0,0,0,0,0,0,0,0,0,0,0,0,0,0,0,0,0,0,0,0,0,0,0,0,0,0,0,0,DM67,0,0,0,0,0,0,0,0,0)';
      PINUSE='POWER';
      NO_LOAD_CHECK='Both';
      NO_IO_CHECK='Both';
      NO_ASSERT_CHECK='TRUE';
      NO_DIR_CHECK='TRUE';
      ALLOW_CONNECT='TRUE';
    'VSS1133':
      PIN_NUMBER='(0,0,0,0,0,0,0,0,0,0,0,0,0,0,0,0,0,0,0,0,0,0,0,0,0,0,0,0,0,0,0,0,DM65,0,0,0,0,0,0,0,0,0)';
      PINUSE='POWER';
      NO_LOAD_CHECK='Both';
      NO_IO_CHECK='Both';
      NO_ASSERT_CHECK='TRUE';
      NO_DIR_CHECK='TRUE';
      ALLOW_CONNECT='TRUE';
    'VSS1132':
      PIN_NUMBER='(0,0,0,0,0,0,0,0,0,0,0,0,0,0,0,0,0,0,0,0,0,0,0,0,0,0,0,0,0,0,0,0,DM63,0,0,0,0,0,0,0,0,0)';
      PINUSE='POWER';
      NO_LOAD_CHECK='Both';
      NO_IO_CHECK='Both';
      NO_ASSERT_CHECK='TRUE';
      NO_DIR_CHECK='TRUE';
      ALLOW_CONNECT='TRUE';
    'VSS1130':
      PIN_NUMBER='(0,0,0,0,0,0,0,0,0,0,0,0,0,0,0,0,0,0,0,0,0,0,0,0,0,0,0,0,0,0,0,0,DM61,0,0,0,0,0,0,0,0,0)';
      PINUSE='POWER';
      NO_LOAD_CHECK='Both';
      NO_IO_CHECK='Both';
      NO_ASSERT_CHECK='TRUE';
      NO_DIR_CHECK='TRUE';
      ALLOW_CONNECT='TRUE';
    'VSS1128':
      PIN_NUMBER='(0,0,0,0,0,0,0,0,0,0,0,0,0,0,0,0,0,0,0,0,0,0,0,0,0,0,0,0,0,0,0,0,DM59,0,0,0,0,0,0,0,0,0)';
      PINUSE='POWER';
      NO_LOAD_CHECK='Both';
      NO_IO_CHECK='Both';
      NO_ASSERT_CHECK='TRUE';
      NO_DIR_CHECK='TRUE';
      ALLOW_CONNECT='TRUE';
    'VSS1127':
      PIN_NUMBER='(0,0,0,0,0,0,0,0,0,0,0,0,0,0,0,0,0,0,0,0,0,0,0,0,0,0,0,0,0,0,0,0,DM57,0,0,0,0,0,0,0,0,0)';
      PINUSE='POWER';
      NO_LOAD_CHECK='Both';
      NO_IO_CHECK='Both';
      NO_ASSERT_CHECK='TRUE';
      NO_DIR_CHECK='TRUE';
      ALLOW_CONNECT='TRUE';
    'VSS1124':
      PIN_NUMBER='(0,0,0,0,0,0,0,0,0,0,0,0,0,0,0,0,0,0,0,0,0,0,0,0,0,0,0,0,0,0,0,0,DM55,0,0,0,0,0,0,0,0,0)';
      PINUSE='POWER';
      NO_LOAD_CHECK='Both';
      NO_IO_CHECK='Both';
      NO_ASSERT_CHECK='TRUE';
      NO_DIR_CHECK='TRUE';
      ALLOW_CONNECT='TRUE';
    'VSS1123':
      PIN_NUMBER='(0,0,0,0,0,0,0,0,0,0,0,0,0,0,0,0,0,0,0,0,0,0,0,0,0,0,0,0,0,0,0,0,DM53,0,0,0,0,0,0,0,0,0)';
      PINUSE='POWER';
      NO_LOAD_CHECK='Both';
      NO_IO_CHECK='Both';
      NO_ASSERT_CHECK='TRUE';
      NO_DIR_CHECK='TRUE';
      ALLOW_CONNECT='TRUE';
    'VSS1122':
      PIN_NUMBER='(0,0,0,0,0,0,0,0,0,0,0,0,0,0,0,0,0,0,0,0,0,0,0,0,0,0,0,0,0,0,0,0,DM49,0,0,0,0,0,0,0,0,0)';
      PINUSE='POWER';
      NO_LOAD_CHECK='Both';
      NO_IO_CHECK='Both';
      NO_ASSERT_CHECK='TRUE';
      NO_DIR_CHECK='TRUE';
      ALLOW_CONNECT='TRUE';
    'VSS1121':
      PIN_NUMBER='(0,0,0,0,0,0,0,0,0,0,0,0,0,0,0,0,0,0,0,0,0,0,0,0,0,0,0,0,0,0,0,0,DM47,0,0,0,0,0,0,0,0,0)';
      PINUSE='POWER';
      NO_LOAD_CHECK='Both';
      NO_IO_CHECK='Both';
      NO_ASSERT_CHECK='TRUE';
      NO_DIR_CHECK='TRUE';
      ALLOW_CONNECT='TRUE';
    'VSS1120':
      PIN_NUMBER='(0,0,0,0,0,0,0,0,0,0,0,0,0,0,0,0,0,0,0,0,0,0,0,0,0,0,0,0,0,0,0,0,DM44,0,0,0,0,0,0,0,0,0)';
      PINUSE='POWER';
      NO_LOAD_CHECK='Both';
      NO_IO_CHECK='Both';
      NO_ASSERT_CHECK='TRUE';
      NO_DIR_CHECK='TRUE';
      ALLOW_CONNECT='TRUE';
    'VSS1119':
      PIN_NUMBER='(0,0,0,0,0,0,0,0,0,0,0,0,0,0,0,0,0,0,0,0,0,0,0,0,0,0,0,0,0,0,0,0,DM42,0,0,0,0,0,0,0,0,0)';
      PINUSE='POWER';
      NO_LOAD_CHECK='Both';
      NO_IO_CHECK='Both';
      NO_ASSERT_CHECK='TRUE';
      NO_DIR_CHECK='TRUE';
      ALLOW_CONNECT='TRUE';
    'VSS1118':
      PIN_NUMBER='(0,0,0,0,0,0,0,0,0,0,0,0,0,0,0,0,0,0,0,0,0,0,0,0,0,0,0,0,0,0,0,0,DM40,0,0,0,0,0,0,0,0,0)';
      PINUSE='POWER';
      NO_LOAD_CHECK='Both';
      NO_IO_CHECK='Both';
      NO_ASSERT_CHECK='TRUE';
      NO_DIR_CHECK='TRUE';
      ALLOW_CONNECT='TRUE';
    'VSS1117':
      PIN_NUMBER='(0,0,0,0,0,0,0,0,0,0,0,0,0,0,0,0,0,0,0,0,0,0,0,0,0,0,0,0,0,0,0,0,DM4,0,0,0,0,0,0,0,0,0)';
      PINUSE='POWER';
      NO_LOAD_CHECK='Both';
      NO_IO_CHECK='Both';
      NO_ASSERT_CHECK='TRUE';
      NO_DIR_CHECK='TRUE';
      ALLOW_CONNECT='TRUE';
    'VSS1114':
      PIN_NUMBER='(0,0,0,0,0,0,0,0,0,0,0,0,0,0,0,0,0,0,0,0,0,0,0,0,0,0,0,0,0,0,0,0,DM38,0,0,0,0,0,0,0,0,0)';
      PINUSE='POWER';
      NO_LOAD_CHECK='Both';
      NO_IO_CHECK='Both';
      NO_ASSERT_CHECK='TRUE';
      NO_DIR_CHECK='TRUE';
      ALLOW_CONNECT='TRUE';
    'VSS1113':
      PIN_NUMBER='(0,0,0,0,0,0,0,0,0,0,0,0,0,0,0,0,0,0,0,0,0,0,0,0,0,0,0,0,0,0,0,0,DM36,0,0,0,0,0,0,0,0,0)';
      PINUSE='POWER';
      NO_LOAD_CHECK='Both';
      NO_IO_CHECK='Both';
      NO_ASSERT_CHECK='TRUE';
      NO_DIR_CHECK='TRUE';
      ALLOW_CONNECT='TRUE';
    'VSS1110':
      PIN_NUMBER='(0,0,0,0,0,0,0,0,0,0,0,0,0,0,0,0,0,0,0,0,0,0,0,0,0,0,0,0,0,0,0,0,DM34,0,0,0,0,0,0,0,0,0)';
      PINUSE='POWER';
      NO_LOAD_CHECK='Both';
      NO_IO_CHECK='Both';
      NO_ASSERT_CHECK='TRUE';
      NO_DIR_CHECK='TRUE';
      ALLOW_CONNECT='TRUE';
    'VSS1109':
      PIN_NUMBER='(0,0,0,0,0,0,0,0,0,0,0,0,0,0,0,0,0,0,0,0,0,0,0,0,0,0,0,0,0,0,0,0,DM32,0,0,0,0,0,0,0,0,0)';
      PINUSE='POWER';
      NO_LOAD_CHECK='Both';
      NO_IO_CHECK='Both';
      NO_ASSERT_CHECK='TRUE';
      NO_DIR_CHECK='TRUE';
      ALLOW_CONNECT='TRUE';
    'VSS1108':
      PIN_NUMBER='(0,0,0,0,0,0,0,0,0,0,0,0,0,0,0,0,0,0,0,0,0,0,0,0,0,0,0,0,0,0,0,0,DM30,0,0,0,0,0,0,0,0,0)';
      PINUSE='POWER';
      NO_LOAD_CHECK='Both';
      NO_IO_CHECK='Both';
      NO_ASSERT_CHECK='TRUE';
      NO_DIR_CHECK='TRUE';
      ALLOW_CONNECT='TRUE';
    'VSS1107':
      PIN_NUMBER='(0,0,0,0,0,0,0,0,0,0,0,0,0,0,0,0,0,0,0,0,0,0,0,0,0,0,0,0,0,0,0,0,DM28,0,0,0,0,0,0,0,0,0)';
      PINUSE='POWER';
      NO_LOAD_CHECK='Both';
      NO_IO_CHECK='Both';
      NO_ASSERT_CHECK='TRUE';
      NO_DIR_CHECK='TRUE';
      ALLOW_CONNECT='TRUE';
    'VSS1106':
      PIN_NUMBER='(0,0,0,0,0,0,0,0,0,0,0,0,0,0,0,0,0,0,0,0,0,0,0,0,0,0,0,0,0,0,0,0,DM26,0,0,0,0,0,0,0,0,0)';
      PINUSE='POWER';
      NO_LOAD_CHECK='Both';
      NO_IO_CHECK='Both';
      NO_ASSERT_CHECK='TRUE';
      NO_DIR_CHECK='TRUE';
      ALLOW_CONNECT='TRUE';
    'VSS1105':
      PIN_NUMBER='(0,0,0,0,0,0,0,0,0,0,0,0,0,0,0,0,0,0,0,0,0,0,0,0,0,0,0,0,0,0,0,0,DM24,0,0,0,0,0,0,0,0,0)';
      PINUSE='POWER';
      NO_LOAD_CHECK='Both';
      NO_IO_CHECK='Both';
      NO_ASSERT_CHECK='TRUE';
      NO_DIR_CHECK='TRUE';
      ALLOW_CONNECT='TRUE';
    'VSS1104':
      PIN_NUMBER='(0,0,0,0,0,0,0,0,0,0,0,0,0,0,0,0,0,0,0,0,0,0,0,0,0,0,0,0,0,0,0,0,DM22,0,0,0,0,0,0,0,0,0)';
      PINUSE='POWER';
      NO_LOAD_CHECK='Both';
      NO_IO_CHECK='Both';
      NO_ASSERT_CHECK='TRUE';
      NO_DIR_CHECK='TRUE';
      ALLOW_CONNECT='TRUE';
    'VSS1103':
      PIN_NUMBER='(0,0,0,0,0,0,0,0,0,0,0,0,0,0,0,0,0,0,0,0,0,0,0,0,0,0,0,0,0,0,0,0,DM20,0,0,0,0,0,0,0,0,0)';
      PINUSE='POWER';
      NO_LOAD_CHECK='Both';
      NO_IO_CHECK='Both';
      NO_ASSERT_CHECK='TRUE';
      NO_DIR_CHECK='TRUE';
      ALLOW_CONNECT='TRUE';
    'VSS1102':
      PIN_NUMBER='(0,0,0,0,0,0,0,0,0,0,0,0,0,0,0,0,0,0,0,0,0,0,0,0,0,0,0,0,0,0,0,0,DM18,0,0,0,0,0,0,0,0,0)';
      PINUSE='POWER';
      NO_LOAD_CHECK='Both';
      NO_IO_CHECK='Both';
      NO_ASSERT_CHECK='TRUE';
      NO_DIR_CHECK='TRUE';
      ALLOW_CONNECT='TRUE';
    'VSS1101':
      PIN_NUMBER='(0,0,0,0,0,0,0,0,0,0,0,0,0,0,0,0,0,0,0,0,0,0,0,0,0,0,0,0,0,0,0,0,DM16,0,0,0,0,0,0,0,0,0)';
      PINUSE='POWER';
      NO_LOAD_CHECK='Both';
      NO_IO_CHECK='Both';
      NO_ASSERT_CHECK='TRUE';
      NO_DIR_CHECK='TRUE';
      ALLOW_CONNECT='TRUE';
    'VSS1100':
      PIN_NUMBER='(0,0,0,0,0,0,0,0,0,0,0,0,0,0,0,0,0,0,0,0,0,0,0,0,0,0,0,0,0,0,0,0,DM12,0,0,0,0,0,0,0,0,0)';
      PINUSE='POWER';
      NO_LOAD_CHECK='Both';
      NO_IO_CHECK='Both';
      NO_ASSERT_CHECK='TRUE';
      NO_DIR_CHECK='TRUE';
      ALLOW_CONNECT='TRUE';
    'VSS1097':
      PIN_NUMBER='(0,0,0,0,0,0,0,0,0,0,0,0,0,0,0,0,0,0,0,0,0,0,0,0,0,0,0,0,0,0,0,0,DW60,0,0,0,0,0,0,0,0,0)';
      PINUSE='POWER';
      NO_LOAD_CHECK='Both';
      NO_IO_CHECK='Both';
      NO_ASSERT_CHECK='TRUE';
      NO_DIR_CHECK='TRUE';
      ALLOW_CONNECT='TRUE';
    'VSS1077':
      PIN_NUMBER='(0,0,0,0,0,0,0,0,0,0,0,0,0,0,0,0,0,0,0,0,0,0,0,0,0,0,0,0,0,0,0,0,DW21,0,0,0,0,0,0,0,0,0)';
      PINUSE='POWER';
      NO_LOAD_CHECK='Both';
      NO_IO_CHECK='Both';
      NO_ASSERT_CHECK='TRUE';
      NO_DIR_CHECK='TRUE';
      ALLOW_CONNECT='TRUE';
    'VSS1064':
      PIN_NUMBER='(0,0,0,0,0,0,0,0,0,0,0,0,0,0,0,0,0,0,0,0,0,0,0,0,0,0,0,0,0,0,0,0,DV42,0,0,0,0,0,0,0,0,0)';
      PINUSE='POWER';
      NO_LOAD_CHECK='Both';
      NO_IO_CHECK='Both';
      NO_ASSERT_CHECK='TRUE';
      NO_DIR_CHECK='TRUE';
      ALLOW_CONNECT='TRUE';
    'VSS1063':
      PIN_NUMBER='(0,0,0,0,0,0,0,0,0,0,0,0,0,0,0,0,0,0,0,0,0,0,0,0,0,0,0,0,0,0,0,0,DV4,0,0,0,0,0,0,0,0,0)';
      PINUSE='POWER';
      NO_LOAD_CHECK='Both';
      NO_IO_CHECK='Both';
      NO_ASSERT_CHECK='TRUE';
      NO_DIR_CHECK='TRUE';
      ALLOW_CONNECT='TRUE';
    'VSS1060':
      PIN_NUMBER='(0,0,0,0,0,0,0,0,0,0,0,0,0,0,0,0,0,0,0,0,0,0,0,0,0,0,0,0,0,0,0,0,DV16,0,0,0,0,0,0,0,0,0)';
      PINUSE='POWER';
      NO_LOAD_CHECK='Both';
      NO_IO_CHECK='Both';
      NO_ASSERT_CHECK='TRUE';
      NO_DIR_CHECK='TRUE';
      ALLOW_CONNECT='TRUE';
    'VSS1059':
      PIN_NUMBER='(0,0,0,0,0,0,0,0,0,0,0,0,0,0,0,0,0,0,0,0,0,0,0,0,0,0,0,0,0,0,0,0,DV12,0,0,0,0,0,0,0,0,0)';
      PINUSE='POWER';
      NO_LOAD_CHECK='Both';
      NO_IO_CHECK='Both';
      NO_ASSERT_CHECK='TRUE';
      NO_DIR_CHECK='TRUE';
      ALLOW_CONNECT='TRUE';
    'VSS1054':
      PIN_NUMBER='(0,0,0,0,0,0,0,0,0,0,0,0,0,0,0,0,0,0,0,0,0,0,0,0,0,0,0,0,0,0,0,0,DU70,0,0,0,0,0,0,0,0,0)';
      PINUSE='POWER';
      NO_LOAD_CHECK='Both';
      NO_IO_CHECK='Both';
      NO_ASSERT_CHECK='TRUE';
      NO_DIR_CHECK='TRUE';
      ALLOW_CONNECT='TRUE';
    'VSS1052':
      PIN_NUMBER='(0,0,0,0,0,0,0,0,0,0,0,0,0,0,0,0,0,0,0,0,0,0,0,0,0,0,0,0,0,0,0,0,DU64,0,0,0,0,0,0,0,0,0)';
      PINUSE='POWER';
      NO_LOAD_CHECK='Both';
      NO_IO_CHECK='Both';
      NO_ASSERT_CHECK='TRUE';
      NO_DIR_CHECK='TRUE';
      ALLOW_CONNECT='TRUE';
    'VSS1051':
      PIN_NUMBER='(0,0,0,0,0,0,0,0,0,0,0,0,0,0,0,0,0,0,0,0,0,0,0,0,0,0,0,0,0,0,0,0,DU58,0,0,0,0,0,0,0,0,0)';
      PINUSE='POWER';
      NO_LOAD_CHECK='Both';
      NO_IO_CHECK='Both';
      NO_ASSERT_CHECK='TRUE';
      NO_DIR_CHECK='TRUE';
      ALLOW_CONNECT='TRUE';
    'VSS1050':
      PIN_NUMBER='(0,0,0,0,0,0,0,0,0,0,0,0,0,0,0,0,0,0,0,0,0,0,0,0,0,0,0,0,0,0,0,0,DU52,0,0,0,0,0,0,0,0,0)';
      PINUSE='POWER';
      NO_LOAD_CHECK='Both';
      NO_IO_CHECK='Both';
      NO_ASSERT_CHECK='TRUE';
      NO_DIR_CHECK='TRUE';
      ALLOW_CONNECT='TRUE';
    'VSS1048':
      PIN_NUMBER='(0,0,0,0,0,0,0,0,0,0,0,0,0,0,0,0,0,0,0,0,0,0,0,0,0,0,0,0,0,0,0,0,DU45,0,0,0,0,0,0,0,0,0)';
      PINUSE='POWER';
      NO_LOAD_CHECK='Both';
      NO_IO_CHECK='Both';
      NO_ASSERT_CHECK='TRUE';
      NO_DIR_CHECK='TRUE';
      ALLOW_CONNECT='TRUE';
    'VSS1047':
      PIN_NUMBER='(0,0,0,0,0,0,0,0,0,0,0,0,0,0,0,0,0,0,0,0,0,0,0,0,0,0,0,0,0,0,0,0,DU39,0,0,0,0,0,0,0,0,0)';
      PINUSE='POWER';
      NO_LOAD_CHECK='Both';
      NO_IO_CHECK='Both';
      NO_ASSERT_CHECK='TRUE';
      NO_DIR_CHECK='TRUE';
      ALLOW_CONNECT='TRUE';
    'VSS1036':
      PIN_NUMBER='(0,0,0,0,0,0,0,0,0,0,0,0,0,0,0,0,0,0,0,0,0,0,0,0,0,0,0,0,0,0,0,0,DT83,0,0,0,0,0,0,0,0,0)';
      PINUSE='POWER';
      NO_LOAD_CHECK='Both';
      NO_IO_CHECK='Both';
      NO_ASSERT_CHECK='TRUE';
      NO_DIR_CHECK='TRUE';
      ALLOW_CONNECT='TRUE';
    'VSS1029':
      PIN_NUMBER='(0,0,0,0,0,0,0,0,0,0,0,0,0,0,0,0,0,0,0,0,0,0,0,0,0,0,0,0,0,0,0,0,DT63,0,0,0,0,0,0,0,0,0)';
      PINUSE='POWER';
      NO_LOAD_CHECK='Both';
      NO_IO_CHECK='Both';
      NO_ASSERT_CHECK='TRUE';
      NO_DIR_CHECK='TRUE';
      ALLOW_CONNECT='TRUE';
    'VSS1028':
      PIN_NUMBER='(0,0,0,0,0,0,0,0,0,0,0,0,0,0,0,0,0,0,0,0,0,0,0,0,0,0,0,0,0,0,0,0,DT59,0,0,0,0,0,0,0,0,0)';
      PINUSE='POWER';
      NO_LOAD_CHECK='Both';
      NO_IO_CHECK='Both';
      NO_ASSERT_CHECK='TRUE';
      NO_DIR_CHECK='TRUE';
      ALLOW_CONNECT='TRUE';
    'VSS1026':
      PIN_NUMBER='(0,0,0,0,0,0,0,0,0,0,0,0,0,0,0,0,0,0,0,0,0,0,0,0,0,0,0,0,0,0,0,0,DT53,0,0,0,0,0,0,0,0,0)';
      PINUSE='POWER';
      NO_LOAD_CHECK='Both';
      NO_IO_CHECK='Both';
      NO_ASSERT_CHECK='TRUE';
      NO_DIR_CHECK='TRUE';
      ALLOW_CONNECT='TRUE';
    'VSS1025':
      PIN_NUMBER='(0,0,0,0,0,0,0,0,0,0,0,0,0,0,0,0,0,0,0,0,0,0,0,0,0,0,0,0,0,0,0,0,DT51,0,0,0,0,0,0,0,0,0)';
      PINUSE='POWER';
      NO_LOAD_CHECK='Both';
      NO_IO_CHECK='Both';
      NO_ASSERT_CHECK='TRUE';
      NO_DIR_CHECK='TRUE';
      ALLOW_CONNECT='TRUE';
    'VSS1023':
      PIN_NUMBER='(0,0,0,0,0,0,0,0,0,0,0,0,0,0,0,0,0,0,0,0,0,0,0,0,0,0,0,0,0,0,0,0,DT44,0,0,0,0,0,0,0,0,0)';
      PINUSE='POWER';
      NO_LOAD_CHECK='Both';
      NO_IO_CHECK='Both';
      NO_ASSERT_CHECK='TRUE';
      NO_DIR_CHECK='TRUE';
      ALLOW_CONNECT='TRUE';
    'VSS1021':
      PIN_NUMBER='(0,0,0,0,0,0,0,0,0,0,0,0,0,0,0,0,0,0,0,0,0,0,0,0,0,0,0,0,0,0,0,0,DT4,0,0,0,0,0,0,0,0,0)';
      PINUSE='POWER';
      NO_LOAD_CHECK='Both';
      NO_IO_CHECK='Both';
      NO_ASSERT_CHECK='TRUE';
      NO_DIR_CHECK='TRUE';
      ALLOW_CONNECT='TRUE';
    'VSS1016':
      PIN_NUMBER='(0,0,0,0,0,0,0,0,0,0,0,0,0,0,0,0,0,0,0,0,0,0,0,0,0,0,0,0,0,0,0,0,DT26,0,0,0,0,0,0,0,0,0)';
      PINUSE='POWER';
      NO_LOAD_CHECK='Both';
      NO_IO_CHECK='Both';
      NO_ASSERT_CHECK='TRUE';
      NO_DIR_CHECK='TRUE';
      ALLOW_CONNECT='TRUE';
    'VSS1014':
      PIN_NUMBER='(0,0,0,0,0,0,0,0,0,0,0,0,0,0,0,0,0,0,0,0,0,0,0,0,0,0,0,0,0,0,0,0,DT20,0,0,0,0,0,0,0,0,0)';
      PINUSE='POWER';
      NO_LOAD_CHECK='Both';
      NO_IO_CHECK='Both';
      NO_ASSERT_CHECK='TRUE';
      NO_DIR_CHECK='TRUE';
      ALLOW_CONNECT='TRUE';
    'VSS1013':
      PIN_NUMBER='(0,0,0,0,0,0,0,0,0,0,0,0,0,0,0,0,0,0,0,0,0,0,0,0,0,0,0,0,0,0,0,0,DT16,0,0,0,0,0,0,0,0,0)';
      PINUSE='POWER';
      NO_LOAD_CHECK='Both';
      NO_IO_CHECK='Both';
      NO_ASSERT_CHECK='TRUE';
      NO_DIR_CHECK='TRUE';
      ALLOW_CONNECT='TRUE';
    'VSS1006':
      PIN_NUMBER='(0,0,0,0,0,0,0,0,0,0,0,0,0,0,0,0,0,0,0,0,0,0,0,0,0,0,0,0,0,0,0,0,DR72,0,0,0,0,0,0,0,0,0)';
      PINUSE='POWER';
      NO_LOAD_CHECK='Both';
      NO_IO_CHECK='Both';
      NO_ASSERT_CHECK='TRUE';
      NO_DIR_CHECK='TRUE';
      ALLOW_CONNECT='TRUE';
    'VSS1005':
      PIN_NUMBER='(0,0,0,0,0,0,0,0,0,0,0,0,0,0,0,0,0,0,0,0,0,0,0,0,0,0,0,0,0,0,0,0,DR68,0,0,0,0,0,0,0,0,0)';
      PINUSE='POWER';
      NO_LOAD_CHECK='Both';
      NO_IO_CHECK='Both';
      NO_ASSERT_CHECK='TRUE';
      NO_DIR_CHECK='TRUE';
      ALLOW_CONNECT='TRUE';
    'VSS1003':
      PIN_NUMBER='(0,0,0,0,0,0,0,0,0,0,0,0,0,0,0,0,0,0,0,0,0,0,0,0,0,0,0,0,0,0,0,0,DR62,0,0,0,0,0,0,0,0,0)';
      PINUSE='POWER';
      NO_LOAD_CHECK='Both';
      NO_IO_CHECK='Both';
      NO_ASSERT_CHECK='TRUE';
      NO_DIR_CHECK='TRUE';
      ALLOW_CONNECT='TRUE';
    'VSS1002':
      PIN_NUMBER='(0,0,0,0,0,0,0,0,0,0,0,0,0,0,0,0,0,0,0,0,0,0,0,0,0,0,0,0,0,0,0,0,DR60,0,0,0,0,0,0,0,0,0)';
      PINUSE='POWER';
      NO_LOAD_CHECK='Both';
      NO_IO_CHECK='Both';
      NO_ASSERT_CHECK='TRUE';
      NO_DIR_CHECK='TRUE';
      ALLOW_CONNECT='TRUE';
    'VSS1000':
      PIN_NUMBER='(0,0,0,0,0,0,0,0,0,0,0,0,0,0,0,0,0,0,0,0,0,0,0,0,0,0,0,0,0,0,0,0,DR54,0,0,0,0,0,0,0,0,0)';
      PINUSE='POWER';
      NO_LOAD_CHECK='Both';
      NO_IO_CHECK='Both';
      NO_ASSERT_CHECK='TRUE';
      NO_DIR_CHECK='TRUE';
      ALLOW_CONNECT='TRUE';
    'VSS998':
      PIN_NUMBER='(0,0,0,0,0,0,0,0,0,0,0,0,0,0,0,0,0,0,0,0,0,0,0,0,0,0,0,0,0,0,0,0,DR5,0,0,0,0,0,0,0,0,0)';
      PINUSE='POWER';
      NO_LOAD_CHECK='Both';
      NO_IO_CHECK='Both';
      NO_ASSERT_CHECK='TRUE';
      NO_DIR_CHECK='TRUE';
      ALLOW_CONNECT='TRUE';
    'VSS993':
      PIN_NUMBER='(0,0,0,0,0,0,0,0,0,0,0,0,0,0,0,0,0,0,0,0,0,0,0,0,0,0,0,0,0,0,0,0,DR35,0,0,0,0,0,0,0,0,0)';
      PINUSE='POWER';
      NO_LOAD_CHECK='Both';
      NO_IO_CHECK='Both';
      NO_ASSERT_CHECK='TRUE';
      NO_DIR_CHECK='TRUE';
      ALLOW_CONNECT='TRUE';
    'VSS990':
      PIN_NUMBER='(0,0,0,0,0,0,0,0,0,0,0,0,0,0,0,0,0,0,0,0,0,0,0,0,0,0,0,0,0,0,0,0,DR25,0,0,0,0,0,0,0,0,0)';
      PINUSE='POWER';
      NO_LOAD_CHECK='Both';
      NO_IO_CHECK='Both';
      NO_ASSERT_CHECK='TRUE';
      NO_DIR_CHECK='TRUE';
      ALLOW_CONNECT='TRUE';
    'VSS985':
      PIN_NUMBER='(0,0,0,0,0,0,0,0,0,0,0,0,0,0,0,0,0,0,0,0,0,0,0,0,0,0,0,0,0,0,0,0,DP91,0,0,0,0,0,0,0,0,0)';
      PINUSE='POWER';
      NO_LOAD_CHECK='Both';
      NO_IO_CHECK='Both';
      NO_ASSERT_CHECK='TRUE';
      NO_DIR_CHECK='TRUE';
      ALLOW_CONNECT='TRUE';
    'VSS980':
      PIN_NUMBER='(0,0,0,0,0,0,0,0,0,0,0,0,0,0,0,0,0,0,0,0,0,0,0,0,0,0,0,0,0,0,0,0,DP67,0,0,0,0,0,0,0,0,0)';
      PINUSE='POWER';
      NO_LOAD_CHECK='Both';
      NO_IO_CHECK='Both';
      NO_ASSERT_CHECK='TRUE';
      NO_DIR_CHECK='TRUE';
      ALLOW_CONNECT='TRUE';
    'VSS979':
      PIN_NUMBER='(0,0,0,0,0,0,0,0,0,0,0,0,0,0,0,0,0,0,0,0,0,0,0,0,0,0,0,0,0,0,0,0,DP61,0,0,0,0,0,0,0,0,0)';
      PINUSE='POWER';
      NO_LOAD_CHECK='Both';
      NO_IO_CHECK='Both';
      NO_ASSERT_CHECK='TRUE';
      NO_DIR_CHECK='TRUE';
      ALLOW_CONNECT='TRUE';
    'VSS976':
      PIN_NUMBER='(0,0,0,0,0,0,0,0,0,0,0,0,0,0,0,0,0,0,0,0,0,0,0,0,0,0,0,0,0,0,0,0,DP55,0,0,0,0,0,0,0,0,0)';
      PINUSE='POWER';
      NO_LOAD_CHECK='Both';
      NO_IO_CHECK='Both';
      NO_ASSERT_CHECK='TRUE';
      NO_DIR_CHECK='TRUE';
      ALLOW_CONNECT='TRUE';
    'VSS973':
      PIN_NUMBER='(0,0,0,0,0,0,0,0,0,0,0,0,0,0,0,0,0,0,0,0,0,0,0,0,0,0,0,0,0,0,0,0,DP42,0,0,0,0,0,0,0,0,0)';
      PINUSE='POWER';
      NO_LOAD_CHECK='Both';
      NO_IO_CHECK='Both';
      NO_ASSERT_CHECK='TRUE';
      NO_DIR_CHECK='TRUE';
      ALLOW_CONNECT='TRUE';
    'VSS969':
      PIN_NUMBER='(0,0,0,0,0,0,0,0,0,0,0,0,0,0,0,0,0,0,0,0,0,0,0,0,0,0,0,0,0,0,0,0,DP24,0,0,0,0,0,0,0,0,0)';
      PINUSE='POWER';
      NO_LOAD_CHECK='Both';
      NO_IO_CHECK='Both';
      NO_ASSERT_CHECK='TRUE';
      NO_DIR_CHECK='TRUE';
      ALLOW_CONNECT='TRUE';
    'VSS968':
      PIN_NUMBER='(0,0,0,0,0,0,0,0,0,0,0,0,0,0,0,0,0,0,0,0,0,0,0,0,0,0,0,0,0,0,0,0,DP18,0,0,0,0,0,0,0,0,0)';
      PINUSE='POWER';
      NO_LOAD_CHECK='Both';
      NO_IO_CHECK='Both';
      NO_ASSERT_CHECK='TRUE';
      NO_DIR_CHECK='TRUE';
      ALLOW_CONNECT='TRUE';
    'VSS966':
      PIN_NUMBER='(0,0,0,0,0,0,0,0,0,0,0,0,0,0,0,0,0,0,0,0,0,0,0,0,0,0,0,0,0,0,0,0,DP12,0,0,0,0,0,0,0,0,0)';
      PINUSE='POWER';
      NO_LOAD_CHECK='Both';
      NO_IO_CHECK='Both';
      NO_ASSERT_CHECK='TRUE';
      NO_DIR_CHECK='TRUE';
      ALLOW_CONNECT='TRUE';
    'VSS959':
      PIN_NUMBER='(0,0,0,0,0,0,0,0,0,0,0,0,0,0,0,0,0,0,0,0,0,0,0,0,0,0,0,0,0,0,0,0,DN52,0,0,0,0,0,0,0,0,0)';
      PINUSE='POWER';
      NO_LOAD_CHECK='Both';
      NO_IO_CHECK='Both';
      NO_ASSERT_CHECK='TRUE';
      NO_DIR_CHECK='TRUE';
      ALLOW_CONNECT='TRUE';
    'VSS957':
      PIN_NUMBER='(0,0,0,0,0,0,0,0,0,0,0,0,0,0,0,0,0,0,0,0,0,0,0,0,0,0,0,0,0,0,0,0,DN39,0,0,0,0,0,0,0,0,0)';
      PINUSE='POWER';
      NO_LOAD_CHECK='Both';
      NO_IO_CHECK='Both';
      NO_ASSERT_CHECK='TRUE';
      NO_DIR_CHECK='TRUE';
      ALLOW_CONNECT='TRUE';
    'VSS955':
      PIN_NUMBER='(0,0,0,0,0,0,0,0,0,0,0,0,0,0,0,0,0,0,0,0,0,0,0,0,0,0,0,0,0,0,0,0,DN17,0,0,0,0,0,0,0,0,0)';
      PINUSE='POWER';
      NO_LOAD_CHECK='Both';
      NO_IO_CHECK='Both';
      NO_ASSERT_CHECK='TRUE';
      NO_DIR_CHECK='TRUE';
      ALLOW_CONNECT='TRUE';
    'VSS945':
      PIN_NUMBER='(0,0,0,0,0,0,0,0,0,0,0,0,0,0,0,0,0,0,0,0,0,0,0,0,0,0,0,0,0,0,0,0,DM73,0,0,0,0,0,0,0,0,0)';
      PINUSE='POWER';
      NO_LOAD_CHECK='Both';
      NO_IO_CHECK='Both';
      NO_ASSERT_CHECK='TRUE';
      NO_DIR_CHECK='TRUE';
      ALLOW_CONNECT='TRUE';
    'VSS934':
      PIN_NUMBER='(0,0,0,0,0,0,0,0,0,0,0,0,0,0,0,0,0,0,0,0,0,0,0,0,0,0,0,0,0,0,0,0,DM51,0,0,0,0,0,0,0,0,0)';
      PINUSE='POWER';
      NO_LOAD_CHECK='Both';
      NO_IO_CHECK='Both';
      NO_ASSERT_CHECK='TRUE';
      NO_DIR_CHECK='TRUE';
      ALLOW_CONNECT='TRUE';
    'VSS1099':
      PIN_NUMBER='(0,0,0,0,0,0,0,0,0,0,0,0,0,0,0,0,0,0,0,0,0,0,0,0,0,0,0,0,0,0,0,0,0,DL9,0,0,0,0,0,0,0,0)';
      PINUSE='POWER';
      NO_LOAD_CHECK='Both';
      NO_IO_CHECK='Both';
      NO_ASSERT_CHECK='TRUE';
      NO_DIR_CHECK='TRUE';
      ALLOW_CONNECT='TRUE';
    'VSS1098':
      PIN_NUMBER='(0,0,0,0,0,0,0,0,0,0,0,0,0,0,0,0,0,0,0,0,0,0,0,0,0,0,0,0,0,0,0,0,0,DL88,0,0,0,0,0,0,0,0)';
      PINUSE='POWER';
      NO_LOAD_CHECK='Both';
      NO_IO_CHECK='Both';
      NO_ASSERT_CHECK='TRUE';
      NO_DIR_CHECK='TRUE';
      ALLOW_CONNECT='TRUE';
    'VSS1096':
      PIN_NUMBER='(0,0,0,0,0,0,0,0,0,0,0,0,0,0,0,0,0,0,0,0,0,0,0,0,0,0,0,0,0,0,0,0,0,DL84,0,0,0,0,0,0,0,0)';
      PINUSE='POWER';
      NO_LOAD_CHECK='Both';
      NO_IO_CHECK='Both';
      NO_ASSERT_CHECK='TRUE';
      NO_DIR_CHECK='TRUE';
      ALLOW_CONNECT='TRUE';
    'VSS1095':
      PIN_NUMBER='(0,0,0,0,0,0,0,0,0,0,0,0,0,0,0,0,0,0,0,0,0,0,0,0,0,0,0,0,0,0,0,0,0,DL39,0,0,0,0,0,0,0,0)';
      PINUSE='POWER';
      NO_LOAD_CHECK='Both';
      NO_IO_CHECK='Both';
      NO_ASSERT_CHECK='TRUE';
      NO_DIR_CHECK='TRUE';
      ALLOW_CONNECT='TRUE';
    'VSS1094':
      PIN_NUMBER='(0,0,0,0,0,0,0,0,0,0,0,0,0,0,0,0,0,0,0,0,0,0,0,0,0,0,0,0,0,0,0,0,0,DK91,0,0,0,0,0,0,0,0)';
      PINUSE='POWER';
      NO_LOAD_CHECK='Both';
      NO_IO_CHECK='Both';
      NO_ASSERT_CHECK='TRUE';
      NO_DIR_CHECK='TRUE';
      ALLOW_CONNECT='TRUE';
    'VSS1093':
      PIN_NUMBER='(0,0,0,0,0,0,0,0,0,0,0,0,0,0,0,0,0,0,0,0,0,0,0,0,0,0,0,0,0,0,0,0,0,DK87,0,0,0,0,0,0,0,0)';
      PINUSE='POWER';
      NO_LOAD_CHECK='Both';
      NO_IO_CHECK='Both';
      NO_ASSERT_CHECK='TRUE';
      NO_DIR_CHECK='TRUE';
      ALLOW_CONNECT='TRUE';
    'VSS1092':
      PIN_NUMBER='(0,0,0,0,0,0,0,0,0,0,0,0,0,0,0,0,0,0,0,0,0,0,0,0,0,0,0,0,0,0,0,0,0,DK83,0,0,0,0,0,0,0,0)';
      PINUSE='POWER';
      NO_LOAD_CHECK='Both';
      NO_IO_CHECK='Both';
      NO_ASSERT_CHECK='TRUE';
      NO_DIR_CHECK='TRUE';
      ALLOW_CONNECT='TRUE';
    'VSS1091':
      PIN_NUMBER='(0,0,0,0,0,0,0,0,0,0,0,0,0,0,0,0,0,0,0,0,0,0,0,0,0,0,0,0,0,0,0,0,0,DK81,0,0,0,0,0,0,0,0)';
      PINUSE='POWER';
      NO_LOAD_CHECK='Both';
      NO_IO_CHECK='Both';
      NO_ASSERT_CHECK='TRUE';
      NO_DIR_CHECK='TRUE';
      ALLOW_CONNECT='TRUE';
    'VSS1090':
      PIN_NUMBER='(0,0,0,0,0,0,0,0,0,0,0,0,0,0,0,0,0,0,0,0,0,0,0,0,0,0,0,0,0,0,0,0,0,DK8,0,0,0,0,0,0,0,0)';
      PINUSE='POWER';
      NO_LOAD_CHECK='Both';
      NO_IO_CHECK='Both';
      NO_ASSERT_CHECK='TRUE';
      NO_DIR_CHECK='TRUE';
      ALLOW_CONNECT='TRUE';
    'VSS1089':
      PIN_NUMBER='(0,0,0,0,0,0,0,0,0,0,0,0,0,0,0,0,0,0,0,0,0,0,0,0,0,0,0,0,0,0,0,0,0,DK79,0,0,0,0,0,0,0,0)';
      PINUSE='POWER';
      NO_LOAD_CHECK='Both';
      NO_IO_CHECK='Both';
      NO_ASSERT_CHECK='TRUE';
      NO_DIR_CHECK='TRUE';
      ALLOW_CONNECT='TRUE';
    'VSS1088':
      PIN_NUMBER='(0,0,0,0,0,0,0,0,0,0,0,0,0,0,0,0,0,0,0,0,0,0,0,0,0,0,0,0,0,0,0,0,0,DK77,0,0,0,0,0,0,0,0)';
      PINUSE='POWER';
      NO_LOAD_CHECK='Both';
      NO_IO_CHECK='Both';
      NO_ASSERT_CHECK='TRUE';
      NO_DIR_CHECK='TRUE';
      ALLOW_CONNECT='TRUE';
    'VSS1087':
      PIN_NUMBER='(0,0,0,0,0,0,0,0,0,0,0,0,0,0,0,0,0,0,0,0,0,0,0,0,0,0,0,0,0,0,0,0,0,DK73,0,0,0,0,0,0,0,0)';
      PINUSE='POWER';
      NO_LOAD_CHECK='Both';
      NO_IO_CHECK='Both';
      NO_ASSERT_CHECK='TRUE';
      NO_DIR_CHECK='TRUE';
      ALLOW_CONNECT='TRUE';
    'VSS1086':
      PIN_NUMBER='(0,0,0,0,0,0,0,0,0,0,0,0,0,0,0,0,0,0,0,0,0,0,0,0,0,0,0,0,0,0,0,0,0,DK49,0,0,0,0,0,0,0,0)';
      PINUSE='POWER';
      NO_LOAD_CHECK='Both';
      NO_IO_CHECK='Both';
      NO_ASSERT_CHECK='TRUE';
      NO_DIR_CHECK='TRUE';
      ALLOW_CONNECT='TRUE';
    'VSS1085':
      PIN_NUMBER='(0,0,0,0,0,0,0,0,0,0,0,0,0,0,0,0,0,0,0,0,0,0,0,0,0,0,0,0,0,0,0,0,0,DK4,0,0,0,0,0,0,0,0)';
      PINUSE='POWER';
      NO_LOAD_CHECK='Both';
      NO_IO_CHECK='Both';
      NO_ASSERT_CHECK='TRUE';
      NO_DIR_CHECK='TRUE';
      ALLOW_CONNECT='TRUE';
    'VSS1084':
      PIN_NUMBER='(0,0,0,0,0,0,0,0,0,0,0,0,0,0,0,0,0,0,0,0,0,0,0,0,0,0,0,0,0,0,0,0,0,DK36,0,0,0,0,0,0,0,0)';
      PINUSE='POWER';
      NO_LOAD_CHECK='Both';
      NO_IO_CHECK='Both';
      NO_ASSERT_CHECK='TRUE';
      NO_DIR_CHECK='TRUE';
      ALLOW_CONNECT='TRUE';
    'VSS1083':
      PIN_NUMBER='(0,0,0,0,0,0,0,0,0,0,0,0,0,0,0,0,0,0,0,0,0,0,0,0,0,0,0,0,0,0,0,0,0,DK30,0,0,0,0,0,0,0,0)';
      PINUSE='POWER';
      NO_LOAD_CHECK='Both';
      NO_IO_CHECK='Both';
      NO_ASSERT_CHECK='TRUE';
      NO_DIR_CHECK='TRUE';
      ALLOW_CONNECT='TRUE';
    'VSS1082':
      PIN_NUMBER='(0,0,0,0,0,0,0,0,0,0,0,0,0,0,0,0,0,0,0,0,0,0,0,0,0,0,0,0,0,0,0,0,0,DK16,0,0,0,0,0,0,0,0)';
      PINUSE='POWER';
      NO_LOAD_CHECK='Both';
      NO_IO_CHECK='Both';
      NO_ASSERT_CHECK='TRUE';
      NO_DIR_CHECK='TRUE';
      ALLOW_CONNECT='TRUE';
    'VSS1081':
      PIN_NUMBER='(0,0,0,0,0,0,0,0,0,0,0,0,0,0,0,0,0,0,0,0,0,0,0,0,0,0,0,0,0,0,0,0,0,DJ88,0,0,0,0,0,0,0,0)';
      PINUSE='POWER';
      NO_LOAD_CHECK='Both';
      NO_IO_CHECK='Both';
      NO_ASSERT_CHECK='TRUE';
      NO_DIR_CHECK='TRUE';
      ALLOW_CONNECT='TRUE';
    'VSS1080':
      PIN_NUMBER='(0,0,0,0,0,0,0,0,0,0,0,0,0,0,0,0,0,0,0,0,0,0,0,0,0,0,0,0,0,0,0,0,0,DJ84,0,0,0,0,0,0,0,0)';
      PINUSE='POWER';
      NO_LOAD_CHECK='Both';
      NO_IO_CHECK='Both';
      NO_ASSERT_CHECK='TRUE';
      NO_DIR_CHECK='TRUE';
      ALLOW_CONNECT='TRUE';
    'VSS1079':
      PIN_NUMBER='(0,0,0,0,0,0,0,0,0,0,0,0,0,0,0,0,0,0,0,0,0,0,0,0,0,0,0,0,0,0,0,0,0,DJ82,0,0,0,0,0,0,0,0)';
      PINUSE='POWER';
      NO_LOAD_CHECK='Both';
      NO_IO_CHECK='Both';
      NO_ASSERT_CHECK='TRUE';
      NO_DIR_CHECK='TRUE';
      ALLOW_CONNECT='TRUE';
    'VSS1078':
      PIN_NUMBER='(0,0,0,0,0,0,0,0,0,0,0,0,0,0,0,0,0,0,0,0,0,0,0,0,0,0,0,0,0,0,0,0,0,DJ80,0,0,0,0,0,0,0,0)';
      PINUSE='POWER';
      NO_LOAD_CHECK='Both';
      NO_IO_CHECK='Both';
      NO_ASSERT_CHECK='TRUE';
      NO_DIR_CHECK='TRUE';
      ALLOW_CONNECT='TRUE';
    'VSS1076':
      PIN_NUMBER='(0,0,0,0,0,0,0,0,0,0,0,0,0,0,0,0,0,0,0,0,0,0,0,0,0,0,0,0,0,0,0,0,0,DJ74,0,0,0,0,0,0,0,0)';
      PINUSE='POWER';
      NO_LOAD_CHECK='Both';
      NO_IO_CHECK='Both';
      NO_ASSERT_CHECK='TRUE';
      NO_DIR_CHECK='TRUE';
      ALLOW_CONNECT='TRUE';
    'VSS1075':
      PIN_NUMBER='(0,0,0,0,0,0,0,0,0,0,0,0,0,0,0,0,0,0,0,0,0,0,0,0,0,0,0,0,0,0,0,0,0,DJ72,0,0,0,0,0,0,0,0)';
      PINUSE='POWER';
      NO_LOAD_CHECK='Both';
      NO_IO_CHECK='Both';
      NO_ASSERT_CHECK='TRUE';
      NO_DIR_CHECK='TRUE';
      ALLOW_CONNECT='TRUE';
    'VSS1074':
      PIN_NUMBER='(0,0,0,0,0,0,0,0,0,0,0,0,0,0,0,0,0,0,0,0,0,0,0,0,0,0,0,0,0,0,0,0,0,DJ66,0,0,0,0,0,0,0,0)';
      PINUSE='POWER';
      NO_LOAD_CHECK='Both';
      NO_IO_CHECK='Both';
      NO_ASSERT_CHECK='TRUE';
      NO_DIR_CHECK='TRUE';
      ALLOW_CONNECT='TRUE';
    'VSS1073':
      PIN_NUMBER='(0,0,0,0,0,0,0,0,0,0,0,0,0,0,0,0,0,0,0,0,0,0,0,0,0,0,0,0,0,0,0,0,0,DJ60,0,0,0,0,0,0,0,0)';
      PINUSE='POWER';
      NO_LOAD_CHECK='Both';
      NO_IO_CHECK='Both';
      NO_ASSERT_CHECK='TRUE';
      NO_DIR_CHECK='TRUE';
      ALLOW_CONNECT='TRUE';
    'VSS1072':
      PIN_NUMBER='(0,0,0,0,0,0,0,0,0,0,0,0,0,0,0,0,0,0,0,0,0,0,0,0,0,0,0,0,0,0,0,0,0,DJ56,0,0,0,0,0,0,0,0)';
      PINUSE='POWER';
      NO_LOAD_CHECK='Both';
      NO_IO_CHECK='Both';
      NO_ASSERT_CHECK='TRUE';
      NO_DIR_CHECK='TRUE';
      ALLOW_CONNECT='TRUE';
    'VSS1071':
      PIN_NUMBER='(0,0,0,0,0,0,0,0,0,0,0,0,0,0,0,0,0,0,0,0,0,0,0,0,0,0,0,0,0,0,0,0,0,DJ50,0,0,0,0,0,0,0,0)';
      PINUSE='POWER';
      NO_LOAD_CHECK='Both';
      NO_IO_CHECK='Both';
      NO_ASSERT_CHECK='TRUE';
      NO_DIR_CHECK='TRUE';
      ALLOW_CONNECT='TRUE';
    'VSS1070':
      PIN_NUMBER='(0,0,0,0,0,0,0,0,0,0,0,0,0,0,0,0,0,0,0,0,0,0,0,0,0,0,0,0,0,0,0,0,0,DJ48,0,0,0,0,0,0,0,0)';
      PINUSE='POWER';
      NO_LOAD_CHECK='Both';
      NO_IO_CHECK='Both';
      NO_ASSERT_CHECK='TRUE';
      NO_DIR_CHECK='TRUE';
      ALLOW_CONNECT='TRUE';
    'VSS1069':
      PIN_NUMBER='(0,0,0,0,0,0,0,0,0,0,0,0,0,0,0,0,0,0,0,0,0,0,0,0,0,0,0,0,0,0,0,0,0,DJ43,0,0,0,0,0,0,0,0)';
      PINUSE='POWER';
      NO_LOAD_CHECK='Both';
      NO_IO_CHECK='Both';
      NO_ASSERT_CHECK='TRUE';
      NO_DIR_CHECK='TRUE';
      ALLOW_CONNECT='TRUE';
    'VSS1068':
      PIN_NUMBER='(0,0,0,0,0,0,0,0,0,0,0,0,0,0,0,0,0,0,0,0,0,0,0,0,0,0,0,0,0,0,0,0,0,DJ41,0,0,0,0,0,0,0,0)';
      PINUSE='POWER';
      NO_LOAD_CHECK='Both';
      NO_IO_CHECK='Both';
      NO_ASSERT_CHECK='TRUE';
      NO_DIR_CHECK='TRUE';
      ALLOW_CONNECT='TRUE';
    'VSS1067':
      PIN_NUMBER='(0,0,0,0,0,0,0,0,0,0,0,0,0,0,0,0,0,0,0,0,0,0,0,0,0,0,0,0,0,0,0,0,0,DJ37,0,0,0,0,0,0,0,0)';
      PINUSE='POWER';
      NO_LOAD_CHECK='Both';
      NO_IO_CHECK='Both';
      NO_ASSERT_CHECK='TRUE';
      NO_DIR_CHECK='TRUE';
      ALLOW_CONNECT='TRUE';
    'VSS1066':
      PIN_NUMBER='(0,0,0,0,0,0,0,0,0,0,0,0,0,0,0,0,0,0,0,0,0,0,0,0,0,0,0,0,0,0,0,0,0,DJ31,0,0,0,0,0,0,0,0)';
      PINUSE='POWER';
      NO_LOAD_CHECK='Both';
      NO_IO_CHECK='Both';
      NO_ASSERT_CHECK='TRUE';
      NO_DIR_CHECK='TRUE';
      ALLOW_CONNECT='TRUE';
    'VSS1065':
      PIN_NUMBER='(0,0,0,0,0,0,0,0,0,0,0,0,0,0,0,0,0,0,0,0,0,0,0,0,0,0,0,0,0,0,0,0,0,DJ29,0,0,0,0,0,0,0,0)';
      PINUSE='POWER';
      NO_LOAD_CHECK='Both';
      NO_IO_CHECK='Both';
      NO_ASSERT_CHECK='TRUE';
      NO_DIR_CHECK='TRUE';
      ALLOW_CONNECT='TRUE';
    'VSS1062':
      PIN_NUMBER='(0,0,0,0,0,0,0,0,0,0,0,0,0,0,0,0,0,0,0,0,0,0,0,0,0,0,0,0,0,0,0,0,0,DJ23,0,0,0,0,0,0,0,0)';
      PINUSE='POWER';
      NO_LOAD_CHECK='Both';
      NO_IO_CHECK='Both';
      NO_ASSERT_CHECK='TRUE';
      NO_DIR_CHECK='TRUE';
      ALLOW_CONNECT='TRUE';
    'VSS1061':
      PIN_NUMBER='(0,0,0,0,0,0,0,0,0,0,0,0,0,0,0,0,0,0,0,0,0,0,0,0,0,0,0,0,0,0,0,0,0,DJ19,0,0,0,0,0,0,0,0)';
      PINUSE='POWER';
      NO_LOAD_CHECK='Both';
      NO_IO_CHECK='Both';
      NO_ASSERT_CHECK='TRUE';
      NO_DIR_CHECK='TRUE';
      ALLOW_CONNECT='TRUE';
    'VSS1058':
      PIN_NUMBER='(0,0,0,0,0,0,0,0,0,0,0,0,0,0,0,0,0,0,0,0,0,0,0,0,0,0,0,0,0,0,0,0,0,DH85,0,0,0,0,0,0,0,0)';
      PINUSE='POWER';
      NO_LOAD_CHECK='Both';
      NO_IO_CHECK='Both';
      NO_ASSERT_CHECK='TRUE';
      NO_DIR_CHECK='TRUE';
      ALLOW_CONNECT='TRUE';
    'VSS1057':
      PIN_NUMBER='(0,0,0,0,0,0,0,0,0,0,0,0,0,0,0,0,0,0,0,0,0,0,0,0,0,0,0,0,0,0,0,0,0,DH8,0,0,0,0,0,0,0,0)';
      PINUSE='POWER';
      NO_LOAD_CHECK='Both';
      NO_IO_CHECK='Both';
      NO_ASSERT_CHECK='TRUE';
      NO_DIR_CHECK='TRUE';
      ALLOW_CONNECT='TRUE';
    'VSS1056':
      PIN_NUMBER='(0,0,0,0,0,0,0,0,0,0,0,0,0,0,0,0,0,0,0,0,0,0,0,0,0,0,0,0,0,0,0,0,0,DH77,0,0,0,0,0,0,0,0)';
      PINUSE='POWER';
      NO_LOAD_CHECK='Both';
      NO_IO_CHECK='Both';
      NO_ASSERT_CHECK='TRUE';
      NO_DIR_CHECK='TRUE';
      ALLOW_CONNECT='TRUE';
    'VSS1055':
      PIN_NUMBER='(0,0,0,0,0,0,0,0,0,0,0,0,0,0,0,0,0,0,0,0,0,0,0,0,0,0,0,0,0,0,0,0,0,DH71,0,0,0,0,0,0,0,0)';
      PINUSE='POWER';
      NO_LOAD_CHECK='Both';
      NO_IO_CHECK='Both';
      NO_ASSERT_CHECK='TRUE';
      NO_DIR_CHECK='TRUE';
      ALLOW_CONNECT='TRUE';
    'VSS1053':
      PIN_NUMBER='(0,0,0,0,0,0,0,0,0,0,0,0,0,0,0,0,0,0,0,0,0,0,0,0,0,0,0,0,0,0,0,0,0,DH65,0,0,0,0,0,0,0,0)';
      PINUSE='POWER';
      NO_LOAD_CHECK='Both';
      NO_IO_CHECK='Both';
      NO_ASSERT_CHECK='TRUE';
      NO_DIR_CHECK='TRUE';
      ALLOW_CONNECT='TRUE';
    'VSS1049':
      PIN_NUMBER='(0,0,0,0,0,0,0,0,0,0,0,0,0,0,0,0,0,0,0,0,0,0,0,0,0,0,0,0,0,0,0,0,0,DH57,0,0,0,0,0,0,0,0)';
      PINUSE='POWER';
      NO_LOAD_CHECK='Both';
      NO_IO_CHECK='Both';
      NO_ASSERT_CHECK='TRUE';
      NO_DIR_CHECK='TRUE';
      ALLOW_CONNECT='TRUE';
    'VSS1046':
      PIN_NUMBER='(0,0,0,0,0,0,0,0,0,0,0,0,0,0,0,0,0,0,0,0,0,0,0,0,0,0,0,0,0,0,0,0,0,DH47,0,0,0,0,0,0,0,0)';
      PINUSE='POWER';
      NO_LOAD_CHECK='Both';
      NO_IO_CHECK='Both';
      NO_ASSERT_CHECK='TRUE';
      NO_DIR_CHECK='TRUE';
      ALLOW_CONNECT='TRUE';
    'VSS1045':
      PIN_NUMBER='(0,0,0,0,0,0,0,0,0,0,0,0,0,0,0,0,0,0,0,0,0,0,0,0,0,0,0,0,0,0,0,0,0,DH40,0,0,0,0,0,0,0,0)';
      PINUSE='POWER';
      NO_LOAD_CHECK='Both';
      NO_IO_CHECK='Both';
      NO_ASSERT_CHECK='TRUE';
      NO_DIR_CHECK='TRUE';
      ALLOW_CONNECT='TRUE';
    'VSS1044':
      PIN_NUMBER='(0,0,0,0,0,0,0,0,0,0,0,0,0,0,0,0,0,0,0,0,0,0,0,0,0,0,0,0,0,0,0,0,0,DH4,0,0,0,0,0,0,0,0)';
      PINUSE='POWER';
      NO_LOAD_CHECK='Both';
      NO_IO_CHECK='Both';
      NO_ASSERT_CHECK='TRUE';
      NO_DIR_CHECK='TRUE';
      ALLOW_CONNECT='TRUE';
    'VSS1043':
      PIN_NUMBER='(0,0,0,0,0,0,0,0,0,0,0,0,0,0,0,0,0,0,0,0,0,0,0,0,0,0,0,0,0,0,0,0,0,DH38,0,0,0,0,0,0,0,0)';
      PINUSE='POWER';
      NO_LOAD_CHECK='Both';
      NO_IO_CHECK='Both';
      NO_ASSERT_CHECK='TRUE';
      NO_DIR_CHECK='TRUE';
      ALLOW_CONNECT='TRUE';
    'VSS1042':
      PIN_NUMBER='(0,0,0,0,0,0,0,0,0,0,0,0,0,0,0,0,0,0,0,0,0,0,0,0,0,0,0,0,0,0,0,0,0,DH32,0,0,0,0,0,0,0,0)';
      PINUSE='POWER';
      NO_LOAD_CHECK='Both';
      NO_IO_CHECK='Both';
      NO_ASSERT_CHECK='TRUE';
      NO_DIR_CHECK='TRUE';
      ALLOW_CONNECT='TRUE';
    'VSS1041':
      PIN_NUMBER='(0,0,0,0,0,0,0,0,0,0,0,0,0,0,0,0,0,0,0,0,0,0,0,0,0,0,0,0,0,0,0,0,0,DH28,0,0,0,0,0,0,0,0)';
      PINUSE='POWER';
      NO_LOAD_CHECK='Both';
      NO_IO_CHECK='Both';
      NO_ASSERT_CHECK='TRUE';
      NO_DIR_CHECK='TRUE';
      ALLOW_CONNECT='TRUE';
    'VSS1040':
      PIN_NUMBER='(0,0,0,0,0,0,0,0,0,0,0,0,0,0,0,0,0,0,0,0,0,0,0,0,0,0,0,0,0,0,0,0,0,DH22,0,0,0,0,0,0,0,0)';
      PINUSE='POWER';
      NO_LOAD_CHECK='Both';
      NO_IO_CHECK='Both';
      NO_ASSERT_CHECK='TRUE';
      NO_DIR_CHECK='TRUE';
      ALLOW_CONNECT='TRUE';
    'VSS1039':
      PIN_NUMBER='(0,0,0,0,0,0,0,0,0,0,0,0,0,0,0,0,0,0,0,0,0,0,0,0,0,0,0,0,0,0,0,0,0,DH12,0,0,0,0,0,0,0,0)';
      PINUSE='POWER';
      NO_LOAD_CHECK='Both';
      NO_IO_CHECK='Both';
      NO_ASSERT_CHECK='TRUE';
      NO_DIR_CHECK='TRUE';
      ALLOW_CONNECT='TRUE';
    'VSS1038':
      PIN_NUMBER='(0,0,0,0,0,0,0,0,0,0,0,0,0,0,0,0,0,0,0,0,0,0,0,0,0,0,0,0,0,0,0,0,0,DG9,0,0,0,0,0,0,0,0)';
      PINUSE='POWER';
      NO_LOAD_CHECK='Both';
      NO_IO_CHECK='Both';
      NO_ASSERT_CHECK='TRUE';
      NO_DIR_CHECK='TRUE';
      ALLOW_CONNECT='TRUE';
    'VSS1037':
      PIN_NUMBER='(0,0,0,0,0,0,0,0,0,0,0,0,0,0,0,0,0,0,0,0,0,0,0,0,0,0,0,0,0,0,0,0,0,DG88,0,0,0,0,0,0,0,0)';
      PINUSE='POWER';
      NO_LOAD_CHECK='Both';
      NO_IO_CHECK='Both';
      NO_ASSERT_CHECK='TRUE';
      NO_DIR_CHECK='TRUE';
      ALLOW_CONNECT='TRUE';
    'VSS1035':
      PIN_NUMBER='(0,0,0,0,0,0,0,0,0,0,0,0,0,0,0,0,0,0,0,0,0,0,0,0,0,0,0,0,0,0,0,0,0,DG84,0,0,0,0,0,0,0,0)';
      PINUSE='POWER';
      NO_LOAD_CHECK='Both';
      NO_IO_CHECK='Both';
      NO_ASSERT_CHECK='TRUE';
      NO_DIR_CHECK='TRUE';
      ALLOW_CONNECT='TRUE';
    'VSS1034':
      PIN_NUMBER='(0,0,0,0,0,0,0,0,0,0,0,0,0,0,0,0,0,0,0,0,0,0,0,0,0,0,0,0,0,0,0,0,0,DG80,0,0,0,0,0,0,0,0)';
      PINUSE='POWER';
      NO_LOAD_CHECK='Both';
      NO_IO_CHECK='Both';
      NO_ASSERT_CHECK='TRUE';
      NO_DIR_CHECK='TRUE';
      ALLOW_CONNECT='TRUE';
    'VSS1033':
      PIN_NUMBER='(0,0,0,0,0,0,0,0,0,0,0,0,0,0,0,0,0,0,0,0,0,0,0,0,0,0,0,0,0,0,0,0,0,DG76,0,0,0,0,0,0,0,0)';
      PINUSE='POWER';
      NO_LOAD_CHECK='Both';
      NO_IO_CHECK='Both';
      NO_ASSERT_CHECK='TRUE';
      NO_DIR_CHECK='TRUE';
      ALLOW_CONNECT='TRUE';
    'VSS1032':
      PIN_NUMBER='(0,0,0,0,0,0,0,0,0,0,0,0,0,0,0,0,0,0,0,0,0,0,0,0,0,0,0,0,0,0,0,0,0,DG70,0,0,0,0,0,0,0,0)';
      PINUSE='POWER';
      NO_LOAD_CHECK='Both';
      NO_IO_CHECK='Both';
      NO_ASSERT_CHECK='TRUE';
      NO_DIR_CHECK='TRUE';
      ALLOW_CONNECT='TRUE';
    'VSS1031':
      PIN_NUMBER='(0,0,0,0,0,0,0,0,0,0,0,0,0,0,0,0,0,0,0,0,0,0,0,0,0,0,0,0,0,0,0,0,0,DG5,0,0,0,0,0,0,0,0)';
      PINUSE='POWER';
      NO_LOAD_CHECK='Both';
      NO_IO_CHECK='Both';
      NO_ASSERT_CHECK='TRUE';
      NO_DIR_CHECK='TRUE';
      ALLOW_CONNECT='TRUE';
    'VSS1030':
      PIN_NUMBER='(0,0,0,0,0,0,0,0,0,0,0,0,0,0,0,0,0,0,0,0,0,0,0,0,0,0,0,0,0,0,0,0,0,DG45,0,0,0,0,0,0,0,0)';
      PINUSE='POWER';
      NO_LOAD_CHECK='Both';
      NO_IO_CHECK='Both';
      NO_ASSERT_CHECK='TRUE';
      NO_DIR_CHECK='TRUE';
      ALLOW_CONNECT='TRUE';
    'VSS1027':
      PIN_NUMBER='(0,0,0,0,0,0,0,0,0,0,0,0,0,0,0,0,0,0,0,0,0,0,0,0,0,0,0,0,0,0,0,0,0,DG39,0,0,0,0,0,0,0,0)';
      PINUSE='POWER';
      NO_LOAD_CHECK='Both';
      NO_IO_CHECK='Both';
      NO_ASSERT_CHECK='TRUE';
      NO_DIR_CHECK='TRUE';
      ALLOW_CONNECT='TRUE';
    'VSS1024':
      PIN_NUMBER='(0,0,0,0,0,0,0,0,0,0,0,0,0,0,0,0,0,0,0,0,0,0,0,0,0,0,0,0,0,0,0,0,0,DG33,0,0,0,0,0,0,0,0)';
      PINUSE='POWER';
      NO_LOAD_CHECK='Both';
      NO_IO_CHECK='Both';
      NO_ASSERT_CHECK='TRUE';
      NO_DIR_CHECK='TRUE';
      ALLOW_CONNECT='TRUE';
    'VSS1022':
      PIN_NUMBER='(0,0,0,0,0,0,0,0,0,0,0,0,0,0,0,0,0,0,0,0,0,0,0,0,0,0,0,0,0,0,0,0,0,DG27,0,0,0,0,0,0,0,0)';
      PINUSE='POWER';
      NO_LOAD_CHECK='Both';
      NO_IO_CHECK='Both';
      NO_ASSERT_CHECK='TRUE';
      NO_DIR_CHECK='TRUE';
      ALLOW_CONNECT='TRUE';
    'VSS1020':
      PIN_NUMBER='(0,0,0,0,0,0,0,0,0,0,0,0,0,0,0,0,0,0,0,0,0,0,0,0,0,0,0,0,0,0,0,0,0,DF87,0,0,0,0,0,0,0,0)';
      PINUSE='POWER';
      NO_LOAD_CHECK='Both';
      NO_IO_CHECK='Both';
      NO_ASSERT_CHECK='TRUE';
      NO_DIR_CHECK='TRUE';
      ALLOW_CONNECT='TRUE';
    'VSS1019':
      PIN_NUMBER='(0,0,0,0,0,0,0,0,0,0,0,0,0,0,0,0,0,0,0,0,0,0,0,0,0,0,0,0,0,0,0,0,0,DF8,0,0,0,0,0,0,0,0)';
      PINUSE='POWER';
      NO_LOAD_CHECK='Both';
      NO_IO_CHECK='Both';
      NO_ASSERT_CHECK='TRUE';
      NO_DIR_CHECK='TRUE';
      ALLOW_CONNECT='TRUE';
    'VSS1018':
      PIN_NUMBER='(0,0,0,0,0,0,0,0,0,0,0,0,0,0,0,0,0,0,0,0,0,0,0,0,0,0,0,0,0,0,0,0,0,DF79,0,0,0,0,0,0,0,0)';
      PINUSE='POWER';
      NO_LOAD_CHECK='Both';
      NO_IO_CHECK='Both';
      NO_ASSERT_CHECK='TRUE';
      NO_DIR_CHECK='TRUE';
      ALLOW_CONNECT='TRUE';
    'VSS1017':
      PIN_NUMBER='(0,0,0,0,0,0,0,0,0,0,0,0,0,0,0,0,0,0,0,0,0,0,0,0,0,0,0,0,0,0,0,0,0,DF4,0,0,0,0,0,0,0,0)';
      PINUSE='POWER';
      NO_LOAD_CHECK='Both';
      NO_IO_CHECK='Both';
      NO_ASSERT_CHECK='TRUE';
      NO_DIR_CHECK='TRUE';
      ALLOW_CONNECT='TRUE';
    'VSS1015':
      PIN_NUMBER='(0,0,0,0,0,0,0,0,0,0,0,0,0,0,0,0,0,0,0,0,0,0,0,0,0,0,0,0,0,0,0,0,0,DE88,0,0,0,0,0,0,0,0)';
      PINUSE='POWER';
      NO_LOAD_CHECK='Both';
      NO_IO_CHECK='Both';
      NO_ASSERT_CHECK='TRUE';
      NO_DIR_CHECK='TRUE';
      ALLOW_CONNECT='TRUE';
    'VSS1012':
      PIN_NUMBER='(0,0,0,0,0,0,0,0,0,0,0,0,0,0,0,0,0,0,0,0,0,0,0,0,0,0,0,0,0,0,0,0,0,DE84,0,0,0,0,0,0,0,0)';
      PINUSE='POWER';
      NO_LOAD_CHECK='Both';
      NO_IO_CHECK='Both';
      NO_ASSERT_CHECK='TRUE';
      NO_DIR_CHECK='TRUE';
      ALLOW_CONNECT='TRUE';
    'VSS1011':
      PIN_NUMBER='(0,0,0,0,0,0,0,0,0,0,0,0,0,0,0,0,0,0,0,0,0,0,0,0,0,0,0,0,0,0,0,0,0,DE82,0,0,0,0,0,0,0,0)';
      PINUSE='POWER';
      NO_LOAD_CHECK='Both';
      NO_IO_CHECK='Both';
      NO_ASSERT_CHECK='TRUE';
      NO_DIR_CHECK='TRUE';
      ALLOW_CONNECT='TRUE';
    'VSS1010':
      PIN_NUMBER='(0,0,0,0,0,0,0,0,0,0,0,0,0,0,0,0,0,0,0,0,0,0,0,0,0,0,0,0,0,0,0,0,0,DE76,0,0,0,0,0,0,0,0)';
      PINUSE='POWER';
      NO_LOAD_CHECK='Both';
      NO_IO_CHECK='Both';
      NO_ASSERT_CHECK='TRUE';
      NO_DIR_CHECK='TRUE';
      ALLOW_CONNECT='TRUE';
    'VSS1009':
      PIN_NUMBER='(0,0,0,0,0,0,0,0,0,0,0,0,0,0,0,0,0,0,0,0,0,0,0,0,0,0,0,0,0,0,0,0,0,DE74,0,0,0,0,0,0,0,0)';
      PINUSE='POWER';
      NO_LOAD_CHECK='Both';
      NO_IO_CHECK='Both';
      NO_ASSERT_CHECK='TRUE';
      NO_DIR_CHECK='TRUE';
      ALLOW_CONNECT='TRUE';
    'VSS1008':
      PIN_NUMBER='(0,0,0,0,0,0,0,0,0,0,0,0,0,0,0,0,0,0,0,0,0,0,0,0,0,0,0,0,0,0,0,0,0,DE72,0,0,0,0,0,0,0,0)';
      PINUSE='POWER';
      NO_LOAD_CHECK='Both';
      NO_IO_CHECK='Both';
      NO_ASSERT_CHECK='TRUE';
      NO_DIR_CHECK='TRUE';
      ALLOW_CONNECT='TRUE';
    'VSS1007':
      PIN_NUMBER='(0,0,0,0,0,0,0,0,0,0,0,0,0,0,0,0,0,0,0,0,0,0,0,0,0,0,0,0,0,0,0,0,0,DE68,0,0,0,0,0,0,0,0)';
      PINUSE='POWER';
      NO_LOAD_CHECK='Both';
      NO_IO_CHECK='Both';
      NO_ASSERT_CHECK='TRUE';
      NO_DIR_CHECK='TRUE';
      ALLOW_CONNECT='TRUE';
    'VSS1004':
      PIN_NUMBER='(0,0,0,0,0,0,0,0,0,0,0,0,0,0,0,0,0,0,0,0,0,0,0,0,0,0,0,0,0,0,0,0,0,DE66,0,0,0,0,0,0,0,0)';
      PINUSE='POWER';
      NO_LOAD_CHECK='Both';
      NO_IO_CHECK='Both';
      NO_ASSERT_CHECK='TRUE';
      NO_DIR_CHECK='TRUE';
      ALLOW_CONNECT='TRUE';
    'VSS1001':
      PIN_NUMBER='(0,0,0,0,0,0,0,0,0,0,0,0,0,0,0,0,0,0,0,0,0,0,0,0,0,0,0,0,0,0,0,0,0,DE64,0,0,0,0,0,0,0,0)';
      PINUSE='POWER';
      NO_LOAD_CHECK='Both';
      NO_IO_CHECK='Both';
      NO_ASSERT_CHECK='TRUE';
      NO_DIR_CHECK='TRUE';
      ALLOW_CONNECT='TRUE';
    'VSS999':
      PIN_NUMBER='(0,0,0,0,0,0,0,0,0,0,0,0,0,0,0,0,0,0,0,0,0,0,0,0,0,0,0,0,0,0,0,0,0,DE62,0,0,0,0,0,0,0,0)';
      PINUSE='POWER';
      NO_LOAD_CHECK='Both';
      NO_IO_CHECK='Both';
      NO_ASSERT_CHECK='TRUE';
      NO_DIR_CHECK='TRUE';
      ALLOW_CONNECT='TRUE';
    'VSS997':
      PIN_NUMBER='(0,0,0,0,0,0,0,0,0,0,0,0,0,0,0,0,0,0,0,0,0,0,0,0,0,0,0,0,0,0,0,0,0,DE60,0,0,0,0,0,0,0,0)';
      PINUSE='POWER';
      NO_LOAD_CHECK='Both';
      NO_IO_CHECK='Both';
      NO_ASSERT_CHECK='TRUE';
      NO_DIR_CHECK='TRUE';
      ALLOW_CONNECT='TRUE';
    'VSS996':
      PIN_NUMBER='(0,0,0,0,0,0,0,0,0,0,0,0,0,0,0,0,0,0,0,0,0,0,0,0,0,0,0,0,0,0,0,0,0,DE58,0,0,0,0,0,0,0,0)';
      PINUSE='POWER';
      NO_LOAD_CHECK='Both';
      NO_IO_CHECK='Both';
      NO_ASSERT_CHECK='TRUE';
      NO_DIR_CHECK='TRUE';
      ALLOW_CONNECT='TRUE';
    'VSS995':
      PIN_NUMBER='(0,0,0,0,0,0,0,0,0,0,0,0,0,0,0,0,0,0,0,0,0,0,0,0,0,0,0,0,0,0,0,0,0,DE56,0,0,0,0,0,0,0,0)';
      PINUSE='POWER';
      NO_LOAD_CHECK='Both';
      NO_IO_CHECK='Both';
      NO_ASSERT_CHECK='TRUE';
      NO_DIR_CHECK='TRUE';
      ALLOW_CONNECT='TRUE';
    'VSS994':
      PIN_NUMBER='(0,0,0,0,0,0,0,0,0,0,0,0,0,0,0,0,0,0,0,0,0,0,0,0,0,0,0,0,0,0,0,0,0,DE54,0,0,0,0,0,0,0,0)';
      PINUSE='POWER';
      NO_LOAD_CHECK='Both';
      NO_IO_CHECK='Both';
      NO_ASSERT_CHECK='TRUE';
      NO_DIR_CHECK='TRUE';
      ALLOW_CONNECT='TRUE';
    'VSS992':
      PIN_NUMBER='(0,0,0,0,0,0,0,0,0,0,0,0,0,0,0,0,0,0,0,0,0,0,0,0,0,0,0,0,0,0,0,0,0,DE52,0,0,0,0,0,0,0,0)';
      PINUSE='POWER';
      NO_LOAD_CHECK='Both';
      NO_IO_CHECK='Both';
      NO_ASSERT_CHECK='TRUE';
      NO_DIR_CHECK='TRUE';
      ALLOW_CONNECT='TRUE';
    'VSS991':
      PIN_NUMBER='(0,0,0,0,0,0,0,0,0,0,0,0,0,0,0,0,0,0,0,0,0,0,0,0,0,0,0,0,0,0,0,0,0,DE50,0,0,0,0,0,0,0,0)';
      PINUSE='POWER';
      NO_LOAD_CHECK='Both';
      NO_IO_CHECK='Both';
      NO_ASSERT_CHECK='TRUE';
      NO_DIR_CHECK='TRUE';
      ALLOW_CONNECT='TRUE';
    'VSS989':
      PIN_NUMBER='(0,0,0,0,0,0,0,0,0,0,0,0,0,0,0,0,0,0,0,0,0,0,0,0,0,0,0,0,0,0,0,0,0,DE48,0,0,0,0,0,0,0,0)';
      PINUSE='POWER';
      NO_LOAD_CHECK='Both';
      NO_IO_CHECK='Both';
      NO_ASSERT_CHECK='TRUE';
      NO_DIR_CHECK='TRUE';
      ALLOW_CONNECT='TRUE';
    'VSS988':
      PIN_NUMBER='(0,0,0,0,0,0,0,0,0,0,0,0,0,0,0,0,0,0,0,0,0,0,0,0,0,0,0,0,0,0,0,0,0,DE45,0,0,0,0,0,0,0,0)';
      PINUSE='POWER';
      NO_LOAD_CHECK='Both';
      NO_IO_CHECK='Both';
      NO_ASSERT_CHECK='TRUE';
      NO_DIR_CHECK='TRUE';
      ALLOW_CONNECT='TRUE';
    'VSS987':
      PIN_NUMBER='(0,0,0,0,0,0,0,0,0,0,0,0,0,0,0,0,0,0,0,0,0,0,0,0,0,0,0,0,0,0,0,0,0,DE43,0,0,0,0,0,0,0,0)';
      PINUSE='POWER';
      NO_LOAD_CHECK='Both';
      NO_IO_CHECK='Both';
      NO_ASSERT_CHECK='TRUE';
      NO_DIR_CHECK='TRUE';
      ALLOW_CONNECT='TRUE';
    'VSS986':
      PIN_NUMBER='(0,0,0,0,0,0,0,0,0,0,0,0,0,0,0,0,0,0,0,0,0,0,0,0,0,0,0,0,0,0,0,0,0,DE41,0,0,0,0,0,0,0,0)';
      PINUSE='POWER';
      NO_LOAD_CHECK='Both';
      NO_IO_CHECK='Both';
      NO_ASSERT_CHECK='TRUE';
      NO_DIR_CHECK='TRUE';
      ALLOW_CONNECT='TRUE';
    'VSS984':
      PIN_NUMBER='(0,0,0,0,0,0,0,0,0,0,0,0,0,0,0,0,0,0,0,0,0,0,0,0,0,0,0,0,0,0,0,0,0,DE37,0,0,0,0,0,0,0,0)';
      PINUSE='POWER';
      NO_LOAD_CHECK='Both';
      NO_IO_CHECK='Both';
      NO_ASSERT_CHECK='TRUE';
      NO_DIR_CHECK='TRUE';
      ALLOW_CONNECT='TRUE';
    'VSS983':
      PIN_NUMBER='(0,0,0,0,0,0,0,0,0,0,0,0,0,0,0,0,0,0,0,0,0,0,0,0,0,0,0,0,0,0,0,0,0,DE35,0,0,0,0,0,0,0,0)';
      PINUSE='POWER';
      NO_LOAD_CHECK='Both';
      NO_IO_CHECK='Both';
      NO_ASSERT_CHECK='TRUE';
      NO_DIR_CHECK='TRUE';
      ALLOW_CONNECT='TRUE';
    'VSS982':
      PIN_NUMBER='(0,0,0,0,0,0,0,0,0,0,0,0,0,0,0,0,0,0,0,0,0,0,0,0,0,0,0,0,0,0,0,0,0,DE33,0,0,0,0,0,0,0,0)';
      PINUSE='POWER';
      NO_LOAD_CHECK='Both';
      NO_IO_CHECK='Both';
      NO_ASSERT_CHECK='TRUE';
      NO_DIR_CHECK='TRUE';
      ALLOW_CONNECT='TRUE';
    'VSS981':
      PIN_NUMBER='(0,0,0,0,0,0,0,0,0,0,0,0,0,0,0,0,0,0,0,0,0,0,0,0,0,0,0,0,0,0,0,0,0,DE31,0,0,0,0,0,0,0,0)';
      PINUSE='POWER';
      NO_LOAD_CHECK='Both';
      NO_IO_CHECK='Both';
      NO_ASSERT_CHECK='TRUE';
      NO_DIR_CHECK='TRUE';
      ALLOW_CONNECT='TRUE';
    'VSS978':
      PIN_NUMBER='(0,0,0,0,0,0,0,0,0,0,0,0,0,0,0,0,0,0,0,0,0,0,0,0,0,0,0,0,0,0,0,0,0,DE29,0,0,0,0,0,0,0,0)';
      PINUSE='POWER';
      NO_LOAD_CHECK='Both';
      NO_IO_CHECK='Both';
      NO_ASSERT_CHECK='TRUE';
      NO_DIR_CHECK='TRUE';
      ALLOW_CONNECT='TRUE';
    'VSS977':
      PIN_NUMBER='(0,0,0,0,0,0,0,0,0,0,0,0,0,0,0,0,0,0,0,0,0,0,0,0,0,0,0,0,0,0,0,0,0,DE27,0,0,0,0,0,0,0,0)';
      PINUSE='POWER';
      NO_LOAD_CHECK='Both';
      NO_IO_CHECK='Both';
      NO_ASSERT_CHECK='TRUE';
      NO_DIR_CHECK='TRUE';
      ALLOW_CONNECT='TRUE';
    'VSS975':
      PIN_NUMBER='(0,0,0,0,0,0,0,0,0,0,0,0,0,0,0,0,0,0,0,0,0,0,0,0,0,0,0,0,0,0,0,0,0,DE25,0,0,0,0,0,0,0,0)';
      PINUSE='POWER';
      NO_LOAD_CHECK='Both';
      NO_IO_CHECK='Both';
      NO_ASSERT_CHECK='TRUE';
      NO_DIR_CHECK='TRUE';
      ALLOW_CONNECT='TRUE';
    'VSS974':
      PIN_NUMBER='(0,0,0,0,0,0,0,0,0,0,0,0,0,0,0,0,0,0,0,0,0,0,0,0,0,0,0,0,0,0,0,0,0,DE23,0,0,0,0,0,0,0,0)';
      PINUSE='POWER';
      NO_LOAD_CHECK='Both';
      NO_IO_CHECK='Both';
      NO_ASSERT_CHECK='TRUE';
      NO_DIR_CHECK='TRUE';
      ALLOW_CONNECT='TRUE';
    'VSS972':
      PIN_NUMBER='(0,0,0,0,0,0,0,0,0,0,0,0,0,0,0,0,0,0,0,0,0,0,0,0,0,0,0,0,0,0,0,0,0,DE21,0,0,0,0,0,0,0,0)';
      PINUSE='POWER';
      NO_LOAD_CHECK='Both';
      NO_IO_CHECK='Both';
      NO_ASSERT_CHECK='TRUE';
      NO_DIR_CHECK='TRUE';
      ALLOW_CONNECT='TRUE';
    'VSS971':
      PIN_NUMBER='(0,0,0,0,0,0,0,0,0,0,0,0,0,0,0,0,0,0,0,0,0,0,0,0,0,0,0,0,0,0,0,0,0,DE19,0,0,0,0,0,0,0,0)';
      PINUSE='POWER';
      NO_LOAD_CHECK='Both';
      NO_IO_CHECK='Both';
      NO_ASSERT_CHECK='TRUE';
      NO_DIR_CHECK='TRUE';
      ALLOW_CONNECT='TRUE';
    'VSS970':
      PIN_NUMBER='(0,0,0,0,0,0,0,0,0,0,0,0,0,0,0,0,0,0,0,0,0,0,0,0,0,0,0,0,0,0,0,0,0,DE17,0,0,0,0,0,0,0,0)';
      PINUSE='POWER';
      NO_LOAD_CHECK='Both';
      NO_IO_CHECK='Both';
      NO_ASSERT_CHECK='TRUE';
      NO_DIR_CHECK='TRUE';
      ALLOW_CONNECT='TRUE';
    'VSS967':
      PIN_NUMBER='(0,0,0,0,0,0,0,0,0,0,0,0,0,0,0,0,0,0,0,0,0,0,0,0,0,0,0,0,0,0,0,0,0,DD8,0,0,0,0,0,0,0,0)';
      PINUSE='POWER';
      NO_LOAD_CHECK='Both';
      NO_IO_CHECK='Both';
      NO_ASSERT_CHECK='TRUE';
      NO_DIR_CHECK='TRUE';
      ALLOW_CONNECT='TRUE';
    'VSS965':
      PIN_NUMBER='(0,0,0,0,0,0,0,0,0,0,0,0,0,0,0,0,0,0,0,0,0,0,0,0,0,0,0,0,0,0,0,0,0,DD79,0,0,0,0,0,0,0,0)';
      PINUSE='POWER';
      NO_LOAD_CHECK='Both';
      NO_IO_CHECK='Both';
      NO_ASSERT_CHECK='TRUE';
      NO_DIR_CHECK='TRUE';
      ALLOW_CONNECT='TRUE';
    'VSS964':
      PIN_NUMBER='(0,0,0,0,0,0,0,0,0,0,0,0,0,0,0,0,0,0,0,0,0,0,0,0,0,0,0,0,0,0,0,0,0,DD4,0,0,0,0,0,0,0,0)';
      PINUSE='POWER';
      NO_LOAD_CHECK='Both';
      NO_IO_CHECK='Both';
      NO_ASSERT_CHECK='TRUE';
      NO_DIR_CHECK='TRUE';
      ALLOW_CONNECT='TRUE';
    'VSS963':
      PIN_NUMBER='(0,0,0,0,0,0,0,0,0,0,0,0,0,0,0,0,0,0,0,0,0,0,0,0,0,0,0,0,0,0,0,0,0,DC9,0,0,0,0,0,0,0,0)';
      PINUSE='POWER';
      NO_LOAD_CHECK='Both';
      NO_IO_CHECK='Both';
      NO_ASSERT_CHECK='TRUE';
      NO_DIR_CHECK='TRUE';
      ALLOW_CONNECT='TRUE';
    'VSS962':
      PIN_NUMBER='(0,0,0,0,0,0,0,0,0,0,0,0,0,0,0,0,0,0,0,0,0,0,0,0,0,0,0,0,0,0,0,0,0,DC88,0,0,0,0,0,0,0,0)';
      PINUSE='POWER';
      NO_LOAD_CHECK='Both';
      NO_IO_CHECK='Both';
      NO_ASSERT_CHECK='TRUE';
      NO_DIR_CHECK='TRUE';
      ALLOW_CONNECT='TRUE';
    'VSS961':
      PIN_NUMBER='(0,0,0,0,0,0,0,0,0,0,0,0,0,0,0,0,0,0,0,0,0,0,0,0,0,0,0,0,0,0,0,0,0,DC84,0,0,0,0,0,0,0,0)';
      PINUSE='POWER';
      NO_LOAD_CHECK='Both';
      NO_IO_CHECK='Both';
      NO_ASSERT_CHECK='TRUE';
      NO_DIR_CHECK='TRUE';
      ALLOW_CONNECT='TRUE';
    'VSS960':
      PIN_NUMBER='(0,0,0,0,0,0,0,0,0,0,0,0,0,0,0,0,0,0,0,0,0,0,0,0,0,0,0,0,0,0,0,0,0,DC80,0,0,0,0,0,0,0,0)';
      PINUSE='POWER';
      NO_LOAD_CHECK='Both';
      NO_IO_CHECK='Both';
      NO_ASSERT_CHECK='TRUE';
      NO_DIR_CHECK='TRUE';
      ALLOW_CONNECT='TRUE';
    'VSS958':
      PIN_NUMBER='(0,0,0,0,0,0,0,0,0,0,0,0,0,0,0,0,0,0,0,0,0,0,0,0,0,0,0,0,0,0,0,0,0,DC78,0,0,0,0,0,0,0,0)';
      PINUSE='POWER';
      NO_LOAD_CHECK='Both';
      NO_IO_CHECK='Both';
      NO_ASSERT_CHECK='TRUE';
      NO_DIR_CHECK='TRUE';
      ALLOW_CONNECT='TRUE';
    'VSS956':
      PIN_NUMBER='(0,0,0,0,0,0,0,0,0,0,0,0,0,0,0,0,0,0,0,0,0,0,0,0,0,0,0,0,0,0,0,0,0,DC76,0,0,0,0,0,0,0,0)';
      PINUSE='POWER';
      NO_LOAD_CHECK='Both';
      NO_IO_CHECK='Both';
      NO_ASSERT_CHECK='TRUE';
      NO_DIR_CHECK='TRUE';
      ALLOW_CONNECT='TRUE';
    'VSS954':
      PIN_NUMBER='(0,0,0,0,0,0,0,0,0,0,0,0,0,0,0,0,0,0,0,0,0,0,0,0,0,0,0,0,0,0,0,0,0,DC70,0,0,0,0,0,0,0,0)';
      PINUSE='POWER';
      NO_LOAD_CHECK='Both';
      NO_IO_CHECK='Both';
      NO_ASSERT_CHECK='TRUE';
      NO_DIR_CHECK='TRUE';
      ALLOW_CONNECT='TRUE';
    'VSS953':
      PIN_NUMBER='(0,0,0,0,0,0,0,0,0,0,0,0,0,0,0,0,0,0,0,0,0,0,0,0,0,0,0,0,0,0,0,0,0,DC5,0,0,0,0,0,0,0,0)';
      PINUSE='POWER';
      NO_LOAD_CHECK='Both';
      NO_IO_CHECK='Both';
      NO_ASSERT_CHECK='TRUE';
      NO_DIR_CHECK='TRUE';
      ALLOW_CONNECT='TRUE';
    'VSS952':
      PIN_NUMBER='(0,0,0,0,0,0,0,0,0,0,0,0,0,0,0,0,0,0,0,0,0,0,0,0,0,0,0,0,0,0,0,0,0,DC45,0,0,0,0,0,0,0,0)';
      PINUSE='POWER';
      NO_LOAD_CHECK='Both';
      NO_IO_CHECK='Both';
      NO_ASSERT_CHECK='TRUE';
      NO_DIR_CHECK='TRUE';
      ALLOW_CONNECT='TRUE';
    'VSS951':
      PIN_NUMBER='(0,0,0,0,0,0,0,0,0,0,0,0,0,0,0,0,0,0,0,0,0,0,0,0,0,0,0,0,0,0,0,0,0,DC39,0,0,0,0,0,0,0,0)';
      PINUSE='POWER';
      NO_LOAD_CHECK='Both';
      NO_IO_CHECK='Both';
      NO_ASSERT_CHECK='TRUE';
      NO_DIR_CHECK='TRUE';
      ALLOW_CONNECT='TRUE';
    'VSS950':
      PIN_NUMBER='(0,0,0,0,0,0,0,0,0,0,0,0,0,0,0,0,0,0,0,0,0,0,0,0,0,0,0,0,0,0,0,0,0,DC33,0,0,0,0,0,0,0,0)';
      PINUSE='POWER';
      NO_LOAD_CHECK='Both';
      NO_IO_CHECK='Both';
      NO_ASSERT_CHECK='TRUE';
      NO_DIR_CHECK='TRUE';
      ALLOW_CONNECT='TRUE';
    'VSS949':
      PIN_NUMBER='(0,0,0,0,0,0,0,0,0,0,0,0,0,0,0,0,0,0,0,0,0,0,0,0,0,0,0,0,0,0,0,0,0,DC27,0,0,0,0,0,0,0,0)';
      PINUSE='POWER';
      NO_LOAD_CHECK='Both';
      NO_IO_CHECK='Both';
      NO_ASSERT_CHECK='TRUE';
      NO_DIR_CHECK='TRUE';
      ALLOW_CONNECT='TRUE';
    'VSS909':
      PIN_NUMBER='(0,0,0,0,0,0,0,0,0,0,0,0,0,0,0,0,0,0,0,0,0,0,0,0,0,0,0,0,0,0,0,0,0,DL52,0,0,0,0,0,0,0,0)';
      PINUSE='POWER';
      NO_LOAD_CHECK='Both';
      NO_IO_CHECK='Both';
      NO_ASSERT_CHECK='TRUE';
      NO_DIR_CHECK='TRUE';
      ALLOW_CONNECT='TRUE';
    'VSS908':
      PIN_NUMBER='(0,0,0,0,0,0,0,0,0,0,0,0,0,0,0,0,0,0,0,0,0,0,0,0,0,0,0,0,0,0,0,0,0,DL5,0,0,0,0,0,0,0,0)';
      PINUSE='POWER';
      NO_LOAD_CHECK='Both';
      NO_IO_CHECK='Both';
      NO_ASSERT_CHECK='TRUE';
      NO_DIR_CHECK='TRUE';
      ALLOW_CONNECT='TRUE';
    'VSS905':
      PIN_NUMBER='(0,0,0,0,0,0,0,0,0,0,0,0,0,0,0,0,0,0,0,0,0,0,0,0,0,0,0,0,0,0,0,0,0,DL17,0,0,0,0,0,0,0,0)';
      PINUSE='POWER';
      NO_LOAD_CHECK='Both';
      NO_IO_CHECK='Both';
      NO_ASSERT_CHECK='TRUE';
      NO_DIR_CHECK='TRUE';
      ALLOW_CONNECT='TRUE';
    'VSS904':
      PIN_NUMBER='(0,0,0,0,0,0,0,0,0,0,0,0,0,0,0,0,0,0,0,0,0,0,0,0,0,0,0,0,0,0,0,0,0,DL13,0,0,0,0,0,0,0,0)';
      PINUSE='POWER';
      NO_LOAD_CHECK='Both';
      NO_IO_CHECK='Both';
      NO_ASSERT_CHECK='TRUE';
      NO_DIR_CHECK='TRUE';
      ALLOW_CONNECT='TRUE';
    'VSS903':
      PIN_NUMBER='(0,0,0,0,0,0,0,0,0,0,0,0,0,0,0,0,0,0,0,0,0,0,0,0,0,0,0,0,0,0,0,0,0,DL1,0,0,0,0,0,0,0,0)';
      PINUSE='POWER';
      NO_LOAD_CHECK='Both';
      NO_IO_CHECK='Both';
      NO_ASSERT_CHECK='TRUE';
      NO_DIR_CHECK='TRUE';
      ALLOW_CONNECT='TRUE';
    'VSS894':
      PIN_NUMBER='(0,0,0,0,0,0,0,0,0,0,0,0,0,0,0,0,0,0,0,0,0,0,0,0,0,0,0,0,0,0,0,0,0,DK67,0,0,0,0,0,0,0,0)';
      PINUSE='POWER';
      NO_LOAD_CHECK='Both';
      NO_IO_CHECK='Both';
      NO_ASSERT_CHECK='TRUE';
      NO_DIR_CHECK='TRUE';
      ALLOW_CONNECT='TRUE';
    'VSS893':
      PIN_NUMBER='(0,0,0,0,0,0,0,0,0,0,0,0,0,0,0,0,0,0,0,0,0,0,0,0,0,0,0,0,0,0,0,0,0,DK61,0,0,0,0,0,0,0,0)';
      PINUSE='POWER';
      NO_LOAD_CHECK='Both';
      NO_IO_CHECK='Both';
      NO_ASSERT_CHECK='TRUE';
      NO_DIR_CHECK='TRUE';
      ALLOW_CONNECT='TRUE';
    'VSS890':
      PIN_NUMBER='(0,0,0,0,0,0,0,0,0,0,0,0,0,0,0,0,0,0,0,0,0,0,0,0,0,0,0,0,0,0,0,0,0,DK55,0,0,0,0,0,0,0,0)';
      PINUSE='POWER';
      NO_LOAD_CHECK='Both';
      NO_IO_CHECK='Both';
      NO_ASSERT_CHECK='TRUE';
      NO_DIR_CHECK='TRUE';
      ALLOW_CONNECT='TRUE';
    'VSS887':
      PIN_NUMBER='(0,0,0,0,0,0,0,0,0,0,0,0,0,0,0,0,0,0,0,0,0,0,0,0,0,0,0,0,0,0,0,0,0,DK42,0,0,0,0,0,0,0,0)';
      PINUSE='POWER';
      NO_LOAD_CHECK='Both';
      NO_IO_CHECK='Both';
      NO_ASSERT_CHECK='TRUE';
      NO_DIR_CHECK='TRUE';
      ALLOW_CONNECT='TRUE';
    'VSS883':
      PIN_NUMBER='(0,0,0,0,0,0,0,0,0,0,0,0,0,0,0,0,0,0,0,0,0,0,0,0,0,0,0,0,0,0,0,0,0,DK24,0,0,0,0,0,0,0,0)';
      PINUSE='POWER';
      NO_LOAD_CHECK='Both';
      NO_IO_CHECK='Both';
      NO_ASSERT_CHECK='TRUE';
      NO_DIR_CHECK='TRUE';
      ALLOW_CONNECT='TRUE';
    'VSS882':
      PIN_NUMBER='(0,0,0,0,0,0,0,0,0,0,0,0,0,0,0,0,0,0,0,0,0,0,0,0,0,0,0,0,0,0,0,0,0,DK18,0,0,0,0,0,0,0,0)';
      PINUSE='POWER';
      NO_LOAD_CHECK='Both';
      NO_IO_CHECK='Both';
      NO_ASSERT_CHECK='TRUE';
      NO_DIR_CHECK='TRUE';
      ALLOW_CONNECT='TRUE';
    'VSS880':
      PIN_NUMBER='(0,0,0,0,0,0,0,0,0,0,0,0,0,0,0,0,0,0,0,0,0,0,0,0,0,0,0,0,0,0,0,0,0,DK12,0,0,0,0,0,0,0,0)';
      PINUSE='POWER';
      NO_LOAD_CHECK='Both';
      NO_IO_CHECK='Both';
      NO_ASSERT_CHECK='TRUE';
      NO_DIR_CHECK='TRUE';
      ALLOW_CONNECT='TRUE';
    'VSS872':
      PIN_NUMBER='(0,0,0,0,0,0,0,0,0,0,0,0,0,0,0,0,0,0,0,0,0,0,0,0,0,0,0,0,0,0,0,0,0,DJ68,0,0,0,0,0,0,0,0)';
      PINUSE='POWER';
      NO_LOAD_CHECK='Both';
      NO_IO_CHECK='Both';
      NO_ASSERT_CHECK='TRUE';
      NO_DIR_CHECK='TRUE';
      ALLOW_CONNECT='TRUE';
    'VSS870':
      PIN_NUMBER='(0,0,0,0,0,0,0,0,0,0,0,0,0,0,0,0,0,0,0,0,0,0,0,0,0,0,0,0,0,0,0,0,0,DJ62,0,0,0,0,0,0,0,0)';
      PINUSE='POWER';
      NO_LOAD_CHECK='Both';
      NO_IO_CHECK='Both';
      NO_ASSERT_CHECK='TRUE';
      NO_DIR_CHECK='TRUE';
      ALLOW_CONNECT='TRUE';
    'VSS867':
      PIN_NUMBER='(0,0,0,0,0,0,0,0,0,0,0,0,0,0,0,0,0,0,0,0,0,0,0,0,0,0,0,0,0,0,0,0,0,DJ54,0,0,0,0,0,0,0,0)';
      PINUSE='POWER';
      NO_LOAD_CHECK='Both';
      NO_IO_CHECK='Both';
      NO_ASSERT_CHECK='TRUE';
      NO_DIR_CHECK='TRUE';
      ALLOW_CONNECT='TRUE';
    'VSS861':
      PIN_NUMBER='(0,0,0,0,0,0,0,0,0,0,0,0,0,0,0,0,0,0,0,0,0,0,0,0,0,0,0,0,0,0,0,0,0,DJ35,0,0,0,0,0,0,0,0)';
      PINUSE='POWER';
      NO_LOAD_CHECK='Both';
      NO_IO_CHECK='Both';
      NO_ASSERT_CHECK='TRUE';
      NO_DIR_CHECK='TRUE';
      ALLOW_CONNECT='TRUE';
    'VSS857':
      PIN_NUMBER='(0,0,0,0,0,0,0,0,0,0,0,0,0,0,0,0,0,0,0,0,0,0,0,0,0,0,0,0,0,0,0,0,0,DJ25,0,0,0,0,0,0,0,0)';
      PINUSE='POWER';
      NO_LOAD_CHECK='Both';
      NO_IO_CHECK='Both';
      NO_ASSERT_CHECK='TRUE';
      NO_DIR_CHECK='TRUE';
      ALLOW_CONNECT='TRUE';
    'VSS849':
      PIN_NUMBER='(0,0,0,0,0,0,0,0,0,0,0,0,0,0,0,0,0,0,0,0,0,0,0,0,0,0,0,0,0,0,0,0,0,DH75,0,0,0,0,0,0,0,0)';
      PINUSE='POWER';
      NO_LOAD_CHECK='Both';
      NO_IO_CHECK='Both';
      NO_ASSERT_CHECK='TRUE';
      NO_DIR_CHECK='TRUE';
      ALLOW_CONNECT='TRUE';
    'VSS847':
      PIN_NUMBER='(0,0,0,0,0,0,0,0,0,0,0,0,0,0,0,0,0,0,0,0,0,0,0,0,0,0,0,0,0,0,0,0,0,DH69,0,0,0,0,0,0,0,0)';
      PINUSE='POWER';
      NO_LOAD_CHECK='Both';
      NO_IO_CHECK='Both';
      NO_ASSERT_CHECK='TRUE';
      NO_DIR_CHECK='TRUE';
      ALLOW_CONNECT='TRUE';
    'VSS845':
      PIN_NUMBER='(0,0,0,0,0,0,0,0,0,0,0,0,0,0,0,0,0,0,0,0,0,0,0,0,0,0,0,0,0,0,0,0,0,DH63,0,0,0,0,0,0,0,0)';
      PINUSE='POWER';
      NO_LOAD_CHECK='Both';
      NO_IO_CHECK='Both';
      NO_ASSERT_CHECK='TRUE';
      NO_DIR_CHECK='TRUE';
      ALLOW_CONNECT='TRUE';
    'VSS844':
      PIN_NUMBER='(0,0,0,0,0,0,0,0,0,0,0,0,0,0,0,0,0,0,0,0,0,0,0,0,0,0,0,0,0,0,0,0,0,DH59,0,0,0,0,0,0,0,0)';
      PINUSE='POWER';
      NO_LOAD_CHECK='Both';
      NO_IO_CHECK='Both';
      NO_ASSERT_CHECK='TRUE';
      NO_DIR_CHECK='TRUE';
      ALLOW_CONNECT='TRUE';
    'VSS842':
      PIN_NUMBER='(0,0,0,0,0,0,0,0,0,0,0,0,0,0,0,0,0,0,0,0,0,0,0,0,0,0,0,0,0,0,0,0,0,DH53,0,0,0,0,0,0,0,0)';
      PINUSE='POWER';
      NO_LOAD_CHECK='Both';
      NO_IO_CHECK='Both';
      NO_ASSERT_CHECK='TRUE';
      NO_DIR_CHECK='TRUE';
      ALLOW_CONNECT='TRUE';
    'VSS841':
      PIN_NUMBER='(0,0,0,0,0,0,0,0,0,0,0,0,0,0,0,0,0,0,0,0,0,0,0,0,0,0,0,0,0,0,0,0,0,DH51,0,0,0,0,0,0,0,0)';
      PINUSE='POWER';
      NO_LOAD_CHECK='Both';
      NO_IO_CHECK='Both';
      NO_ASSERT_CHECK='TRUE';
      NO_DIR_CHECK='TRUE';
      ALLOW_CONNECT='TRUE';
    'VSS839':
      PIN_NUMBER='(0,0,0,0,0,0,0,0,0,0,0,0,0,0,0,0,0,0,0,0,0,0,0,0,0,0,0,0,0,0,0,0,0,DH44,0,0,0,0,0,0,0,0)';
      PINUSE='POWER';
      NO_LOAD_CHECK='Both';
      NO_IO_CHECK='Both';
      NO_ASSERT_CHECK='TRUE';
      NO_DIR_CHECK='TRUE';
      ALLOW_CONNECT='TRUE';
    'VSS835':
      PIN_NUMBER='(0,0,0,0,0,0,0,0,0,0,0,0,0,0,0,0,0,0,0,0,0,0,0,0,0,0,0,0,0,0,0,0,0,DH34,0,0,0,0,0,0,0,0)';
      PINUSE='POWER';
      NO_LOAD_CHECK='Both';
      NO_IO_CHECK='Both';
      NO_ASSERT_CHECK='TRUE';
      NO_DIR_CHECK='TRUE';
      ALLOW_CONNECT='TRUE';
    'VSS832':
      PIN_NUMBER='(0,0,0,0,0,0,0,0,0,0,0,0,0,0,0,0,0,0,0,0,0,0,0,0,0,0,0,0,0,0,0,0,0,DH26,0,0,0,0,0,0,0,0)';
      PINUSE='POWER';
      NO_LOAD_CHECK='Both';
      NO_IO_CHECK='Both';
      NO_ASSERT_CHECK='TRUE';
      NO_DIR_CHECK='TRUE';
      ALLOW_CONNECT='TRUE';
    'VSS830':
      PIN_NUMBER='(0,0,0,0,0,0,0,0,0,0,0,0,0,0,0,0,0,0,0,0,0,0,0,0,0,0,0,0,0,0,0,0,0,DH20,0,0,0,0,0,0,0,0)';
      PINUSE='POWER';
      NO_LOAD_CHECK='Both';
      NO_IO_CHECK='Both';
      NO_ASSERT_CHECK='TRUE';
      NO_DIR_CHECK='TRUE';
      ALLOW_CONNECT='TRUE';
    'VSS829':
      PIN_NUMBER='(0,0,0,0,0,0,0,0,0,0,0,0,0,0,0,0,0,0,0,0,0,0,0,0,0,0,0,0,0,0,0,0,0,DH16,0,0,0,0,0,0,0,0)';
      PINUSE='POWER';
      NO_LOAD_CHECK='Both';
      NO_IO_CHECK='Both';
      NO_ASSERT_CHECK='TRUE';
      NO_DIR_CHECK='TRUE';
      ALLOW_CONNECT='TRUE';
    'VSS821':
      PIN_NUMBER='(0,0,0,0,0,0,0,0,0,0,0,0,0,0,0,0,0,0,0,0,0,0,0,0,0,0,0,0,0,0,0,0,0,DG64,0,0,0,0,0,0,0,0)';
      PINUSE='POWER';
      NO_LOAD_CHECK='Both';
      NO_IO_CHECK='Both';
      NO_ASSERT_CHECK='TRUE';
      NO_DIR_CHECK='TRUE';
      ALLOW_CONNECT='TRUE';
    'VSS820':
      PIN_NUMBER='(0,0,0,0,0,0,0,0,0,0,0,0,0,0,0,0,0,0,0,0,0,0,0,0,0,0,0,0,0,0,0,0,0,DG58,0,0,0,0,0,0,0,0)';
      PINUSE='POWER';
      NO_LOAD_CHECK='Both';
      NO_IO_CHECK='Both';
      NO_ASSERT_CHECK='TRUE';
      NO_DIR_CHECK='TRUE';
      ALLOW_CONNECT='TRUE';
    'VSS817':
      PIN_NUMBER='(0,0,0,0,0,0,0,0,0,0,0,0,0,0,0,0,0,0,0,0,0,0,0,0,0,0,0,0,0,0,0,0,0,DG52,0,0,0,0,0,0,0,0)';
      PINUSE='POWER';
      NO_LOAD_CHECK='Both';
      NO_IO_CHECK='Both';
      NO_ASSERT_CHECK='TRUE';
      NO_DIR_CHECK='TRUE';
      ALLOW_CONNECT='TRUE';
    'VSS809':
      PIN_NUMBER='(0,0,0,0,0,0,0,0,0,0,0,0,0,0,0,0,0,0,0,0,0,0,0,0,0,0,0,0,0,0,0,0,0,DG21,0,0,0,0,0,0,0,0)';
      PINUSE='POWER';
      NO_LOAD_CHECK='Both';
      NO_IO_CHECK='Both';
      NO_ASSERT_CHECK='TRUE';
      NO_DIR_CHECK='TRUE';
      ALLOW_CONNECT='TRUE';
    'VSS808':
      PIN_NUMBER='(0,0,0,0,0,0,0,0,0,0,0,0,0,0,0,0,0,0,0,0,0,0,0,0,0,0,0,0,0,0,0,0,0,DG13,0,0,0,0,0,0,0,0)';
      PINUSE='POWER';
      NO_LOAD_CHECK='Both';
      NO_IO_CHECK='Both';
      NO_ASSERT_CHECK='TRUE';
      NO_DIR_CHECK='TRUE';
      ALLOW_CONNECT='TRUE';
    'VSS807':
      PIN_NUMBER='(0,0,0,0,0,0,0,0,0,0,0,0,0,0,0,0,0,0,0,0,0,0,0,0,0,0,0,0,0,0,0,0,0,DG1,0,0,0,0,0,0,0,0)';
      PINUSE='POWER';
      NO_LOAD_CHECK='Both';
      NO_IO_CHECK='Both';
      NO_ASSERT_CHECK='TRUE';
      NO_DIR_CHECK='TRUE';
      ALLOW_CONNECT='TRUE';
    'VSS806':
      PIN_NUMBER='(0,0,0,0,0,0,0,0,0,0,0,0,0,0,0,0,0,0,0,0,0,0,0,0,0,0,0,0,0,0,0,0,0,DF91,0,0,0,0,0,0,0,0)';
      PINUSE='POWER';
      NO_LOAD_CHECK='Both';
      NO_IO_CHECK='Both';
      NO_ASSERT_CHECK='TRUE';
      NO_DIR_CHECK='TRUE';
      ALLOW_CONNECT='TRUE';
    'VSS802':
      PIN_NUMBER='(0,0,0,0,0,0,0,0,0,0,0,0,0,0,0,0,0,0,0,0,0,0,0,0,0,0,0,0,0,0,0,0,0,DF49,0,0,0,0,0,0,0,0)';
      PINUSE='POWER';
      NO_LOAD_CHECK='Both';
      NO_IO_CHECK='Both';
      NO_ASSERT_CHECK='TRUE';
      NO_DIR_CHECK='TRUE';
      ALLOW_CONNECT='TRUE';
    'VSS799':
      PIN_NUMBER='(0,0,0,0,0,0,0,0,0,0,0,0,0,0,0,0,0,0,0,0,0,0,0,0,0,0,0,0,0,0,0,0,0,DF16,0,0,0,0,0,0,0,0)';
      PINUSE='POWER';
      NO_LOAD_CHECK='Both';
      NO_IO_CHECK='Both';
      NO_ASSERT_CHECK='TRUE';
      NO_DIR_CHECK='TRUE';
      ALLOW_CONNECT='TRUE';
    'VSS798':
      PIN_NUMBER='(0,0,0,0,0,0,0,0,0,0,0,0,0,0,0,0,0,0,0,0,0,0,0,0,0,0,0,0,0,0,0,0,0,DF12,0,0,0,0,0,0,0,0)';
      PINUSE='POWER';
      NO_LOAD_CHECK='Both';
      NO_IO_CHECK='Both';
      NO_ASSERT_CHECK='TRUE';
      NO_DIR_CHECK='TRUE';
      ALLOW_CONNECT='TRUE';
    'VSS791':
      PIN_NUMBER='(0,0,0,0,0,0,0,0,0,0,0,0,0,0,0,0,0,0,0,0,0,0,0,0,0,0,0,0,0,0,0,0,0,DE70,0,0,0,0,0,0,0,0)';
      PINUSE='POWER';
      NO_LOAD_CHECK='Both';
      NO_IO_CHECK='Both';
      NO_ASSERT_CHECK='TRUE';
      NO_DIR_CHECK='TRUE';
      ALLOW_CONNECT='TRUE';
    'VSS776':
      PIN_NUMBER='(0,0,0,0,0,0,0,0,0,0,0,0,0,0,0,0,0,0,0,0,0,0,0,0,0,0,0,0,0,0,0,0,0,DE39,0,0,0,0,0,0,0,0)';
      PINUSE='POWER';
      NO_LOAD_CHECK='Both';
      NO_IO_CHECK='Both';
      NO_ASSERT_CHECK='TRUE';
      NO_DIR_CHECK='TRUE';
      ALLOW_CONNECT='TRUE';
    'VSS753':
      PIN_NUMBER='(0,0,0,0,0,0,0,0,0,0,0,0,0,0,0,0,0,0,0,0,0,0,0,0,0,0,0,0,0,0,0,0,0,DD49,0,0,0,0,0,0,0,0)';
      PINUSE='POWER';
      NO_LOAD_CHECK='Both';
      NO_IO_CHECK='Both';
      NO_ASSERT_CHECK='TRUE';
      NO_DIR_CHECK='TRUE';
      ALLOW_CONNECT='TRUE';
    'VSS748':
      PIN_NUMBER='(0,0,0,0,0,0,0,0,0,0,0,0,0,0,0,0,0,0,0,0,0,0,0,0,0,0,0,0,0,0,0,0,0,DD16,0,0,0,0,0,0,0,0)';
      PINUSE='POWER';
      NO_LOAD_CHECK='Both';
      NO_IO_CHECK='Both';
      NO_ASSERT_CHECK='TRUE';
      NO_DIR_CHECK='TRUE';
      ALLOW_CONNECT='TRUE';
    'VSS747':
      PIN_NUMBER='(0,0,0,0,0,0,0,0,0,0,0,0,0,0,0,0,0,0,0,0,0,0,0,0,0,0,0,0,0,0,0,0,0,DD12,0,0,0,0,0,0,0,0)';
      PINUSE='POWER';
      NO_LOAD_CHECK='Both';
      NO_IO_CHECK='Both';
      NO_ASSERT_CHECK='TRUE';
      NO_DIR_CHECK='TRUE';
      ALLOW_CONNECT='TRUE';
    'VSS739':
      PIN_NUMBER='(0,0,0,0,0,0,0,0,0,0,0,0,0,0,0,0,0,0,0,0,0,0,0,0,0,0,0,0,0,0,0,0,0,DC64,0,0,0,0,0,0,0,0)';
      PINUSE='POWER';
      NO_LOAD_CHECK='Both';
      NO_IO_CHECK='Both';
      NO_ASSERT_CHECK='TRUE';
      NO_DIR_CHECK='TRUE';
      ALLOW_CONNECT='TRUE';
    'VSS738':
      PIN_NUMBER='(0,0,0,0,0,0,0,0,0,0,0,0,0,0,0,0,0,0,0,0,0,0,0,0,0,0,0,0,0,0,0,0,0,DC58,0,0,0,0,0,0,0,0)';
      PINUSE='POWER';
      NO_LOAD_CHECK='Both';
      NO_IO_CHECK='Both';
      NO_ASSERT_CHECK='TRUE';
      NO_DIR_CHECK='TRUE';
      ALLOW_CONNECT='TRUE';
    'VSS735':
      PIN_NUMBER='(0,0,0,0,0,0,0,0,0,0,0,0,0,0,0,0,0,0,0,0,0,0,0,0,0,0,0,0,0,0,0,0,0,DC52,0,0,0,0,0,0,0,0)';
      PINUSE='POWER';
      NO_LOAD_CHECK='Both';
      NO_IO_CHECK='Both';
      NO_ASSERT_CHECK='TRUE';
      NO_DIR_CHECK='TRUE';
      ALLOW_CONNECT='TRUE';
    'VSS726':
      PIN_NUMBER='(0,0,0,0,0,0,0,0,0,0,0,0,0,0,0,0,0,0,0,0,0,0,0,0,0,0,0,0,0,0,0,0,0,DC21,0,0,0,0,0,0,0,0)';
      PINUSE='POWER';
      NO_LOAD_CHECK='Both';
      NO_IO_CHECK='Both';
      NO_ASSERT_CHECK='TRUE';
      NO_DIR_CHECK='TRUE';
      ALLOW_CONNECT='TRUE';
    'VSS725':
      PIN_NUMBER='(0,0,0,0,0,0,0,0,0,0,0,0,0,0,0,0,0,0,0,0,0,0,0,0,0,0,0,0,0,0,0,0,0,DC13,0,0,0,0,0,0,0,0)';
      PINUSE='POWER';
      NO_LOAD_CHECK='Both';
      NO_IO_CHECK='Both';
      NO_ASSERT_CHECK='TRUE';
      NO_DIR_CHECK='TRUE';
      ALLOW_CONNECT='TRUE';
    'VSS724':
      PIN_NUMBER='(0,0,0,0,0,0,0,0,0,0,0,0,0,0,0,0,0,0,0,0,0,0,0,0,0,0,0,0,0,0,0,0,0,DC1,0,0,0,0,0,0,0,0)';
      PINUSE='POWER';
      NO_LOAD_CHECK='Both';
      NO_IO_CHECK='Both';
      NO_ASSERT_CHECK='TRUE';
      NO_DIR_CHECK='TRUE';
      ALLOW_CONNECT='TRUE';
    'VSS723':
      PIN_NUMBER='(0,0,0,0,0,0,0,0,0,0,0,0,0,0,0,0,0,0,0,0,0,0,0,0,0,0,0,0,0,0,0,0,0,DB91,0,0,0,0,0,0,0,0)';
      PINUSE='POWER';
      NO_LOAD_CHECK='Both';
      NO_IO_CHECK='Both';
      NO_ASSERT_CHECK='TRUE';
      NO_DIR_CHECK='TRUE';
      ALLOW_CONNECT='TRUE';
    'VSS948':
      PIN_NUMBER='(0,0,0,0,0,0,0,0,0,0,0,0,0,0,0,0,0,0,0,0,0,0,0,0,0,0,0,0,0,0,0,0,0,0,DB87,0,0,0,0,0,0,0)';
      PINUSE='POWER';
      NO_LOAD_CHECK='Both';
      NO_IO_CHECK='Both';
      NO_ASSERT_CHECK='TRUE';
      NO_DIR_CHECK='TRUE';
      ALLOW_CONNECT='TRUE';
    'VSS947':
      PIN_NUMBER='(0,0,0,0,0,0,0,0,0,0,0,0,0,0,0,0,0,0,0,0,0,0,0,0,0,0,0,0,0,0,0,0,0,0,DB8,0,0,0,0,0,0,0)';
      PINUSE='POWER';
      NO_LOAD_CHECK='Both';
      NO_IO_CHECK='Both';
      NO_ASSERT_CHECK='TRUE';
      NO_DIR_CHECK='TRUE';
      ALLOW_CONNECT='TRUE';
    'VSS946':
      PIN_NUMBER='(0,0,0,0,0,0,0,0,0,0,0,0,0,0,0,0,0,0,0,0,0,0,0,0,0,0,0,0,0,0,0,0,0,0,DB77,0,0,0,0,0,0,0)';
      PINUSE='POWER';
      NO_LOAD_CHECK='Both';
      NO_IO_CHECK='Both';
      NO_ASSERT_CHECK='TRUE';
      NO_DIR_CHECK='TRUE';
      ALLOW_CONNECT='TRUE';
    'VSS944':
      PIN_NUMBER='(0,0,0,0,0,0,0,0,0,0,0,0,0,0,0,0,0,0,0,0,0,0,0,0,0,0,0,0,0,0,0,0,0,0,DB71,0,0,0,0,0,0,0)';
      PINUSE='POWER';
      NO_LOAD_CHECK='Both';
      NO_IO_CHECK='Both';
      NO_ASSERT_CHECK='TRUE';
      NO_DIR_CHECK='TRUE';
      ALLOW_CONNECT='TRUE';
    'VSS943':
      PIN_NUMBER='(0,0,0,0,0,0,0,0,0,0,0,0,0,0,0,0,0,0,0,0,0,0,0,0,0,0,0,0,0,0,0,0,0,0,DB65,0,0,0,0,0,0,0)';
      PINUSE='POWER';
      NO_LOAD_CHECK='Both';
      NO_IO_CHECK='Both';
      NO_ASSERT_CHECK='TRUE';
      NO_DIR_CHECK='TRUE';
      ALLOW_CONNECT='TRUE';
    'VSS942':
      PIN_NUMBER='(0,0,0,0,0,0,0,0,0,0,0,0,0,0,0,0,0,0,0,0,0,0,0,0,0,0,0,0,0,0,0,0,0,0,DB57,0,0,0,0,0,0,0)';
      PINUSE='POWER';
      NO_LOAD_CHECK='Both';
      NO_IO_CHECK='Both';
      NO_ASSERT_CHECK='TRUE';
      NO_DIR_CHECK='TRUE';
      ALLOW_CONNECT='TRUE';
    'VSS941':
      PIN_NUMBER='(0,0,0,0,0,0,0,0,0,0,0,0,0,0,0,0,0,0,0,0,0,0,0,0,0,0,0,0,0,0,0,0,0,0,DB47,0,0,0,0,0,0,0)';
      PINUSE='POWER';
      NO_LOAD_CHECK='Both';
      NO_IO_CHECK='Both';
      NO_ASSERT_CHECK='TRUE';
      NO_DIR_CHECK='TRUE';
      ALLOW_CONNECT='TRUE';
    'VSS940':
      PIN_NUMBER='(0,0,0,0,0,0,0,0,0,0,0,0,0,0,0,0,0,0,0,0,0,0,0,0,0,0,0,0,0,0,0,0,0,0,DB40,0,0,0,0,0,0,0)';
      PINUSE='POWER';
      NO_LOAD_CHECK='Both';
      NO_IO_CHECK='Both';
      NO_ASSERT_CHECK='TRUE';
      NO_DIR_CHECK='TRUE';
      ALLOW_CONNECT='TRUE';
    'VSS939':
      PIN_NUMBER='(0,0,0,0,0,0,0,0,0,0,0,0,0,0,0,0,0,0,0,0,0,0,0,0,0,0,0,0,0,0,0,0,0,0,DB4,0,0,0,0,0,0,0)';
      PINUSE='POWER';
      NO_LOAD_CHECK='Both';
      NO_IO_CHECK='Both';
      NO_ASSERT_CHECK='TRUE';
      NO_DIR_CHECK='TRUE';
      ALLOW_CONNECT='TRUE';
    'VSS938':
      PIN_NUMBER='(0,0,0,0,0,0,0,0,0,0,0,0,0,0,0,0,0,0,0,0,0,0,0,0,0,0,0,0,0,0,0,0,0,0,DB38,0,0,0,0,0,0,0)';
      PINUSE='POWER';
      NO_LOAD_CHECK='Both';
      NO_IO_CHECK='Both';
      NO_ASSERT_CHECK='TRUE';
      NO_DIR_CHECK='TRUE';
      ALLOW_CONNECT='TRUE';
    'VSS937':
      PIN_NUMBER='(0,0,0,0,0,0,0,0,0,0,0,0,0,0,0,0,0,0,0,0,0,0,0,0,0,0,0,0,0,0,0,0,0,0,DB32,0,0,0,0,0,0,0)';
      PINUSE='POWER';
      NO_LOAD_CHECK='Both';
      NO_IO_CHECK='Both';
      NO_ASSERT_CHECK='TRUE';
      NO_DIR_CHECK='TRUE';
      ALLOW_CONNECT='TRUE';
    'VSS936':
      PIN_NUMBER='(0,0,0,0,0,0,0,0,0,0,0,0,0,0,0,0,0,0,0,0,0,0,0,0,0,0,0,0,0,0,0,0,0,0,DB28,0,0,0,0,0,0,0)';
      PINUSE='POWER';
      NO_LOAD_CHECK='Both';
      NO_IO_CHECK='Both';
      NO_ASSERT_CHECK='TRUE';
      NO_DIR_CHECK='TRUE';
      ALLOW_CONNECT='TRUE';
    'VSS935':
      PIN_NUMBER='(0,0,0,0,0,0,0,0,0,0,0,0,0,0,0,0,0,0,0,0,0,0,0,0,0,0,0,0,0,0,0,0,0,0,DB22,0,0,0,0,0,0,0)';
      PINUSE='POWER';
      NO_LOAD_CHECK='Both';
      NO_IO_CHECK='Both';
      NO_ASSERT_CHECK='TRUE';
      NO_DIR_CHECK='TRUE';
      ALLOW_CONNECT='TRUE';
    'VSS933':
      PIN_NUMBER='(0,0,0,0,0,0,0,0,0,0,0,0,0,0,0,0,0,0,0,0,0,0,0,0,0,0,0,0,0,0,0,0,0,0,DB12,0,0,0,0,0,0,0)';
      PINUSE='POWER';
      NO_LOAD_CHECK='Both';
      NO_IO_CHECK='Both';
      NO_ASSERT_CHECK='TRUE';
      NO_DIR_CHECK='TRUE';
      ALLOW_CONNECT='TRUE';
    'VSS932':
      PIN_NUMBER='(0,0,0,0,0,0,0,0,0,0,0,0,0,0,0,0,0,0,0,0,0,0,0,0,0,0,0,0,0,0,0,0,0,0,DA88,0,0,0,0,0,0,0)';
      PINUSE='POWER';
      NO_LOAD_CHECK='Both';
      NO_IO_CHECK='Both';
      NO_ASSERT_CHECK='TRUE';
      NO_DIR_CHECK='TRUE';
      ALLOW_CONNECT='TRUE';
    'VSS931':
      PIN_NUMBER='(0,0,0,0,0,0,0,0,0,0,0,0,0,0,0,0,0,0,0,0,0,0,0,0,0,0,0,0,0,0,0,0,0,0,DA84,0,0,0,0,0,0,0)';
      PINUSE='POWER';
      NO_LOAD_CHECK='Both';
      NO_IO_CHECK='Both';
      NO_ASSERT_CHECK='TRUE';
      NO_DIR_CHECK='TRUE';
      ALLOW_CONNECT='TRUE';
    'VSS930':
      PIN_NUMBER='(0,0,0,0,0,0,0,0,0,0,0,0,0,0,0,0,0,0,0,0,0,0,0,0,0,0,0,0,0,0,0,0,0,0,DA82,0,0,0,0,0,0,0)';
      PINUSE='POWER';
      NO_LOAD_CHECK='Both';
      NO_IO_CHECK='Both';
      NO_ASSERT_CHECK='TRUE';
      NO_DIR_CHECK='TRUE';
      ALLOW_CONNECT='TRUE';
    'VSS929':
      PIN_NUMBER='(0,0,0,0,0,0,0,0,0,0,0,0,0,0,0,0,0,0,0,0,0,0,0,0,0,0,0,0,0,0,0,0,0,0,DA80,0,0,0,0,0,0,0)';
      PINUSE='POWER';
      NO_LOAD_CHECK='Both';
      NO_IO_CHECK='Both';
      NO_ASSERT_CHECK='TRUE';
      NO_DIR_CHECK='TRUE';
      ALLOW_CONNECT='TRUE';
    'VSS928':
      PIN_NUMBER='(0,0,0,0,0,0,0,0,0,0,0,0,0,0,0,0,0,0,0,0,0,0,0,0,0,0,0,0,0,0,0,0,0,0,DA74,0,0,0,0,0,0,0)';
      PINUSE='POWER';
      NO_LOAD_CHECK='Both';
      NO_IO_CHECK='Both';
      NO_ASSERT_CHECK='TRUE';
      NO_DIR_CHECK='TRUE';
      ALLOW_CONNECT='TRUE';
    'VSS927':
      PIN_NUMBER='(0,0,0,0,0,0,0,0,0,0,0,0,0,0,0,0,0,0,0,0,0,0,0,0,0,0,0,0,0,0,0,0,0,0,DA72,0,0,0,0,0,0,0)';
      PINUSE='POWER';
      NO_LOAD_CHECK='Both';
      NO_IO_CHECK='Both';
      NO_ASSERT_CHECK='TRUE';
      NO_DIR_CHECK='TRUE';
      ALLOW_CONNECT='TRUE';
    'VSS926':
      PIN_NUMBER='(0,0,0,0,0,0,0,0,0,0,0,0,0,0,0,0,0,0,0,0,0,0,0,0,0,0,0,0,0,0,0,0,0,0,DA66,0,0,0,0,0,0,0)';
      PINUSE='POWER';
      NO_LOAD_CHECK='Both';
      NO_IO_CHECK='Both';
      NO_ASSERT_CHECK='TRUE';
      NO_DIR_CHECK='TRUE';
      ALLOW_CONNECT='TRUE';
    'VSS925':
      PIN_NUMBER='(0,0,0,0,0,0,0,0,0,0,0,0,0,0,0,0,0,0,0,0,0,0,0,0,0,0,0,0,0,0,0,0,0,0,DA62,0,0,0,0,0,0,0)';
      PINUSE='POWER';
      NO_LOAD_CHECK='Both';
      NO_IO_CHECK='Both';
      NO_ASSERT_CHECK='TRUE';
      NO_DIR_CHECK='TRUE';
      ALLOW_CONNECT='TRUE';
    'VSS924':
      PIN_NUMBER='(0,0,0,0,0,0,0,0,0,0,0,0,0,0,0,0,0,0,0,0,0,0,0,0,0,0,0,0,0,0,0,0,0,0,DA60,0,0,0,0,0,0,0)';
      PINUSE='POWER';
      NO_LOAD_CHECK='Both';
      NO_IO_CHECK='Both';
      NO_ASSERT_CHECK='TRUE';
      NO_DIR_CHECK='TRUE';
      ALLOW_CONNECT='TRUE';
    'VSS923':
      PIN_NUMBER='(0,0,0,0,0,0,0,0,0,0,0,0,0,0,0,0,0,0,0,0,0,0,0,0,0,0,0,0,0,0,0,0,0,0,DA58,0,0,0,0,0,0,0)';
      PINUSE='POWER';
      NO_LOAD_CHECK='Both';
      NO_IO_CHECK='Both';
      NO_ASSERT_CHECK='TRUE';
      NO_DIR_CHECK='TRUE';
      ALLOW_CONNECT='TRUE';
    'VSS922':
      PIN_NUMBER='(0,0,0,0,0,0,0,0,0,0,0,0,0,0,0,0,0,0,0,0,0,0,0,0,0,0,0,0,0,0,0,0,0,0,DA56,0,0,0,0,0,0,0)';
      PINUSE='POWER';
      NO_LOAD_CHECK='Both';
      NO_IO_CHECK='Both';
      NO_ASSERT_CHECK='TRUE';
      NO_DIR_CHECK='TRUE';
      ALLOW_CONNECT='TRUE';
    'VSS921':
      PIN_NUMBER='(0,0,0,0,0,0,0,0,0,0,0,0,0,0,0,0,0,0,0,0,0,0,0,0,0,0,0,0,0,0,0,0,0,0,DA54,0,0,0,0,0,0,0)';
      PINUSE='POWER';
      NO_LOAD_CHECK='Both';
      NO_IO_CHECK='Both';
      NO_ASSERT_CHECK='TRUE';
      NO_DIR_CHECK='TRUE';
      ALLOW_CONNECT='TRUE';
    'VSS920':
      PIN_NUMBER='(0,0,0,0,0,0,0,0,0,0,0,0,0,0,0,0,0,0,0,0,0,0,0,0,0,0,0,0,0,0,0,0,0,0,DA50,0,0,0,0,0,0,0)';
      PINUSE='POWER';
      NO_LOAD_CHECK='Both';
      NO_IO_CHECK='Both';
      NO_ASSERT_CHECK='TRUE';
      NO_DIR_CHECK='TRUE';
      ALLOW_CONNECT='TRUE';
    'VSS919':
      PIN_NUMBER='(0,0,0,0,0,0,0,0,0,0,0,0,0,0,0,0,0,0,0,0,0,0,0,0,0,0,0,0,0,0,0,0,0,0,DA48,0,0,0,0,0,0,0)';
      PINUSE='POWER';
      NO_LOAD_CHECK='Both';
      NO_IO_CHECK='Both';
      NO_ASSERT_CHECK='TRUE';
      NO_DIR_CHECK='TRUE';
      ALLOW_CONNECT='TRUE';
    'VSS918':
      PIN_NUMBER='(0,0,0,0,0,0,0,0,0,0,0,0,0,0,0,0,0,0,0,0,0,0,0,0,0,0,0,0,0,0,0,0,0,0,DA41,0,0,0,0,0,0,0)';
      PINUSE='POWER';
      NO_LOAD_CHECK='Both';
      NO_IO_CHECK='Both';
      NO_ASSERT_CHECK='TRUE';
      NO_DIR_CHECK='TRUE';
      ALLOW_CONNECT='TRUE';
    'VSS917':
      PIN_NUMBER='(0,0,0,0,0,0,0,0,0,0,0,0,0,0,0,0,0,0,0,0,0,0,0,0,0,0,0,0,0,0,0,0,0,0,DA37,0,0,0,0,0,0,0)';
      PINUSE='POWER';
      NO_LOAD_CHECK='Both';
      NO_IO_CHECK='Both';
      NO_ASSERT_CHECK='TRUE';
      NO_DIR_CHECK='TRUE';
      ALLOW_CONNECT='TRUE';
    'VSS916':
      PIN_NUMBER='(0,0,0,0,0,0,0,0,0,0,0,0,0,0,0,0,0,0,0,0,0,0,0,0,0,0,0,0,0,0,0,0,0,0,DA35,0,0,0,0,0,0,0)';
      PINUSE='POWER';
      NO_LOAD_CHECK='Both';
      NO_IO_CHECK='Both';
      NO_ASSERT_CHECK='TRUE';
      NO_DIR_CHECK='TRUE';
      ALLOW_CONNECT='TRUE';
    'VSS915':
      PIN_NUMBER='(0,0,0,0,0,0,0,0,0,0,0,0,0,0,0,0,0,0,0,0,0,0,0,0,0,0,0,0,0,0,0,0,0,0,DA33,0,0,0,0,0,0,0)';
      PINUSE='POWER';
      NO_LOAD_CHECK='Both';
      NO_IO_CHECK='Both';
      NO_ASSERT_CHECK='TRUE';
      NO_DIR_CHECK='TRUE';
      ALLOW_CONNECT='TRUE';
    'VSS914':
      PIN_NUMBER='(0,0,0,0,0,0,0,0,0,0,0,0,0,0,0,0,0,0,0,0,0,0,0,0,0,0,0,0,0,0,0,0,0,0,DA31,0,0,0,0,0,0,0)';
      PINUSE='POWER';
      NO_LOAD_CHECK='Both';
      NO_IO_CHECK='Both';
      NO_ASSERT_CHECK='TRUE';
      NO_DIR_CHECK='TRUE';
      ALLOW_CONNECT='TRUE';
    'VSS913':
      PIN_NUMBER='(0,0,0,0,0,0,0,0,0,0,0,0,0,0,0,0,0,0,0,0,0,0,0,0,0,0,0,0,0,0,0,0,0,0,DA29,0,0,0,0,0,0,0)';
      PINUSE='POWER';
      NO_LOAD_CHECK='Both';
      NO_IO_CHECK='Both';
      NO_ASSERT_CHECK='TRUE';
      NO_DIR_CHECK='TRUE';
      ALLOW_CONNECT='TRUE';
    'VSS912':
      PIN_NUMBER='(0,0,0,0,0,0,0,0,0,0,0,0,0,0,0,0,0,0,0,0,0,0,0,0,0,0,0,0,0,0,0,0,0,0,DA25,0,0,0,0,0,0,0)';
      PINUSE='POWER';
      NO_LOAD_CHECK='Both';
      NO_IO_CHECK='Both';
      NO_ASSERT_CHECK='TRUE';
      NO_DIR_CHECK='TRUE';
      ALLOW_CONNECT='TRUE';
    'VSS911':
      PIN_NUMBER='(0,0,0,0,0,0,0,0,0,0,0,0,0,0,0,0,0,0,0,0,0,0,0,0,0,0,0,0,0,0,0,0,0,0,DA23,0,0,0,0,0,0,0)';
      PINUSE='POWER';
      NO_LOAD_CHECK='Both';
      NO_IO_CHECK='Both';
      NO_ASSERT_CHECK='TRUE';
      NO_DIR_CHECK='TRUE';
      ALLOW_CONNECT='TRUE';
    'VSS910':
      PIN_NUMBER='(0,0,0,0,0,0,0,0,0,0,0,0,0,0,0,0,0,0,0,0,0,0,0,0,0,0,0,0,0,0,0,0,0,0,DA19,0,0,0,0,0,0,0)';
      PINUSE='POWER';
      NO_LOAD_CHECK='Both';
      NO_IO_CHECK='Both';
      NO_ASSERT_CHECK='TRUE';
      NO_DIR_CHECK='TRUE';
      ALLOW_CONNECT='TRUE';
    'VSS863':
      PIN_NUMBER='(0,0,0,0,0,0,0,0,0,0,0,0,0,0,0,0,0,0,0,0,0,0,0,0,0,0,0,0,0,0,0,0,0,0,CY83,0,0,0,0,0,0,0)';
      PINUSE='POWER';
      NO_LOAD_CHECK='Both';
      NO_IO_CHECK='Both';
      NO_ASSERT_CHECK='TRUE';
      NO_DIR_CHECK='TRUE';
      ALLOW_CONNECT='TRUE';
    'VSS862':
      PIN_NUMBER='(0,0,0,0,0,0,0,0,0,0,0,0,0,0,0,0,0,0,0,0,0,0,0,0,0,0,0,0,0,0,0,0,0,0,CY81,0,0,0,0,0,0,0)';
      PINUSE='POWER';
      NO_LOAD_CHECK='Both';
      NO_IO_CHECK='Both';
      NO_ASSERT_CHECK='TRUE';
      NO_DIR_CHECK='TRUE';
      ALLOW_CONNECT='TRUE';
    'VSS860':
      PIN_NUMBER='(0,0,0,0,0,0,0,0,0,0,0,0,0,0,0,0,0,0,0,0,0,0,0,0,0,0,0,0,0,0,0,0,0,0,CY8,0,0,0,0,0,0,0)';
      PINUSE='POWER';
      NO_LOAD_CHECK='Both';
      NO_IO_CHECK='Both';
      NO_ASSERT_CHECK='TRUE';
      NO_DIR_CHECK='TRUE';
      ALLOW_CONNECT='TRUE';
    'VSS859':
      PIN_NUMBER='(0,0,0,0,0,0,0,0,0,0,0,0,0,0,0,0,0,0,0,0,0,0,0,0,0,0,0,0,0,0,0,0,0,0,CY77,0,0,0,0,0,0,0)';
      PINUSE='POWER';
      NO_LOAD_CHECK='Both';
      NO_IO_CHECK='Both';
      NO_ASSERT_CHECK='TRUE';
      NO_DIR_CHECK='TRUE';
      ALLOW_CONNECT='TRUE';
    'VSS858':
      PIN_NUMBER='(0,0,0,0,0,0,0,0,0,0,0,0,0,0,0,0,0,0,0,0,0,0,0,0,0,0,0,0,0,0,0,0,0,0,CY73,0,0,0,0,0,0,0)';
      PINUSE='POWER';
      NO_LOAD_CHECK='Both';
      NO_IO_CHECK='Both';
      NO_ASSERT_CHECK='TRUE';
      NO_DIR_CHECK='TRUE';
      ALLOW_CONNECT='TRUE';
    'VSS856':
      PIN_NUMBER='(0,0,0,0,0,0,0,0,0,0,0,0,0,0,0,0,0,0,0,0,0,0,0,0,0,0,0,0,0,0,0,0,0,0,CY63,0,0,0,0,0,0,0)';
      PINUSE='POWER';
      NO_LOAD_CHECK='Both';
      NO_IO_CHECK='Both';
      NO_ASSERT_CHECK='TRUE';
      NO_DIR_CHECK='TRUE';
      ALLOW_CONNECT='TRUE';
    'VSS855':
      PIN_NUMBER='(0,0,0,0,0,0,0,0,0,0,0,0,0,0,0,0,0,0,0,0,0,0,0,0,0,0,0,0,0,0,0,0,0,0,CY30,0,0,0,0,0,0,0)';
      PINUSE='POWER';
      NO_LOAD_CHECK='Both';
      NO_IO_CHECK='Both';
      NO_ASSERT_CHECK='TRUE';
      NO_DIR_CHECK='TRUE';
      ALLOW_CONNECT='TRUE';
    'VSS854':
      PIN_NUMBER='(0,0,0,0,0,0,0,0,0,0,0,0,0,0,0,0,0,0,0,0,0,0,0,0,0,0,0,0,0,0,0,0,0,0,CY26,0,0,0,0,0,0,0)';
      PINUSE='POWER';
      NO_LOAD_CHECK='Both';
      NO_IO_CHECK='Both';
      NO_ASSERT_CHECK='TRUE';
      NO_DIR_CHECK='TRUE';
      ALLOW_CONNECT='TRUE';
    'VSS853':
      PIN_NUMBER='(0,0,0,0,0,0,0,0,0,0,0,0,0,0,0,0,0,0,0,0,0,0,0,0,0,0,0,0,0,0,0,0,0,0,CY18,0,0,0,0,0,0,0)';
      PINUSE='POWER';
      NO_LOAD_CHECK='Both';
      NO_IO_CHECK='Both';
      NO_ASSERT_CHECK='TRUE';
      NO_DIR_CHECK='TRUE';
      ALLOW_CONNECT='TRUE';
    'VSS852':
      PIN_NUMBER='(0,0,0,0,0,0,0,0,0,0,0,0,0,0,0,0,0,0,0,0,0,0,0,0,0,0,0,0,0,0,0,0,0,0,CY16,0,0,0,0,0,0,0)';
      PINUSE='POWER';
      NO_LOAD_CHECK='Both';
      NO_IO_CHECK='Both';
      NO_ASSERT_CHECK='TRUE';
      NO_DIR_CHECK='TRUE';
      ALLOW_CONNECT='TRUE';
    'VSS851':
      PIN_NUMBER='(0,0,0,0,0,0,0,0,0,0,0,0,0,0,0,0,0,0,0,0,0,0,0,0,0,0,0,0,0,0,0,0,0,0,CY12,0,0,0,0,0,0,0)';
      PINUSE='POWER';
      NO_LOAD_CHECK='Both';
      NO_IO_CHECK='Both';
      NO_ASSERT_CHECK='TRUE';
      NO_DIR_CHECK='TRUE';
      ALLOW_CONNECT='TRUE';
    'VSS850':
      PIN_NUMBER='(0,0,0,0,0,0,0,0,0,0,0,0,0,0,0,0,0,0,0,0,0,0,0,0,0,0,0,0,0,0,0,0,0,0,CW9,0,0,0,0,0,0,0)';
      PINUSE='POWER';
      NO_LOAD_CHECK='Both';
      NO_IO_CHECK='Both';
      NO_ASSERT_CHECK='TRUE';
      NO_DIR_CHECK='TRUE';
      ALLOW_CONNECT='TRUE';
    'VSS848':
      PIN_NUMBER='(0,0,0,0,0,0,0,0,0,0,0,0,0,0,0,0,0,0,0,0,0,0,0,0,0,0,0,0,0,0,0,0,0,0,CW88,0,0,0,0,0,0,0)';
      PINUSE='POWER';
      NO_LOAD_CHECK='Both';
      NO_IO_CHECK='Both';
      NO_ASSERT_CHECK='TRUE';
      NO_DIR_CHECK='TRUE';
      ALLOW_CONNECT='TRUE';
    'VSS846':
      PIN_NUMBER='(0,0,0,0,0,0,0,0,0,0,0,0,0,0,0,0,0,0,0,0,0,0,0,0,0,0,0,0,0,0,0,0,0,0,CW84,0,0,0,0,0,0,0)';
      PINUSE='POWER';
      NO_LOAD_CHECK='Both';
      NO_IO_CHECK='Both';
      NO_ASSERT_CHECK='TRUE';
      NO_DIR_CHECK='TRUE';
      ALLOW_CONNECT='TRUE';
    'VSS843':
      PIN_NUMBER='(0,0,0,0,0,0,0,0,0,0,0,0,0,0,0,0,0,0,0,0,0,0,0,0,0,0,0,0,0,0,0,0,0,0,CW78,0,0,0,0,0,0,0)';
      PINUSE='POWER';
      NO_LOAD_CHECK='Both';
      NO_IO_CHECK='Both';
      NO_ASSERT_CHECK='TRUE';
      NO_DIR_CHECK='TRUE';
      ALLOW_CONNECT='TRUE';
    'VSS840':
      PIN_NUMBER='(0,0,0,0,0,0,0,0,0,0,0,0,0,0,0,0,0,0,0,0,0,0,0,0,0,0,0,0,0,0,0,0,0,0,CW72,0,0,0,0,0,0,0)';
      PINUSE='POWER';
      NO_LOAD_CHECK='Both';
      NO_IO_CHECK='Both';
      NO_ASSERT_CHECK='TRUE';
      NO_DIR_CHECK='TRUE';
      ALLOW_CONNECT='TRUE';
    'VSS838':
      PIN_NUMBER='(0,0,0,0,0,0,0,0,0,0,0,0,0,0,0,0,0,0,0,0,0,0,0,0,0,0,0,0,0,0,0,0,0,0,CW5,0,0,0,0,0,0,0)';
      PINUSE='POWER';
      NO_LOAD_CHECK='Both';
      NO_IO_CHECK='Both';
      NO_ASSERT_CHECK='TRUE';
      NO_DIR_CHECK='TRUE';
      ALLOW_CONNECT='TRUE';
    'VSS837':
      PIN_NUMBER='(0,0,0,0,0,0,0,0,0,0,0,0,0,0,0,0,0,0,0,0,0,0,0,0,0,0,0,0,0,0,0,0,0,0,CW17,0,0,0,0,0,0,0)';
      PINUSE='POWER';
      NO_LOAD_CHECK='Both';
      NO_IO_CHECK='Both';
      NO_ASSERT_CHECK='TRUE';
      NO_DIR_CHECK='TRUE';
      ALLOW_CONNECT='TRUE';
    'VSS836':
      PIN_NUMBER='(0,0,0,0,0,0,0,0,0,0,0,0,0,0,0,0,0,0,0,0,0,0,0,0,0,0,0,0,0,0,0,0,0,0,CW13,0,0,0,0,0,0,0)';
      PINUSE='POWER';
      NO_LOAD_CHECK='Both';
      NO_IO_CHECK='Both';
      NO_ASSERT_CHECK='TRUE';
      NO_DIR_CHECK='TRUE';
      ALLOW_CONNECT='TRUE';
    'VSS834':
      PIN_NUMBER='(0,0,0,0,0,0,0,0,0,0,0,0,0,0,0,0,0,0,0,0,0,0,0,0,0,0,0,0,0,0,0,0,0,0,CW1,0,0,0,0,0,0,0)';
      PINUSE='POWER';
      NO_LOAD_CHECK='Both';
      NO_IO_CHECK='Both';
      NO_ASSERT_CHECK='TRUE';
      NO_DIR_CHECK='TRUE';
      ALLOW_CONNECT='TRUE';
    'VSS833':
      PIN_NUMBER='(0,0,0,0,0,0,0,0,0,0,0,0,0,0,0,0,0,0,0,0,0,0,0,0,0,0,0,0,0,0,0,0,0,0,CV91,0,0,0,0,0,0,0)';
      PINUSE='POWER';
      NO_LOAD_CHECK='Both';
      NO_IO_CHECK='Both';
      NO_ASSERT_CHECK='TRUE';
      NO_DIR_CHECK='TRUE';
      ALLOW_CONNECT='TRUE';
    'VSS831':
      PIN_NUMBER='(0,0,0,0,0,0,0,0,0,0,0,0,0,0,0,0,0,0,0,0,0,0,0,0,0,0,0,0,0,0,0,0,0,0,CV87,0,0,0,0,0,0,0)';
      PINUSE='POWER';
      NO_LOAD_CHECK='Both';
      NO_IO_CHECK='Both';
      NO_ASSERT_CHECK='TRUE';
      NO_DIR_CHECK='TRUE';
      ALLOW_CONNECT='TRUE';
    'VSS828':
      PIN_NUMBER='(0,0,0,0,0,0,0,0,0,0,0,0,0,0,0,0,0,0,0,0,0,0,0,0,0,0,0,0,0,0,0,0,0,0,CV83,0,0,0,0,0,0,0)';
      PINUSE='POWER';
      NO_LOAD_CHECK='Both';
      NO_IO_CHECK='Both';
      NO_ASSERT_CHECK='TRUE';
      NO_DIR_CHECK='TRUE';
      ALLOW_CONNECT='TRUE';
    'VSS827':
      PIN_NUMBER='(0,0,0,0,0,0,0,0,0,0,0,0,0,0,0,0,0,0,0,0,0,0,0,0,0,0,0,0,0,0,0,0,0,0,CV8,0,0,0,0,0,0,0)';
      PINUSE='POWER';
      NO_LOAD_CHECK='Both';
      NO_IO_CHECK='Both';
      NO_ASSERT_CHECK='TRUE';
      NO_DIR_CHECK='TRUE';
      ALLOW_CONNECT='TRUE';
    'VSS826':
      PIN_NUMBER='(0,0,0,0,0,0,0,0,0,0,0,0,0,0,0,0,0,0,0,0,0,0,0,0,0,0,0,0,0,0,0,0,0,0,CV75,0,0,0,0,0,0,0)';
      PINUSE='POWER';
      NO_LOAD_CHECK='Both';
      NO_IO_CHECK='Both';
      NO_ASSERT_CHECK='TRUE';
      NO_DIR_CHECK='TRUE';
      ALLOW_CONNECT='TRUE';
    'VSS825':
      PIN_NUMBER='(0,0,0,0,0,0,0,0,0,0,0,0,0,0,0,0,0,0,0,0,0,0,0,0,0,0,0,0,0,0,0,0,0,0,CV4,0,0,0,0,0,0,0)';
      PINUSE='POWER';
      NO_LOAD_CHECK='Both';
      NO_IO_CHECK='Both';
      NO_ASSERT_CHECK='TRUE';
      NO_DIR_CHECK='TRUE';
      ALLOW_CONNECT='TRUE';
    'VSS824':
      PIN_NUMBER='(0,0,0,0,0,0,0,0,0,0,0,0,0,0,0,0,0,0,0,0,0,0,0,0,0,0,0,0,0,0,0,0,0,0,CV12,0,0,0,0,0,0,0)';
      PINUSE='POWER';
      NO_LOAD_CHECK='Both';
      NO_IO_CHECK='Both';
      NO_ASSERT_CHECK='TRUE';
      NO_DIR_CHECK='TRUE';
      ALLOW_CONNECT='TRUE';
    'VSS823':
      PIN_NUMBER='(0,0,0,0,0,0,0,0,0,0,0,0,0,0,0,0,0,0,0,0,0,0,0,0,0,0,0,0,0,0,0,0,0,0,CU88,0,0,0,0,0,0,0)';
      PINUSE='POWER';
      NO_LOAD_CHECK='Both';
      NO_IO_CHECK='Both';
      NO_ASSERT_CHECK='TRUE';
      NO_DIR_CHECK='TRUE';
      ALLOW_CONNECT='TRUE';
    'VSS822':
      PIN_NUMBER='(0,0,0,0,0,0,0,0,0,0,0,0,0,0,0,0,0,0,0,0,0,0,0,0,0,0,0,0,0,0,0,0,0,0,CU84,0,0,0,0,0,0,0)';
      PINUSE='POWER';
      NO_LOAD_CHECK='Both';
      NO_IO_CHECK='Both';
      NO_ASSERT_CHECK='TRUE';
      NO_DIR_CHECK='TRUE';
      ALLOW_CONNECT='TRUE';
    'VSS819':
      PIN_NUMBER='(0,0,0,0,0,0,0,0,0,0,0,0,0,0,0,0,0,0,0,0,0,0,0,0,0,0,0,0,0,0,0,0,0,0,CU68,0,0,0,0,0,0,0)';
      PINUSE='POWER';
      NO_LOAD_CHECK='Both';
      NO_IO_CHECK='Both';
      NO_ASSERT_CHECK='TRUE';
      NO_DIR_CHECK='TRUE';
      ALLOW_CONNECT='TRUE';
    'VSS818':
      PIN_NUMBER='(0,0,0,0,0,0,0,0,0,0,0,0,0,0,0,0,0,0,0,0,0,0,0,0,0,0,0,0,0,0,0,0,0,0,CU66,0,0,0,0,0,0,0)';
      PINUSE='POWER';
      NO_LOAD_CHECK='Both';
      NO_IO_CHECK='Both';
      NO_ASSERT_CHECK='TRUE';
      NO_DIR_CHECK='TRUE';
      ALLOW_CONNECT='TRUE';
    'VSS816':
      PIN_NUMBER='(0,0,0,0,0,0,0,0,0,0,0,0,0,0,0,0,0,0,0,0,0,0,0,0,0,0,0,0,0,0,0,0,0,0,CU60,0,0,0,0,0,0,0)';
      PINUSE='POWER';
      NO_LOAD_CHECK='Both';
      NO_IO_CHECK='Both';
      NO_ASSERT_CHECK='TRUE';
      NO_DIR_CHECK='TRUE';
      ALLOW_CONNECT='TRUE';
    'VSS815':
      PIN_NUMBER='(0,0,0,0,0,0,0,0,0,0,0,0,0,0,0,0,0,0,0,0,0,0,0,0,0,0,0,0,0,0,0,0,0,0,CU23,0,0,0,0,0,0,0)';
      PINUSE='POWER';
      NO_LOAD_CHECK='Both';
      NO_IO_CHECK='Both';
      NO_ASSERT_CHECK='TRUE';
      NO_DIR_CHECK='TRUE';
      ALLOW_CONNECT='TRUE';
    'VSS814':
      PIN_NUMBER='(0,0,0,0,0,0,0,0,0,0,0,0,0,0,0,0,0,0,0,0,0,0,0,0,0,0,0,0,0,0,0,0,0,0,CU21,0,0,0,0,0,0,0)';
      PINUSE='POWER';
      NO_LOAD_CHECK='Both';
      NO_IO_CHECK='Both';
      NO_ASSERT_CHECK='TRUE';
      NO_DIR_CHECK='TRUE';
      ALLOW_CONNECT='TRUE';
    'VSS813':
      PIN_NUMBER='(0,0,0,0,0,0,0,0,0,0,0,0,0,0,0,0,0,0,0,0,0,0,0,0,0,0,0,0,0,0,0,0,0,0,CU19,0,0,0,0,0,0,0)';
      PINUSE='POWER';
      NO_LOAD_CHECK='Both';
      NO_IO_CHECK='Both';
      NO_ASSERT_CHECK='TRUE';
      NO_DIR_CHECK='TRUE';
      ALLOW_CONNECT='TRUE';
    'VSS812':
      PIN_NUMBER='(0,0,0,0,0,0,0,0,0,0,0,0,0,0,0,0,0,0,0,0,0,0,0,0,0,0,0,0,0,0,0,0,0,0,CT81,0,0,0,0,0,0,0)';
      PINUSE='POWER';
      NO_LOAD_CHECK='Both';
      NO_IO_CHECK='Both';
      NO_ASSERT_CHECK='TRUE';
      NO_DIR_CHECK='TRUE';
      ALLOW_CONNECT='TRUE';
    'VSS811':
      PIN_NUMBER='(0,0,0,0,0,0,0,0,0,0,0,0,0,0,0,0,0,0,0,0,0,0,0,0,0,0,0,0,0,0,0,0,0,0,CT73,0,0,0,0,0,0,0)';
      PINUSE='POWER';
      NO_LOAD_CHECK='Both';
      NO_IO_CHECK='Both';
      NO_ASSERT_CHECK='TRUE';
      NO_DIR_CHECK='TRUE';
      ALLOW_CONNECT='TRUE';
    'VSS810':
      PIN_NUMBER='(0,0,0,0,0,0,0,0,0,0,0,0,0,0,0,0,0,0,0,0,0,0,0,0,0,0,0,0,0,0,0,0,0,0,CT69,0,0,0,0,0,0,0)';
      PINUSE='POWER';
      NO_LOAD_CHECK='Both';
      NO_IO_CHECK='Both';
      NO_ASSERT_CHECK='TRUE';
      NO_DIR_CHECK='TRUE';
      ALLOW_CONNECT='TRUE';
    'VSS805':
      PIN_NUMBER='(0,0,0,0,0,0,0,0,0,0,0,0,0,0,0,0,0,0,0,0,0,0,0,0,0,0,0,0,0,0,0,0,0,0,CT12,0,0,0,0,0,0,0)';
      PINUSE='POWER';
      NO_LOAD_CHECK='Both';
      NO_IO_CHECK='Both';
      NO_ASSERT_CHECK='TRUE';
      NO_DIR_CHECK='TRUE';
      ALLOW_CONNECT='TRUE';
    'VSS804':
      PIN_NUMBER='(0,0,0,0,0,0,0,0,0,0,0,0,0,0,0,0,0,0,0,0,0,0,0,0,0,0,0,0,0,0,0,0,0,0,CT10,0,0,0,0,0,0,0)';
      PINUSE='POWER';
      NO_LOAD_CHECK='Both';
      NO_IO_CHECK='Both';
      NO_ASSERT_CHECK='TRUE';
      NO_DIR_CHECK='TRUE';
      ALLOW_CONNECT='TRUE';
    'VSS803':
      PIN_NUMBER='(0,0,0,0,0,0,0,0,0,0,0,0,0,0,0,0,0,0,0,0,0,0,0,0,0,0,0,0,0,0,0,0,0,0,CR90,0,0,0,0,0,0,0)';
      PINUSE='POWER';
      NO_LOAD_CHECK='Both';
      NO_IO_CHECK='Both';
      NO_ASSERT_CHECK='TRUE';
      NO_DIR_CHECK='TRUE';
      ALLOW_CONNECT='TRUE';
    'VSS801':
      PIN_NUMBER='(0,0,0,0,0,0,0,0,0,0,0,0,0,0,0,0,0,0,0,0,0,0,0,0,0,0,0,0,0,0,0,0,0,0,CR9,0,0,0,0,0,0,0)';
      PINUSE='POWER';
      NO_LOAD_CHECK='Both';
      NO_IO_CHECK='Both';
      NO_ASSERT_CHECK='TRUE';
      NO_DIR_CHECK='TRUE';
      ALLOW_CONNECT='TRUE';
    'VSS800':
      PIN_NUMBER='(0,0,0,0,0,0,0,0,0,0,0,0,0,0,0,0,0,0,0,0,0,0,0,0,0,0,0,0,0,0,0,0,0,0,CR88,0,0,0,0,0,0,0)';
      PINUSE='POWER';
      NO_LOAD_CHECK='Both';
      NO_IO_CHECK='Both';
      NO_ASSERT_CHECK='TRUE';
      NO_DIR_CHECK='TRUE';
      ALLOW_CONNECT='TRUE';
    'VSS797':
      PIN_NUMBER='(0,0,0,0,0,0,0,0,0,0,0,0,0,0,0,0,0,0,0,0,0,0,0,0,0,0,0,0,0,0,0,0,0,0,CR84,0,0,0,0,0,0,0)';
      PINUSE='POWER';
      NO_LOAD_CHECK='Both';
      NO_IO_CHECK='Both';
      NO_ASSERT_CHECK='TRUE';
      NO_DIR_CHECK='TRUE';
      ALLOW_CONNECT='TRUE';
    'VSS796':
      PIN_NUMBER='(0,0,0,0,0,0,0,0,0,0,0,0,0,0,0,0,0,0,0,0,0,0,0,0,0,0,0,0,0,0,0,0,0,0,CR64,0,0,0,0,0,0,0)';
      PINUSE='POWER';
      NO_LOAD_CHECK='Both';
      NO_IO_CHECK='Both';
      NO_ASSERT_CHECK='TRUE';
      NO_DIR_CHECK='TRUE';
      ALLOW_CONNECT='TRUE';
    'VSS795':
      PIN_NUMBER='(0,0,0,0,0,0,0,0,0,0,0,0,0,0,0,0,0,0,0,0,0,0,0,0,0,0,0,0,0,0,0,0,0,0,CR62,0,0,0,0,0,0,0)';
      PINUSE='POWER';
      NO_LOAD_CHECK='Both';
      NO_IO_CHECK='Both';
      NO_ASSERT_CHECK='TRUE';
      NO_DIR_CHECK='TRUE';
      ALLOW_CONNECT='TRUE';
    'VSS794':
      PIN_NUMBER='(0,0,0,0,0,0,0,0,0,0,0,0,0,0,0,0,0,0,0,0,0,0,0,0,0,0,0,0,0,0,0,0,0,0,CR5,0,0,0,0,0,0,0)';
      PINUSE='POWER';
      NO_LOAD_CHECK='Both';
      NO_IO_CHECK='Both';
      NO_ASSERT_CHECK='TRUE';
      NO_DIR_CHECK='TRUE';
      ALLOW_CONNECT='TRUE';
    'VSS793':
      PIN_NUMBER='(0,0,0,0,0,0,0,0,0,0,0,0,0,0,0,0,0,0,0,0,0,0,0,0,0,0,0,0,0,0,0,0,0,0,CR17,0,0,0,0,0,0,0)';
      PINUSE='POWER';
      NO_LOAD_CHECK='Both';
      NO_IO_CHECK='Both';
      NO_ASSERT_CHECK='TRUE';
      NO_DIR_CHECK='TRUE';
      ALLOW_CONNECT='TRUE';
    'VSS792':
      PIN_NUMBER='(0,0,0,0,0,0,0,0,0,0,0,0,0,0,0,0,0,0,0,0,0,0,0,0,0,0,0,0,0,0,0,0,0,0,CR13,0,0,0,0,0,0,0)';
      PINUSE='POWER';
      NO_LOAD_CHECK='Both';
      NO_IO_CHECK='Both';
      NO_ASSERT_CHECK='TRUE';
      NO_DIR_CHECK='TRUE';
      ALLOW_CONNECT='TRUE';
    'VSS790':
      PIN_NUMBER='(0,0,0,0,0,0,0,0,0,0,0,0,0,0,0,0,0,0,0,0,0,0,0,0,0,0,0,0,0,0,0,0,0,0,CR11,0,0,0,0,0,0,0)';
      PINUSE='POWER';
      NO_LOAD_CHECK='Both';
      NO_IO_CHECK='Both';
      NO_ASSERT_CHECK='TRUE';
      NO_DIR_CHECK='TRUE';
      ALLOW_CONNECT='TRUE';
    'VSS789':
      PIN_NUMBER='(0,0,0,0,0,0,0,0,0,0,0,0,0,0,0,0,0,0,0,0,0,0,0,0,0,0,0,0,0,0,0,0,0,0,CR1,0,0,0,0,0,0,0)';
      PINUSE='POWER';
      NO_LOAD_CHECK='Both';
      NO_IO_CHECK='Both';
      NO_ASSERT_CHECK='TRUE';
      NO_DIR_CHECK='TRUE';
      ALLOW_CONNECT='TRUE';
    'VSS788':
      PIN_NUMBER='(0,0,0,0,0,0,0,0,0,0,0,0,0,0,0,0,0,0,0,0,0,0,0,0,0,0,0,0,0,0,0,0,0,0,CP91,0,0,0,0,0,0,0)';
      PINUSE='POWER';
      NO_LOAD_CHECK='Both';
      NO_IO_CHECK='Both';
      NO_ASSERT_CHECK='TRUE';
      NO_DIR_CHECK='TRUE';
      ALLOW_CONNECT='TRUE';
    'VSS787':
      PIN_NUMBER='(0,0,0,0,0,0,0,0,0,0,0,0,0,0,0,0,0,0,0,0,0,0,0,0,0,0,0,0,0,0,0,0,0,0,CP87,0,0,0,0,0,0,0)';
      PINUSE='POWER';
      NO_LOAD_CHECK='Both';
      NO_IO_CHECK='Both';
      NO_ASSERT_CHECK='TRUE';
      NO_DIR_CHECK='TRUE';
      ALLOW_CONNECT='TRUE';
    'VSS786':
      PIN_NUMBER='(0,0,0,0,0,0,0,0,0,0,0,0,0,0,0,0,0,0,0,0,0,0,0,0,0,0,0,0,0,0,0,0,0,0,CP83,0,0,0,0,0,0,0)';
      PINUSE='POWER';
      NO_LOAD_CHECK='Both';
      NO_IO_CHECK='Both';
      NO_ASSERT_CHECK='TRUE';
      NO_DIR_CHECK='TRUE';
      ALLOW_CONNECT='TRUE';
    'VSS785':
      PIN_NUMBER='(0,0,0,0,0,0,0,0,0,0,0,0,0,0,0,0,0,0,0,0,0,0,0,0,0,0,0,0,0,0,0,0,0,0,CP8,0,0,0,0,0,0,0)';
      PINUSE='POWER';
      NO_LOAD_CHECK='Both';
      NO_IO_CHECK='Both';
      NO_ASSERT_CHECK='TRUE';
      NO_DIR_CHECK='TRUE';
      ALLOW_CONNECT='TRUE';
    'VSS784':
      PIN_NUMBER='(0,0,0,0,0,0,0,0,0,0,0,0,0,0,0,0,0,0,0,0,0,0,0,0,0,0,0,0,0,0,0,0,0,0,CP77,0,0,0,0,0,0,0)';
      PINUSE='POWER';
      NO_LOAD_CHECK='Both';
      NO_IO_CHECK='Both';
      NO_ASSERT_CHECK='TRUE';
      NO_DIR_CHECK='TRUE';
      ALLOW_CONNECT='TRUE';
    'VSS783':
      PIN_NUMBER='(0,0,0,0,0,0,0,0,0,0,0,0,0,0,0,0,0,0,0,0,0,0,0,0,0,0,0,0,0,0,0,0,0,0,CP75,0,0,0,0,0,0,0)';
      PINUSE='POWER';
      NO_LOAD_CHECK='Both';
      NO_IO_CHECK='Both';
      NO_ASSERT_CHECK='TRUE';
      NO_DIR_CHECK='TRUE';
      ALLOW_CONNECT='TRUE';
    'VSS782':
      PIN_NUMBER='(0,0,0,0,0,0,0,0,0,0,0,0,0,0,0,0,0,0,0,0,0,0,0,0,0,0,0,0,0,0,0,0,0,0,CP4,0,0,0,0,0,0,0)';
      PINUSE='POWER';
      NO_LOAD_CHECK='Both';
      NO_IO_CHECK='Both';
      NO_ASSERT_CHECK='TRUE';
      NO_DIR_CHECK='TRUE';
      ALLOW_CONNECT='TRUE';
    'VSS781':
      PIN_NUMBER='(0,0,0,0,0,0,0,0,0,0,0,0,0,0,0,0,0,0,0,0,0,0,0,0,0,0,0,0,0,0,0,0,0,0,CP18,0,0,0,0,0,0,0)';
      PINUSE='POWER';
      NO_LOAD_CHECK='Both';
      NO_IO_CHECK='Both';
      NO_ASSERT_CHECK='TRUE';
      NO_DIR_CHECK='TRUE';
      ALLOW_CONNECT='TRUE';
    'VSS780':
      PIN_NUMBER='(0,0,0,0,0,0,0,0,0,0,0,0,0,0,0,0,0,0,0,0,0,0,0,0,0,0,0,0,0,0,0,0,0,0,CP12,0,0,0,0,0,0,0)';
      PINUSE='POWER';
      NO_LOAD_CHECK='Both';
      NO_IO_CHECK='Both';
      NO_ASSERT_CHECK='TRUE';
      NO_DIR_CHECK='TRUE';
      ALLOW_CONNECT='TRUE';
    'VSS779':
      PIN_NUMBER='(0,0,0,0,0,0,0,0,0,0,0,0,0,0,0,0,0,0,0,0,0,0,0,0,0,0,0,0,0,0,0,0,0,0,CN86,0,0,0,0,0,0,0)';
      PINUSE='POWER';
      NO_LOAD_CHECK='Both';
      NO_IO_CHECK='Both';
      NO_ASSERT_CHECK='TRUE';
      NO_DIR_CHECK='TRUE';
      ALLOW_CONNECT='TRUE';
    'VSS778':
      PIN_NUMBER='(0,0,0,0,0,0,0,0,0,0,0,0,0,0,0,0,0,0,0,0,0,0,0,0,0,0,0,0,0,0,0,0,0,0,CN84,0,0,0,0,0,0,0)';
      PINUSE='POWER';
      NO_LOAD_CHECK='Both';
      NO_IO_CHECK='Both';
      NO_ASSERT_CHECK='TRUE';
      NO_DIR_CHECK='TRUE';
      ALLOW_CONNECT='TRUE';
    'VSS777':
      PIN_NUMBER='(0,0,0,0,0,0,0,0,0,0,0,0,0,0,0,0,0,0,0,0,0,0,0,0,0,0,0,0,0,0,0,0,0,0,CN74,0,0,0,0,0,0,0)';
      PINUSE='POWER';
      NO_LOAD_CHECK='Both';
      NO_IO_CHECK='Both';
      NO_ASSERT_CHECK='TRUE';
      NO_DIR_CHECK='TRUE';
      ALLOW_CONNECT='TRUE';
    'VSS775':
      PIN_NUMBER='(0,0,0,0,0,0,0,0,0,0,0,0,0,0,0,0,0,0,0,0,0,0,0,0,0,0,0,0,0,0,0,0,0,0,CN72,0,0,0,0,0,0,0)';
      PINUSE='POWER';
      NO_LOAD_CHECK='Both';
      NO_IO_CHECK='Both';
      NO_ASSERT_CHECK='TRUE';
      NO_DIR_CHECK='TRUE';
      ALLOW_CONNECT='TRUE';
    'VSS774':
      PIN_NUMBER='(0,0,0,0,0,0,0,0,0,0,0,0,0,0,0,0,0,0,0,0,0,0,0,0,0,0,0,0,0,0,0,0,0,0,CN70,0,0,0,0,0,0,0)';
      PINUSE='POWER';
      NO_LOAD_CHECK='Both';
      NO_IO_CHECK='Both';
      NO_ASSERT_CHECK='TRUE';
      NO_DIR_CHECK='TRUE';
      ALLOW_CONNECT='TRUE';
    'VSS773':
      PIN_NUMBER='(0,0,0,0,0,0,0,0,0,0,0,0,0,0,0,0,0,0,0,0,0,0,0,0,0,0,0,0,0,0,0,0,0,0,CN68,0,0,0,0,0,0,0)';
      PINUSE='POWER';
      NO_LOAD_CHECK='Both';
      NO_IO_CHECK='Both';
      NO_ASSERT_CHECK='TRUE';
      NO_DIR_CHECK='TRUE';
      ALLOW_CONNECT='TRUE';
    'VSS772':
      PIN_NUMBER='(0,0,0,0,0,0,0,0,0,0,0,0,0,0,0,0,0,0,0,0,0,0,0,0,0,0,0,0,0,0,0,0,0,0,CM85,0,0,0,0,0,0,0)';
      PINUSE='POWER';
      NO_LOAD_CHECK='Both';
      NO_IO_CHECK='Both';
      NO_ASSERT_CHECK='TRUE';
      NO_DIR_CHECK='TRUE';
      ALLOW_CONNECT='TRUE';
    'VSS771':
      PIN_NUMBER='(0,0,0,0,0,0,0,0,0,0,0,0,0,0,0,0,0,0,0,0,0,0,0,0,0,0,0,0,0,0,0,0,0,0,CM83,0,0,0,0,0,0,0)';
      PINUSE='POWER';
      NO_LOAD_CHECK='Both';
      NO_IO_CHECK='Both';
      NO_ASSERT_CHECK='TRUE';
      NO_DIR_CHECK='TRUE';
      ALLOW_CONNECT='TRUE';
    'VSS770':
      PIN_NUMBER='(0,0,0,0,0,0,0,0,0,0,0,0,0,0,0,0,0,0,0,0,0,0,0,0,0,0,0,0,0,0,0,0,0,0,CM81,0,0,0,0,0,0,0)';
      PINUSE='POWER';
      NO_LOAD_CHECK='Both';
      NO_IO_CHECK='Both';
      NO_ASSERT_CHECK='TRUE';
      NO_DIR_CHECK='TRUE';
      ALLOW_CONNECT='TRUE';
    'VSS769':
      PIN_NUMBER='(0,0,0,0,0,0,0,0,0,0,0,0,0,0,0,0,0,0,0,0,0,0,0,0,0,0,0,0,0,0,0,0,0,0,CM8,0,0,0,0,0,0,0)';
      PINUSE='POWER';
      NO_LOAD_CHECK='Both';
      NO_IO_CHECK='Both';
      NO_ASSERT_CHECK='TRUE';
      NO_DIR_CHECK='TRUE';
      ALLOW_CONNECT='TRUE';
    'VSS768':
      PIN_NUMBER='(0,0,0,0,0,0,0,0,0,0,0,0,0,0,0,0,0,0,0,0,0,0,0,0,0,0,0,0,0,0,0,0,0,0,CM79,0,0,0,0,0,0,0)';
      PINUSE='POWER';
      NO_LOAD_CHECK='Both';
      NO_IO_CHECK='Both';
      NO_ASSERT_CHECK='TRUE';
      NO_DIR_CHECK='TRUE';
      ALLOW_CONNECT='TRUE';
    'VSS767':
      PIN_NUMBER='(0,0,0,0,0,0,0,0,0,0,0,0,0,0,0,0,0,0,0,0,0,0,0,0,0,0,0,0,0,0,0,0,0,0,CM67,0,0,0,0,0,0,0)';
      PINUSE='POWER';
      NO_LOAD_CHECK='Both';
      NO_IO_CHECK='Both';
      NO_ASSERT_CHECK='TRUE';
      NO_DIR_CHECK='TRUE';
      ALLOW_CONNECT='TRUE';
    'VSS766':
      PIN_NUMBER='(0,0,0,0,0,0,0,0,0,0,0,0,0,0,0,0,0,0,0,0,0,0,0,0,0,0,0,0,0,0,0,0,0,0,CM65,0,0,0,0,0,0,0)';
      PINUSE='POWER';
      NO_LOAD_CHECK='Both';
      NO_IO_CHECK='Both';
      NO_ASSERT_CHECK='TRUE';
      NO_DIR_CHECK='TRUE';
      ALLOW_CONNECT='TRUE';
    'VSS765':
      PIN_NUMBER='(0,0,0,0,0,0,0,0,0,0,0,0,0,0,0,0,0,0,0,0,0,0,0,0,0,0,0,0,0,0,0,0,0,0,CM61,0,0,0,0,0,0,0)';
      PINUSE='POWER';
      NO_LOAD_CHECK='Both';
      NO_IO_CHECK='Both';
      NO_ASSERT_CHECK='TRUE';
      NO_DIR_CHECK='TRUE';
      ALLOW_CONNECT='TRUE';
    'VSS764':
      PIN_NUMBER='(0,0,0,0,0,0,0,0,0,0,0,0,0,0,0,0,0,0,0,0,0,0,0,0,0,0,0,0,0,0,0,0,0,0,CM4,0,0,0,0,0,0,0)';
      PINUSE='POWER';
      NO_LOAD_CHECK='Both';
      NO_IO_CHECK='Both';
      NO_ASSERT_CHECK='TRUE';
      NO_DIR_CHECK='TRUE';
      ALLOW_CONNECT='TRUE';
    'VSS763':
      PIN_NUMBER='(0,0,0,0,0,0,0,0,0,0,0,0,0,0,0,0,0,0,0,0,0,0,0,0,0,0,0,0,0,0,0,0,0,0,CM24,0,0,0,0,0,0,0)';
      PINUSE='POWER';
      NO_LOAD_CHECK='Both';
      NO_IO_CHECK='Both';
      NO_ASSERT_CHECK='TRUE';
      NO_DIR_CHECK='TRUE';
      ALLOW_CONNECT='TRUE';
    'VSS762':
      PIN_NUMBER='(0,0,0,0,0,0,0,0,0,0,0,0,0,0,0,0,0,0,0,0,0,0,0,0,0,0,0,0,0,0,0,0,0,0,CM20,0,0,0,0,0,0,0)';
      PINUSE='POWER';
      NO_LOAD_CHECK='Both';
      NO_IO_CHECK='Both';
      NO_ASSERT_CHECK='TRUE';
      NO_DIR_CHECK='TRUE';
      ALLOW_CONNECT='TRUE';
    'VSS761':
      PIN_NUMBER='(0,0,0,0,0,0,0,0,0,0,0,0,0,0,0,0,0,0,0,0,0,0,0,0,0,0,0,0,0,0,0,0,0,0,CM12,0,0,0,0,0,0,0)';
      PINUSE='POWER';
      NO_LOAD_CHECK='Both';
      NO_IO_CHECK='Both';
      NO_ASSERT_CHECK='TRUE';
      NO_DIR_CHECK='TRUE';
      ALLOW_CONNECT='TRUE';
    'VSS760':
      PIN_NUMBER='(0,0,0,0,0,0,0,0,0,0,0,0,0,0,0,0,0,0,0,0,0,0,0,0,0,0,0,0,0,0,0,0,0,0,CL9,0,0,0,0,0,0,0)';
      PINUSE='POWER';
      NO_LOAD_CHECK='Both';
      NO_IO_CHECK='Both';
      NO_ASSERT_CHECK='TRUE';
      NO_DIR_CHECK='TRUE';
      ALLOW_CONNECT='TRUE';
    'VSS759':
      PIN_NUMBER='(0,0,0,0,0,0,0,0,0,0,0,0,0,0,0,0,0,0,0,0,0,0,0,0,0,0,0,0,0,0,0,0,0,0,CL82,0,0,0,0,0,0,0)';
      PINUSE='POWER';
      NO_LOAD_CHECK='Both';
      NO_IO_CHECK='Both';
      NO_ASSERT_CHECK='TRUE';
      NO_DIR_CHECK='TRUE';
      ALLOW_CONNECT='TRUE';
    'VSS758':
      PIN_NUMBER='(0,0,0,0,0,0,0,0,0,0,0,0,0,0,0,0,0,0,0,0,0,0,0,0,0,0,0,0,0,0,0,0,0,0,CL80,0,0,0,0,0,0,0)';
      PINUSE='POWER';
      NO_LOAD_CHECK='Both';
      NO_IO_CHECK='Both';
      NO_ASSERT_CHECK='TRUE';
      NO_DIR_CHECK='TRUE';
      ALLOW_CONNECT='TRUE';
    'VSS757':
      PIN_NUMBER='(0,0,0,0,0,0,0,0,0,0,0,0,0,0,0,0,0,0,0,0,0,0,0,0,0,0,0,0,0,0,0,0,0,0,CL78,0,0,0,0,0,0,0)';
      PINUSE='POWER';
      NO_LOAD_CHECK='Both';
      NO_IO_CHECK='Both';
      NO_ASSERT_CHECK='TRUE';
      NO_DIR_CHECK='TRUE';
      ALLOW_CONNECT='TRUE';
    'VSS756':
      PIN_NUMBER='(0,0,0,0,0,0,0,0,0,0,0,0,0,0,0,0,0,0,0,0,0,0,0,0,0,0,0,0,0,0,0,0,0,0,CL74,0,0,0,0,0,0,0)';
      PINUSE='POWER';
      NO_LOAD_CHECK='Both';
      NO_IO_CHECK='Both';
      NO_ASSERT_CHECK='TRUE';
      NO_DIR_CHECK='TRUE';
      ALLOW_CONNECT='TRUE';
    'VSS755':
      PIN_NUMBER='(0,0,0,0,0,0,0,0,0,0,0,0,0,0,0,0,0,0,0,0,0,0,0,0,0,0,0,0,0,0,0,0,0,0,CL62,0,0,0,0,0,0,0)';
      PINUSE='POWER';
      NO_LOAD_CHECK='Both';
      NO_IO_CHECK='Both';
      NO_ASSERT_CHECK='TRUE';
      NO_DIR_CHECK='TRUE';
      ALLOW_CONNECT='TRUE';
    'VSS754':
      PIN_NUMBER='(0,0,0,0,0,0,0,0,0,0,0,0,0,0,0,0,0,0,0,0,0,0,0,0,0,0,0,0,0,0,0,0,0,0,CL5,0,0,0,0,0,0,0)';
      PINUSE='POWER';
      NO_LOAD_CHECK='Both';
      NO_IO_CHECK='Both';
      NO_ASSERT_CHECK='TRUE';
      NO_DIR_CHECK='TRUE';
      ALLOW_CONNECT='TRUE';
    'VSS752':
      PIN_NUMBER='(0,0,0,0,0,0,0,0,0,0,0,0,0,0,0,0,0,0,0,0,0,0,0,0,0,0,0,0,0,0,0,0,0,0,CL17,0,0,0,0,0,0,0)';
      PINUSE='POWER';
      NO_LOAD_CHECK='Both';
      NO_IO_CHECK='Both';
      NO_ASSERT_CHECK='TRUE';
      NO_DIR_CHECK='TRUE';
      ALLOW_CONNECT='TRUE';
    'VSS751':
      PIN_NUMBER='(0,0,0,0,0,0,0,0,0,0,0,0,0,0,0,0,0,0,0,0,0,0,0,0,0,0,0,0,0,0,0,0,0,0,CL13,0,0,0,0,0,0,0)';
      PINUSE='POWER';
      NO_LOAD_CHECK='Both';
      NO_IO_CHECK='Both';
      NO_ASSERT_CHECK='TRUE';
      NO_DIR_CHECK='TRUE';
      ALLOW_CONNECT='TRUE';
    'VSS750':
      PIN_NUMBER='(0,0,0,0,0,0,0,0,0,0,0,0,0,0,0,0,0,0,0,0,0,0,0,0,0,0,0,0,0,0,0,0,0,0,CL1,0,0,0,0,0,0,0)';
      PINUSE='POWER';
      NO_LOAD_CHECK='Both';
      NO_IO_CHECK='Both';
      NO_ASSERT_CHECK='TRUE';
      NO_DIR_CHECK='TRUE';
      ALLOW_CONNECT='TRUE';
    'VSS749':
      PIN_NUMBER='(0,0,0,0,0,0,0,0,0,0,0,0,0,0,0,0,0,0,0,0,0,0,0,0,0,0,0,0,0,0,0,0,0,0,CK81,0,0,0,0,0,0,0)';
      PINUSE='POWER';
      NO_LOAD_CHECK='Both';
      NO_IO_CHECK='Both';
      NO_ASSERT_CHECK='TRUE';
      NO_DIR_CHECK='TRUE';
      ALLOW_CONNECT='TRUE';
    'VSS745':
      PIN_NUMBER='(0,0,0,0,0,0,0,0,0,0,0,0,0,0,0,0,0,0,0,0,0,0,0,0,0,0,0,0,0,0,0,0,0,0,CK69,0,0,0,0,0,0,0)';
      PINUSE='POWER';
      NO_LOAD_CHECK='Both';
      NO_IO_CHECK='Both';
      NO_ASSERT_CHECK='TRUE';
      NO_DIR_CHECK='TRUE';
      ALLOW_CONNECT='TRUE';
    'VSS744':
      PIN_NUMBER='(0,0,0,0,0,0,0,0,0,0,0,0,0,0,0,0,0,0,0,0,0,0,0,0,0,0,0,0,0,0,0,0,0,0,CK63,0,0,0,0,0,0,0)';
      PINUSE='POWER';
      NO_LOAD_CHECK='Both';
      NO_IO_CHECK='Both';
      NO_ASSERT_CHECK='TRUE';
      NO_DIR_CHECK='TRUE';
      ALLOW_CONNECT='TRUE';
    'VSS719':
      PIN_NUMBER='(0,0,0,0,0,0,0,0,0,0,0,0,0,0,0,0,0,0,0,0,0,0,0,0,0,0,0,0,0,0,0,0,0,0,DB75,0,0,0,0,0,0,0)';
      PINUSE='POWER';
      NO_LOAD_CHECK='Both';
      NO_IO_CHECK='Both';
      NO_ASSERT_CHECK='TRUE';
      NO_DIR_CHECK='TRUE';
      ALLOW_CONNECT='TRUE';
    'VSS717':
      PIN_NUMBER='(0,0,0,0,0,0,0,0,0,0,0,0,0,0,0,0,0,0,0,0,0,0,0,0,0,0,0,0,0,0,0,0,0,0,DB69,0,0,0,0,0,0,0)';
      PINUSE='POWER';
      NO_LOAD_CHECK='Both';
      NO_IO_CHECK='Both';
      NO_ASSERT_CHECK='TRUE';
      NO_DIR_CHECK='TRUE';
      ALLOW_CONNECT='TRUE';
    'VSS715':
      PIN_NUMBER='(0,0,0,0,0,0,0,0,0,0,0,0,0,0,0,0,0,0,0,0,0,0,0,0,0,0,0,0,0,0,0,0,0,0,DB63,0,0,0,0,0,0,0)';
      PINUSE='POWER';
      NO_LOAD_CHECK='Both';
      NO_IO_CHECK='Both';
      NO_ASSERT_CHECK='TRUE';
      NO_DIR_CHECK='TRUE';
      ALLOW_CONNECT='TRUE';
    'VSS714':
      PIN_NUMBER='(0,0,0,0,0,0,0,0,0,0,0,0,0,0,0,0,0,0,0,0,0,0,0,0,0,0,0,0,0,0,0,0,0,0,DB59,0,0,0,0,0,0,0)';
      PINUSE='POWER';
      NO_LOAD_CHECK='Both';
      NO_IO_CHECK='Both';
      NO_ASSERT_CHECK='TRUE';
      NO_DIR_CHECK='TRUE';
      ALLOW_CONNECT='TRUE';
    'VSS712':
      PIN_NUMBER='(0,0,0,0,0,0,0,0,0,0,0,0,0,0,0,0,0,0,0,0,0,0,0,0,0,0,0,0,0,0,0,0,0,0,DB53,0,0,0,0,0,0,0)';
      PINUSE='POWER';
      NO_LOAD_CHECK='Both';
      NO_IO_CHECK='Both';
      NO_ASSERT_CHECK='TRUE';
      NO_DIR_CHECK='TRUE';
      ALLOW_CONNECT='TRUE';
    'VSS711':
      PIN_NUMBER='(0,0,0,0,0,0,0,0,0,0,0,0,0,0,0,0,0,0,0,0,0,0,0,0,0,0,0,0,0,0,0,0,0,0,DB51,0,0,0,0,0,0,0)';
      PINUSE='POWER';
      NO_LOAD_CHECK='Both';
      NO_IO_CHECK='Both';
      NO_ASSERT_CHECK='TRUE';
      NO_DIR_CHECK='TRUE';
      ALLOW_CONNECT='TRUE';
    'VSS709':
      PIN_NUMBER='(0,0,0,0,0,0,0,0,0,0,0,0,0,0,0,0,0,0,0,0,0,0,0,0,0,0,0,0,0,0,0,0,0,0,DB44,0,0,0,0,0,0,0)';
      PINUSE='POWER';
      NO_LOAD_CHECK='Both';
      NO_IO_CHECK='Both';
      NO_ASSERT_CHECK='TRUE';
      NO_DIR_CHECK='TRUE';
      ALLOW_CONNECT='TRUE';
    'VSS705':
      PIN_NUMBER='(0,0,0,0,0,0,0,0,0,0,0,0,0,0,0,0,0,0,0,0,0,0,0,0,0,0,0,0,0,0,0,0,0,0,DB34,0,0,0,0,0,0,0)';
      PINUSE='POWER';
      NO_LOAD_CHECK='Both';
      NO_IO_CHECK='Both';
      NO_ASSERT_CHECK='TRUE';
      NO_DIR_CHECK='TRUE';
      ALLOW_CONNECT='TRUE';
    'VSS702':
      PIN_NUMBER='(0,0,0,0,0,0,0,0,0,0,0,0,0,0,0,0,0,0,0,0,0,0,0,0,0,0,0,0,0,0,0,0,0,0,DB26,0,0,0,0,0,0,0)';
      PINUSE='POWER';
      NO_LOAD_CHECK='Both';
      NO_IO_CHECK='Both';
      NO_ASSERT_CHECK='TRUE';
      NO_DIR_CHECK='TRUE';
      ALLOW_CONNECT='TRUE';
    'VSS700':
      PIN_NUMBER='(0,0,0,0,0,0,0,0,0,0,0,0,0,0,0,0,0,0,0,0,0,0,0,0,0,0,0,0,0,0,0,0,0,0,DB20,0,0,0,0,0,0,0)';
      PINUSE='POWER';
      NO_LOAD_CHECK='Both';
      NO_IO_CHECK='Both';
      NO_ASSERT_CHECK='TRUE';
      NO_DIR_CHECK='TRUE';
      ALLOW_CONNECT='TRUE';
    'VSS699':
      PIN_NUMBER='(0,0,0,0,0,0,0,0,0,0,0,0,0,0,0,0,0,0,0,0,0,0,0,0,0,0,0,0,0,0,0,0,0,0,DB16,0,0,0,0,0,0,0)';
      PINUSE='POWER';
      NO_LOAD_CHECK='Both';
      NO_IO_CHECK='Both';
      NO_ASSERT_CHECK='TRUE';
      NO_DIR_CHECK='TRUE';
      ALLOW_CONNECT='TRUE';
    'VSS690':
      PIN_NUMBER='(0,0,0,0,0,0,0,0,0,0,0,0,0,0,0,0,0,0,0,0,0,0,0,0,0,0,0,0,0,0,0,0,0,0,DA68,0,0,0,0,0,0,0)';
      PINUSE='POWER';
      NO_LOAD_CHECK='Both';
      NO_IO_CHECK='Both';
      NO_ASSERT_CHECK='TRUE';
      NO_DIR_CHECK='TRUE';
      ALLOW_CONNECT='TRUE';
    'VSS679':
      PIN_NUMBER='(0,0,0,0,0,0,0,0,0,0,0,0,0,0,0,0,0,0,0,0,0,0,0,0,0,0,0,0,0,0,0,0,0,0,DA43,0,0,0,0,0,0,0)';
      PINUSE='POWER';
      NO_LOAD_CHECK='Both';
      NO_IO_CHECK='Both';
      NO_ASSERT_CHECK='TRUE';
      NO_DIR_CHECK='TRUE';
      ALLOW_CONNECT='TRUE';
    'VSS611':
      PIN_NUMBER='(0,0,0,0,0,0,0,0,0,0,0,0,0,0,0,0,0,0,0,0,0,0,0,0,0,0,0,0,0,0,0,0,0,0,CY4,0,0,0,0,0,0,0)';
      PINUSE='POWER';
      NO_LOAD_CHECK='Both';
      NO_IO_CHECK='Both';
      NO_ASSERT_CHECK='TRUE';
      NO_DIR_CHECK='TRUE';
      ALLOW_CONNECT='TRUE';
    'VSS595':
      PIN_NUMBER='(0,0,0,0,0,0,0,0,0,0,0,0,0,0,0,0,0,0,0,0,0,0,0,0,0,0,0,0,0,0,0,0,0,0,CW70,0,0,0,0,0,0,0)';
      PINUSE='POWER';
      NO_LOAD_CHECK='Both';
      NO_IO_CHECK='Both';
      NO_ASSERT_CHECK='TRUE';
      NO_DIR_CHECK='TRUE';
      ALLOW_CONNECT='TRUE';
    'VSS583':
      PIN_NUMBER='(0,0,0,0,0,0,0,0,0,0,0,0,0,0,0,0,0,0,0,0,0,0,0,0,0,0,0,0,0,0,0,0,0,0,CW33,0,0,0,0,0,0,0)';
      PINUSE='POWER';
      NO_LOAD_CHECK='Both';
      NO_IO_CHECK='Both';
      NO_ASSERT_CHECK='TRUE';
      NO_DIR_CHECK='TRUE';
      ALLOW_CONNECT='TRUE';
    'VSS571':
      PIN_NUMBER='(0,0,0,0,0,0,0,0,0,0,0,0,0,0,0,0,0,0,0,0,0,0,0,0,0,0,0,0,0,0,0,0,0,0,CV79,0,0,0,0,0,0,0)';
      PINUSE='POWER';
      NO_LOAD_CHECK='Both';
      NO_IO_CHECK='Both';
      NO_ASSERT_CHECK='TRUE';
      NO_DIR_CHECK='TRUE';
      ALLOW_CONNECT='TRUE';
    'VSS562':
      PIN_NUMBER='(0,0,0,0,0,0,0,0,0,0,0,0,0,0,0,0,0,0,0,0,0,0,0,0,0,0,0,0,0,0,0,0,0,0,CV26,0,0,0,0,0,0,0)';
      PINUSE='POWER';
      NO_LOAD_CHECK='Both';
      NO_IO_CHECK='Both';
      NO_ASSERT_CHECK='TRUE';
      NO_DIR_CHECK='TRUE';
      ALLOW_CONNECT='TRUE';
    'VSS558':
      PIN_NUMBER='(0,0,0,0,0,0,0,0,0,0,0,0,0,0,0,0,0,0,0,0,0,0,0,0,0,0,0,0,0,0,0,0,0,0,CV16,0,0,0,0,0,0,0)';
      PINUSE='POWER';
      NO_LOAD_CHECK='Both';
      NO_IO_CHECK='Both';
      NO_ASSERT_CHECK='TRUE';
      NO_DIR_CHECK='TRUE';
      ALLOW_CONNECT='TRUE';
    'VSS554':
      PIN_NUMBER='(0,0,0,0,0,0,0,0,0,0,0,0,0,0,0,0,0,0,0,0,0,0,0,0,0,0,0,0,0,0,0,0,0,0,CU78,0,0,0,0,0,0,0)';
      PINUSE='POWER';
      NO_LOAD_CHECK='Both';
      NO_IO_CHECK='Both';
      NO_ASSERT_CHECK='TRUE';
      NO_DIR_CHECK='TRUE';
      ALLOW_CONNECT='TRUE';
    'VSS553':
      PIN_NUMBER='(0,0,0,0,0,0,0,0,0,0,0,0,0,0,0,0,0,0,0,0,0,0,0,0,0,0,0,0,0,0,0,0,0,0,CU72,0,0,0,0,0,0,0)';
      PINUSE='POWER';
      NO_LOAD_CHECK='Both';
      NO_IO_CHECK='Both';
      NO_ASSERT_CHECK='TRUE';
      NO_DIR_CHECK='TRUE';
      ALLOW_CONNECT='TRUE';
    'VSS544':
      PIN_NUMBER='(0,0,0,0,0,0,0,0,0,0,0,0,0,0,0,0,0,0,0,0,0,0,0,0,0,0,0,0,0,0,0,0,0,0,CU25,0,0,0,0,0,0,0)';
      PINUSE='POWER';
      NO_LOAD_CHECK='Both';
      NO_IO_CHECK='Both';
      NO_ASSERT_CHECK='TRUE';
      NO_DIR_CHECK='TRUE';
      ALLOW_CONNECT='TRUE';
    'VSS537':
      PIN_NUMBER='(0,0,0,0,0,0,0,0,0,0,0,0,0,0,0,0,0,0,0,0,0,0,0,0,0,0,0,0,0,0,0,0,0,0,CT89,0,0,0,0,0,0,0)';
      PINUSE='POWER';
      NO_LOAD_CHECK='Both';
      NO_IO_CHECK='Both';
      NO_ASSERT_CHECK='TRUE';
      NO_DIR_CHECK='TRUE';
      ALLOW_CONNECT='TRUE';
    'VSS534':
      PIN_NUMBER='(0,0,0,0,0,0,0,0,0,0,0,0,0,0,0,0,0,0,0,0,0,0,0,0,0,0,0,0,0,0,0,0,0,0,CT8,0,0,0,0,0,0,0)';
      PINUSE='POWER';
      NO_LOAD_CHECK='Both';
      NO_IO_CHECK='Both';
      NO_ASSERT_CHECK='TRUE';
      NO_DIR_CHECK='TRUE';
      ALLOW_CONNECT='TRUE';
    'VSS526':
      PIN_NUMBER='(0,0,0,0,0,0,0,0,0,0,0,0,0,0,0,0,0,0,0,0,0,0,0,0,0,0,0,0,0,0,0,0,0,0,CT4,0,0,0,0,0,0,0)';
      PINUSE='POWER';
      NO_LOAD_CHECK='Both';
      NO_IO_CHECK='Both';
      NO_ASSERT_CHECK='TRUE';
      NO_DIR_CHECK='TRUE';
      ALLOW_CONNECT='TRUE';
    'VSS521':
      PIN_NUMBER='(0,0,0,0,0,0,0,0,0,0,0,0,0,0,0,0,0,0,0,0,0,0,0,0,0,0,0,0,0,0,0,0,0,0,CT16,0,0,0,0,0,0,0)';
      PINUSE='POWER';
      NO_LOAD_CHECK='Both';
      NO_IO_CHECK='Both';
      NO_ASSERT_CHECK='TRUE';
      NO_DIR_CHECK='TRUE';
      ALLOW_CONNECT='TRUE';
    'VSS514':
      PIN_NUMBER='(0,0,0,0,0,0,0,0,0,0,0,0,0,0,0,0,0,0,0,0,0,0,0,0,0,0,0,0,0,0,0,0,0,0,CR78,0,0,0,0,0,0,0)';
      PINUSE='POWER';
      NO_LOAD_CHECK='Both';
      NO_IO_CHECK='Both';
      NO_ASSERT_CHECK='TRUE';
      NO_DIR_CHECK='TRUE';
      ALLOW_CONNECT='TRUE';
    'VSS493':
      PIN_NUMBER='(0,0,0,0,0,0,0,0,0,0,0,0,0,0,0,0,0,0,0,0,0,0,0,0,0,0,0,0,0,0,0,0,0,0,CP79,0,0,0,0,0,0,0)';
      PINUSE='POWER';
      NO_LOAD_CHECK='Both';
      NO_IO_CHECK='Both';
      NO_ASSERT_CHECK='TRUE';
      NO_DIR_CHECK='TRUE';
      ALLOW_CONNECT='TRUE';
    'VSS478':
      PIN_NUMBER='(0,0,0,0,0,0,0,0,0,0,0,0,0,0,0,0,0,0,0,0,0,0,0,0,0,0,0,0,0,0,0,0,0,0,CP16,0,0,0,0,0,0,0)';
      PINUSE='POWER';
      NO_LOAD_CHECK='Both';
      NO_IO_CHECK='Both';
      NO_ASSERT_CHECK='TRUE';
      NO_DIR_CHECK='TRUE';
      ALLOW_CONNECT='TRUE';
    'VSS471':
      PIN_NUMBER='(0,0,0,0,0,0,0,0,0,0,0,0,0,0,0,0,0,0,0,0,0,0,0,0,0,0,0,0,0,0,0,0,0,0,CN76,0,0,0,0,0,0,0)';
      PINUSE='POWER';
      NO_LOAD_CHECK='Both';
      NO_IO_CHECK='Both';
      NO_ASSERT_CHECK='TRUE';
      NO_DIR_CHECK='TRUE';
      ALLOW_CONNECT='TRUE';
    'VSS438':
      PIN_NUMBER='(0,0,0,0,0,0,0,0,0,0,0,0,0,0,0,0,0,0,0,0,0,0,0,0,0,0,0,0,0,0,0,0,0,0,CM22,0,0,0,0,0,0,0)';
      PINUSE='POWER';
      NO_LOAD_CHECK='Both';
      NO_IO_CHECK='Both';
      NO_ASSERT_CHECK='TRUE';
      NO_DIR_CHECK='TRUE';
      ALLOW_CONNECT='TRUE';
    'VSS436':
      PIN_NUMBER='(0,0,0,0,0,0,0,0,0,0,0,0,0,0,0,0,0,0,0,0,0,0,0,0,0,0,0,0,0,0,0,0,0,0,CM16,0,0,0,0,0,0,0)';
      PINUSE='POWER';
      NO_LOAD_CHECK='Both';
      NO_IO_CHECK='Both';
      NO_ASSERT_CHECK='TRUE';
      NO_DIR_CHECK='TRUE';
      ALLOW_CONNECT='TRUE';
    'VSS746':
      PIN_NUMBER='(0,0,0,0,0,0,0,0,0,0,0,0,0,0,0,0,0,0,0,0,0,0,0,0,0,0,0,0,0,0,0,0,0,0,0,CK8,0,0,0,0,0,0)';
      PINUSE='POWER';
      NO_LOAD_CHECK='Both';
      NO_IO_CHECK='Both';
      NO_ASSERT_CHECK='TRUE';
      NO_DIR_CHECK='TRUE';
      ALLOW_CONNECT='TRUE';
    'VSS743':
      PIN_NUMBER='(0,0,0,0,0,0,0,0,0,0,0,0,0,0,0,0,0,0,0,0,0,0,0,0,0,0,0,0,0,0,0,0,0,0,0,CK26,0,0,0,0,0,0)';
      PINUSE='POWER';
      NO_LOAD_CHECK='Both';
      NO_IO_CHECK='Both';
      NO_ASSERT_CHECK='TRUE';
      NO_DIR_CHECK='TRUE';
      ALLOW_CONNECT='TRUE';
    'VSS742':
      PIN_NUMBER='(0,0,0,0,0,0,0,0,0,0,0,0,0,0,0,0,0,0,0,0,0,0,0,0,0,0,0,0,0,0,0,0,0,0,0,CK20,0,0,0,0,0,0)';
      PINUSE='POWER';
      NO_LOAD_CHECK='Both';
      NO_IO_CHECK='Both';
      NO_ASSERT_CHECK='TRUE';
      NO_DIR_CHECK='TRUE';
      ALLOW_CONNECT='TRUE';
    'VSS741':
      PIN_NUMBER='(0,0,0,0,0,0,0,0,0,0,0,0,0,0,0,0,0,0,0,0,0,0,0,0,0,0,0,0,0,0,0,0,0,0,0,CK16,0,0,0,0,0,0)';
      PINUSE='POWER';
      NO_LOAD_CHECK='Both';
      NO_IO_CHECK='Both';
      NO_ASSERT_CHECK='TRUE';
      NO_DIR_CHECK='TRUE';
      ALLOW_CONNECT='TRUE';
    'VSS740':
      PIN_NUMBER='(0,0,0,0,0,0,0,0,0,0,0,0,0,0,0,0,0,0,0,0,0,0,0,0,0,0,0,0,0,0,0,0,0,0,0,CK12,0,0,0,0,0,0)';
      PINUSE='POWER';
      NO_LOAD_CHECK='Both';
      NO_IO_CHECK='Both';
      NO_ASSERT_CHECK='TRUE';
      NO_DIR_CHECK='TRUE';
      ALLOW_CONNECT='TRUE';
    'VSS737':
      PIN_NUMBER='(0,0,0,0,0,0,0,0,0,0,0,0,0,0,0,0,0,0,0,0,0,0,0,0,0,0,0,0,0,0,0,0,0,0,0,CJ80,0,0,0,0,0,0)';
      PINUSE='POWER';
      NO_LOAD_CHECK='Both';
      NO_IO_CHECK='Both';
      NO_ASSERT_CHECK='TRUE';
      NO_DIR_CHECK='TRUE';
      ALLOW_CONNECT='TRUE';
    'VSS736':
      PIN_NUMBER='(0,0,0,0,0,0,0,0,0,0,0,0,0,0,0,0,0,0,0,0,0,0,0,0,0,0,0,0,0,0,0,0,0,0,0,CJ60,0,0,0,0,0,0)';
      PINUSE='POWER';
      NO_LOAD_CHECK='Both';
      NO_IO_CHECK='Both';
      NO_ASSERT_CHECK='TRUE';
      NO_DIR_CHECK='TRUE';
      ALLOW_CONNECT='TRUE';
    'VSS734':
      PIN_NUMBER='(0,0,0,0,0,0,0,0,0,0,0,0,0,0,0,0,0,0,0,0,0,0,0,0,0,0,0,0,0,0,0,0,0,0,0,CH89,0,0,0,0,0,0)';
      PINUSE='POWER';
      NO_LOAD_CHECK='Both';
      NO_IO_CHECK='Both';
      NO_ASSERT_CHECK='TRUE';
      NO_DIR_CHECK='TRUE';
      ALLOW_CONNECT='TRUE';
    'VSS733':
      PIN_NUMBER='(0,0,0,0,0,0,0,0,0,0,0,0,0,0,0,0,0,0,0,0,0,0,0,0,0,0,0,0,0,0,0,0,0,0,0,CH87,0,0,0,0,0,0)';
      PINUSE='POWER';
      NO_LOAD_CHECK='Both';
      NO_IO_CHECK='Both';
      NO_ASSERT_CHECK='TRUE';
      NO_DIR_CHECK='TRUE';
      ALLOW_CONNECT='TRUE';
    'VSS732':
      PIN_NUMBER='(0,0,0,0,0,0,0,0,0,0,0,0,0,0,0,0,0,0,0,0,0,0,0,0,0,0,0,0,0,0,0,0,0,0,0,CH85,0,0,0,0,0,0)';
      PINUSE='POWER';
      NO_LOAD_CHECK='Both';
      NO_IO_CHECK='Both';
      NO_ASSERT_CHECK='TRUE';
      NO_DIR_CHECK='TRUE';
      ALLOW_CONNECT='TRUE';
    'VSS731':
      PIN_NUMBER='(0,0,0,0,0,0,0,0,0,0,0,0,0,0,0,0,0,0,0,0,0,0,0,0,0,0,0,0,0,0,0,0,0,0,0,CH83,0,0,0,0,0,0)';
      PINUSE='POWER';
      NO_LOAD_CHECK='Both';
      NO_IO_CHECK='Both';
      NO_ASSERT_CHECK='TRUE';
      NO_DIR_CHECK='TRUE';
      ALLOW_CONNECT='TRUE';
    'VSS730':
      PIN_NUMBER='(0,0,0,0,0,0,0,0,0,0,0,0,0,0,0,0,0,0,0,0,0,0,0,0,0,0,0,0,0,0,0,0,0,0,0,CH8,0,0,0,0,0,0)';
      PINUSE='POWER';
      NO_LOAD_CHECK='Both';
      NO_IO_CHECK='Both';
      NO_ASSERT_CHECK='TRUE';
      NO_DIR_CHECK='TRUE';
      ALLOW_CONNECT='TRUE';
    'VSS729':
      PIN_NUMBER='(0,0,0,0,0,0,0,0,0,0,0,0,0,0,0,0,0,0,0,0,0,0,0,0,0,0,0,0,0,0,0,0,0,0,0,CH79,0,0,0,0,0,0)';
      PINUSE='POWER';
      NO_LOAD_CHECK='Both';
      NO_IO_CHECK='Both';
      NO_ASSERT_CHECK='TRUE';
      NO_DIR_CHECK='TRUE';
      ALLOW_CONNECT='TRUE';
    'VSS728':
      PIN_NUMBER='(0,0,0,0,0,0,0,0,0,0,0,0,0,0,0,0,0,0,0,0,0,0,0,0,0,0,0,0,0,0,0,0,0,0,0,CH73,0,0,0,0,0,0)';
      PINUSE='POWER';
      NO_LOAD_CHECK='Both';
      NO_IO_CHECK='Both';
      NO_ASSERT_CHECK='TRUE';
      NO_DIR_CHECK='TRUE';
      ALLOW_CONNECT='TRUE';
    'VSS727':
      PIN_NUMBER='(0,0,0,0,0,0,0,0,0,0,0,0,0,0,0,0,0,0,0,0,0,0,0,0,0,0,0,0,0,0,0,0,0,0,0,CH67,0,0,0,0,0,0)';
      PINUSE='POWER';
      NO_LOAD_CHECK='Both';
      NO_IO_CHECK='Both';
      NO_ASSERT_CHECK='TRUE';
      NO_DIR_CHECK='TRUE';
      ALLOW_CONNECT='TRUE';
    'VSS722':
      PIN_NUMBER='(0,0,0,0,0,0,0,0,0,0,0,0,0,0,0,0,0,0,0,0,0,0,0,0,0,0,0,0,0,0,0,0,0,0,0,CH4,0,0,0,0,0,0)';
      PINUSE='POWER';
      NO_LOAD_CHECK='Both';
      NO_IO_CHECK='Both';
      NO_ASSERT_CHECK='TRUE';
      NO_DIR_CHECK='TRUE';
      ALLOW_CONNECT='TRUE';
    'VSS721':
      PIN_NUMBER='(0,0,0,0,0,0,0,0,0,0,0,0,0,0,0,0,0,0,0,0,0,0,0,0,0,0,0,0,0,0,0,0,0,0,0,CH20,0,0,0,0,0,0)';
      PINUSE='POWER';
      NO_LOAD_CHECK='Both';
      NO_IO_CHECK='Both';
      NO_ASSERT_CHECK='TRUE';
      NO_DIR_CHECK='TRUE';
      ALLOW_CONNECT='TRUE';
    'VSS720':
      PIN_NUMBER='(0,0,0,0,0,0,0,0,0,0,0,0,0,0,0,0,0,0,0,0,0,0,0,0,0,0,0,0,0,0,0,0,0,0,0,CH16,0,0,0,0,0,0)';
      PINUSE='POWER';
      NO_LOAD_CHECK='Both';
      NO_IO_CHECK='Both';
      NO_ASSERT_CHECK='TRUE';
      NO_DIR_CHECK='TRUE';
      ALLOW_CONNECT='TRUE';
    'VSS718':
      PIN_NUMBER='(0,0,0,0,0,0,0,0,0,0,0,0,0,0,0,0,0,0,0,0,0,0,0,0,0,0,0,0,0,0,0,0,0,0,0,CH12,0,0,0,0,0,0)';
      PINUSE='POWER';
      NO_LOAD_CHECK='Both';
      NO_IO_CHECK='Both';
      NO_ASSERT_CHECK='TRUE';
      NO_DIR_CHECK='TRUE';
      ALLOW_CONNECT='TRUE';
    'VSS716':
      PIN_NUMBER='(0,0,0,0,0,0,0,0,0,0,0,0,0,0,0,0,0,0,0,0,0,0,0,0,0,0,0,0,0,0,0,0,0,0,0,CG9,0,0,0,0,0,0)';
      PINUSE='POWER';
      NO_LOAD_CHECK='Both';
      NO_IO_CHECK='Both';
      NO_ASSERT_CHECK='TRUE';
      NO_DIR_CHECK='TRUE';
      ALLOW_CONNECT='TRUE';
    'VSS713':
      PIN_NUMBER='(0,0,0,0,0,0,0,0,0,0,0,0,0,0,0,0,0,0,0,0,0,0,0,0,0,0,0,0,0,0,0,0,0,0,0,CG78,0,0,0,0,0,0)';
      PINUSE='POWER';
      NO_LOAD_CHECK='Both';
      NO_IO_CHECK='Both';
      NO_ASSERT_CHECK='TRUE';
      NO_DIR_CHECK='TRUE';
      ALLOW_CONNECT='TRUE';
    'VSS710':
      PIN_NUMBER='(0,0,0,0,0,0,0,0,0,0,0,0,0,0,0,0,0,0,0,0,0,0,0,0,0,0,0,0,0,0,0,0,0,0,0,CG74,0,0,0,0,0,0)';
      PINUSE='POWER';
      NO_LOAD_CHECK='Both';
      NO_IO_CHECK='Both';
      NO_ASSERT_CHECK='TRUE';
      NO_DIR_CHECK='TRUE';
      ALLOW_CONNECT='TRUE';
    'VSS708':
      PIN_NUMBER='(0,0,0,0,0,0,0,0,0,0,0,0,0,0,0,0,0,0,0,0,0,0,0,0,0,0,0,0,0,0,0,0,0,0,0,CG72,0,0,0,0,0,0)';
      PINUSE='POWER';
      NO_LOAD_CHECK='Both';
      NO_IO_CHECK='Both';
      NO_ASSERT_CHECK='TRUE';
      NO_DIR_CHECK='TRUE';
      ALLOW_CONNECT='TRUE';
    'VSS707':
      PIN_NUMBER='(0,0,0,0,0,0,0,0,0,0,0,0,0,0,0,0,0,0,0,0,0,0,0,0,0,0,0,0,0,0,0,0,0,0,0,CG70,0,0,0,0,0,0)';
      PINUSE='POWER';
      NO_LOAD_CHECK='Both';
      NO_IO_CHECK='Both';
      NO_ASSERT_CHECK='TRUE';
      NO_DIR_CHECK='TRUE';
      ALLOW_CONNECT='TRUE';
    'VSS706':
      PIN_NUMBER='(0,0,0,0,0,0,0,0,0,0,0,0,0,0,0,0,0,0,0,0,0,0,0,0,0,0,0,0,0,0,0,0,0,0,0,CG64,0,0,0,0,0,0)';
      PINUSE='POWER';
      NO_LOAD_CHECK='Both';
      NO_IO_CHECK='Both';
      NO_ASSERT_CHECK='TRUE';
      NO_DIR_CHECK='TRUE';
      ALLOW_CONNECT='TRUE';
    'VSS704':
      PIN_NUMBER='(0,0,0,0,0,0,0,0,0,0,0,0,0,0,0,0,0,0,0,0,0,0,0,0,0,0,0,0,0,0,0,0,0,0,0,CG62,0,0,0,0,0,0)';
      PINUSE='POWER';
      NO_LOAD_CHECK='Both';
      NO_IO_CHECK='Both';
      NO_ASSERT_CHECK='TRUE';
      NO_DIR_CHECK='TRUE';
      ALLOW_CONNECT='TRUE';
    'VSS703':
      PIN_NUMBER='(0,0,0,0,0,0,0,0,0,0,0,0,0,0,0,0,0,0,0,0,0,0,0,0,0,0,0,0,0,0,0,0,0,0,0,CG5,0,0,0,0,0,0)';
      PINUSE='POWER';
      NO_LOAD_CHECK='Both';
      NO_IO_CHECK='Both';
      NO_ASSERT_CHECK='TRUE';
      NO_DIR_CHECK='TRUE';
      ALLOW_CONNECT='TRUE';
    'VSS701':
      PIN_NUMBER='(0,0,0,0,0,0,0,0,0,0,0,0,0,0,0,0,0,0,0,0,0,0,0,0,0,0,0,0,0,0,0,0,0,0,0,CG25,0,0,0,0,0,0)';
      PINUSE='POWER';
      NO_LOAD_CHECK='Both';
      NO_IO_CHECK='Both';
      NO_ASSERT_CHECK='TRUE';
      NO_DIR_CHECK='TRUE';
      ALLOW_CONNECT='TRUE';
    'VSS698':
      PIN_NUMBER='(0,0,0,0,0,0,0,0,0,0,0,0,0,0,0,0,0,0,0,0,0,0,0,0,0,0,0,0,0,0,0,0,0,0,0,CG23,0,0,0,0,0,0)';
      PINUSE='POWER';
      NO_LOAD_CHECK='Both';
      NO_IO_CHECK='Both';
      NO_ASSERT_CHECK='TRUE';
      NO_DIR_CHECK='TRUE';
      ALLOW_CONNECT='TRUE';
    'VSS697':
      PIN_NUMBER='(0,0,0,0,0,0,0,0,0,0,0,0,0,0,0,0,0,0,0,0,0,0,0,0,0,0,0,0,0,0,0,0,0,0,0,CG21,0,0,0,0,0,0)';
      PINUSE='POWER';
      NO_LOAD_CHECK='Both';
      NO_IO_CHECK='Both';
      NO_ASSERT_CHECK='TRUE';
      NO_DIR_CHECK='TRUE';
      ALLOW_CONNECT='TRUE';
    'VSS696':
      PIN_NUMBER='(0,0,0,0,0,0,0,0,0,0,0,0,0,0,0,0,0,0,0,0,0,0,0,0,0,0,0,0,0,0,0,0,0,0,0,CG17,0,0,0,0,0,0)';
      PINUSE='POWER';
      NO_LOAD_CHECK='Both';
      NO_IO_CHECK='Both';
      NO_ASSERT_CHECK='TRUE';
      NO_DIR_CHECK='TRUE';
      ALLOW_CONNECT='TRUE';
    'VSS695':
      PIN_NUMBER='(0,0,0,0,0,0,0,0,0,0,0,0,0,0,0,0,0,0,0,0,0,0,0,0,0,0,0,0,0,0,0,0,0,0,0,CG13,0,0,0,0,0,0)';
      PINUSE='POWER';
      NO_LOAD_CHECK='Both';
      NO_IO_CHECK='Both';
      NO_ASSERT_CHECK='TRUE';
      NO_DIR_CHECK='TRUE';
      ALLOW_CONNECT='TRUE';
    'VSS694':
      PIN_NUMBER='(0,0,0,0,0,0,0,0,0,0,0,0,0,0,0,0,0,0,0,0,0,0,0,0,0,0,0,0,0,0,0,0,0,0,0,CG1,0,0,0,0,0,0)';
      PINUSE='POWER';
      NO_LOAD_CHECK='Both';
      NO_IO_CHECK='Both';
      NO_ASSERT_CHECK='TRUE';
      NO_DIR_CHECK='TRUE';
      ALLOW_CONNECT='TRUE';
    'VSS693':
      PIN_NUMBER='(0,0,0,0,0,0,0,0,0,0,0,0,0,0,0,0,0,0,0,0,0,0,0,0,0,0,0,0,0,0,0,0,0,0,0,CF8,0,0,0,0,0,0)';
      PINUSE='POWER';
      NO_LOAD_CHECK='Both';
      NO_IO_CHECK='Both';
      NO_ASSERT_CHECK='TRUE';
      NO_DIR_CHECK='TRUE';
      ALLOW_CONNECT='TRUE';
    'VSS692':
      PIN_NUMBER='(0,0,0,0,0,0,0,0,0,0,0,0,0,0,0,0,0,0,0,0,0,0,0,0,0,0,0,0,0,0,0,0,0,0,0,CF71,0,0,0,0,0,0)';
      PINUSE='POWER';
      NO_LOAD_CHECK='Both';
      NO_IO_CHECK='Both';
      NO_ASSERT_CHECK='TRUE';
      NO_DIR_CHECK='TRUE';
      ALLOW_CONNECT='TRUE';
    'VSS691':
      PIN_NUMBER='(0,0,0,0,0,0,0,0,0,0,0,0,0,0,0,0,0,0,0,0,0,0,0,0,0,0,0,0,0,0,0,0,0,0,0,CF69,0,0,0,0,0,0)';
      PINUSE='POWER';
      NO_LOAD_CHECK='Both';
      NO_IO_CHECK='Both';
      NO_ASSERT_CHECK='TRUE';
      NO_DIR_CHECK='TRUE';
      ALLOW_CONNECT='TRUE';
    'VSS689':
      PIN_NUMBER='(0,0,0,0,0,0,0,0,0,0,0,0,0,0,0,0,0,0,0,0,0,0,0,0,0,0,0,0,0,0,0,0,0,0,0,CF4,0,0,0,0,0,0)';
      PINUSE='POWER';
      NO_LOAD_CHECK='Both';
      NO_IO_CHECK='Both';
      NO_ASSERT_CHECK='TRUE';
      NO_DIR_CHECK='TRUE';
      ALLOW_CONNECT='TRUE';
    'VSS688':
      PIN_NUMBER='(0,0,0,0,0,0,0,0,0,0,0,0,0,0,0,0,0,0,0,0,0,0,0,0,0,0,0,0,0,0,0,0,0,0,0,CF20,0,0,0,0,0,0)';
      PINUSE='POWER';
      NO_LOAD_CHECK='Both';
      NO_IO_CHECK='Both';
      NO_ASSERT_CHECK='TRUE';
      NO_DIR_CHECK='TRUE';
      ALLOW_CONNECT='TRUE';
    'VSS687':
      PIN_NUMBER='(0,0,0,0,0,0,0,0,0,0,0,0,0,0,0,0,0,0,0,0,0,0,0,0,0,0,0,0,0,0,0,0,0,0,0,CF16,0,0,0,0,0,0)';
      PINUSE='POWER';
      NO_LOAD_CHECK='Both';
      NO_IO_CHECK='Both';
      NO_ASSERT_CHECK='TRUE';
      NO_DIR_CHECK='TRUE';
      ALLOW_CONNECT='TRUE';
    'VSS686':
      PIN_NUMBER='(0,0,0,0,0,0,0,0,0,0,0,0,0,0,0,0,0,0,0,0,0,0,0,0,0,0,0,0,0,0,0,0,0,0,0,CF12,0,0,0,0,0,0)';
      PINUSE='POWER';
      NO_LOAD_CHECK='Both';
      NO_IO_CHECK='Both';
      NO_ASSERT_CHECK='TRUE';
      NO_DIR_CHECK='TRUE';
      ALLOW_CONNECT='TRUE';
    'VSS685':
      PIN_NUMBER='(0,0,0,0,0,0,0,0,0,0,0,0,0,0,0,0,0,0,0,0,0,0,0,0,0,0,0,0,0,0,0,0,0,0,0,CE78,0,0,0,0,0,0)';
      PINUSE='POWER';
      NO_LOAD_CHECK='Both';
      NO_IO_CHECK='Both';
      NO_ASSERT_CHECK='TRUE';
      NO_DIR_CHECK='TRUE';
      ALLOW_CONNECT='TRUE';
    'VSS684':
      PIN_NUMBER='(0,0,0,0,0,0,0,0,0,0,0,0,0,0,0,0,0,0,0,0,0,0,0,0,0,0,0,0,0,0,0,0,0,0,0,CE76,0,0,0,0,0,0)';
      PINUSE='POWER';
      NO_LOAD_CHECK='Both';
      NO_IO_CHECK='Both';
      NO_ASSERT_CHECK='TRUE';
      NO_DIR_CHECK='TRUE';
      ALLOW_CONNECT='TRUE';
    'VSS683':
      PIN_NUMBER='(0,0,0,0,0,0,0,0,0,0,0,0,0,0,0,0,0,0,0,0,0,0,0,0,0,0,0,0,0,0,0,0,0,0,0,CE72,0,0,0,0,0,0)';
      PINUSE='POWER';
      NO_LOAD_CHECK='Both';
      NO_IO_CHECK='Both';
      NO_ASSERT_CHECK='TRUE';
      NO_DIR_CHECK='TRUE';
      ALLOW_CONNECT='TRUE';
    'VSS682':
      PIN_NUMBER='(0,0,0,0,0,0,0,0,0,0,0,0,0,0,0,0,0,0,0,0,0,0,0,0,0,0,0,0,0,0,0,0,0,0,0,CE66,0,0,0,0,0,0)';
      PINUSE='POWER';
      NO_LOAD_CHECK='Both';
      NO_IO_CHECK='Both';
      NO_ASSERT_CHECK='TRUE';
      NO_DIR_CHECK='TRUE';
      ALLOW_CONNECT='TRUE';
    'VSS681':
      PIN_NUMBER='(0,0,0,0,0,0,0,0,0,0,0,0,0,0,0,0,0,0,0,0,0,0,0,0,0,0,0,0,0,0,0,0,0,0,0,CE60,0,0,0,0,0,0)';
      PINUSE='POWER';
      NO_LOAD_CHECK='Both';
      NO_IO_CHECK='Both';
      NO_ASSERT_CHECK='TRUE';
      NO_DIR_CHECK='TRUE';
      ALLOW_CONNECT='TRUE';
    'VSS680':
      PIN_NUMBER='(0,0,0,0,0,0,0,0,0,0,0,0,0,0,0,0,0,0,0,0,0,0,0,0,0,0,0,0,0,0,0,0,0,0,0,CE3,0,0,0,0,0,0)';
      PINUSE='POWER';
      NO_LOAD_CHECK='Both';
      NO_IO_CHECK='Both';
      NO_ASSERT_CHECK='TRUE';
      NO_DIR_CHECK='TRUE';
      ALLOW_CONNECT='TRUE';
    'VSS678':
      PIN_NUMBER='(0,0,0,0,0,0,0,0,0,0,0,0,0,0,0,0,0,0,0,0,0,0,0,0,0,0,0,0,0,0,0,0,0,0,0,CD8,0,0,0,0,0,0)';
      PINUSE='POWER';
      NO_LOAD_CHECK='Both';
      NO_IO_CHECK='Both';
      NO_ASSERT_CHECK='TRUE';
      NO_DIR_CHECK='TRUE';
      ALLOW_CONNECT='TRUE';
    'VSS677':
      PIN_NUMBER='(0,0,0,0,0,0,0,0,0,0,0,0,0,0,0,0,0,0,0,0,0,0,0,0,0,0,0,0,0,0,0,0,0,0,0,CD77,0,0,0,0,0,0)';
      PINUSE='POWER';
      NO_LOAD_CHECK='Both';
      NO_IO_CHECK='Both';
      NO_ASSERT_CHECK='TRUE';
      NO_DIR_CHECK='TRUE';
      ALLOW_CONNECT='TRUE';
    'VSS676':
      PIN_NUMBER='(0,0,0,0,0,0,0,0,0,0,0,0,0,0,0,0,0,0,0,0,0,0,0,0,0,0,0,0,0,0,0,0,0,0,0,CD75,0,0,0,0,0,0)';
      PINUSE='POWER';
      NO_LOAD_CHECK='Both';
      NO_IO_CHECK='Both';
      NO_ASSERT_CHECK='TRUE';
      NO_DIR_CHECK='TRUE';
      ALLOW_CONNECT='TRUE';
    'VSS675':
      PIN_NUMBER='(0,0,0,0,0,0,0,0,0,0,0,0,0,0,0,0,0,0,0,0,0,0,0,0,0,0,0,0,0,0,0,0,0,0,0,CD61,0,0,0,0,0,0)';
      PINUSE='POWER';
      NO_LOAD_CHECK='Both';
      NO_IO_CHECK='Both';
      NO_ASSERT_CHECK='TRUE';
      NO_DIR_CHECK='TRUE';
      ALLOW_CONNECT='TRUE';
    'VSS674':
      PIN_NUMBER='(0,0,0,0,0,0,0,0,0,0,0,0,0,0,0,0,0,0,0,0,0,0,0,0,0,0,0,0,0,0,0,0,0,0,0,CD4,0,0,0,0,0,0)';
      PINUSE='POWER';
      NO_LOAD_CHECK='Both';
      NO_IO_CHECK='Both';
      NO_ASSERT_CHECK='TRUE';
      NO_DIR_CHECK='TRUE';
      ALLOW_CONNECT='TRUE';
    'VSS673':
      PIN_NUMBER='(0,0,0,0,0,0,0,0,0,0,0,0,0,0,0,0,0,0,0,0,0,0,0,0,0,0,0,0,0,0,0,0,0,0,0,CD20,0,0,0,0,0,0)';
      PINUSE='POWER';
      NO_LOAD_CHECK='Both';
      NO_IO_CHECK='Both';
      NO_ASSERT_CHECK='TRUE';
      NO_DIR_CHECK='TRUE';
      ALLOW_CONNECT='TRUE';
    'VSS672':
      PIN_NUMBER='(0,0,0,0,0,0,0,0,0,0,0,0,0,0,0,0,0,0,0,0,0,0,0,0,0,0,0,0,0,0,0,0,0,0,0,CD16,0,0,0,0,0,0)';
      PINUSE='POWER';
      NO_LOAD_CHECK='Both';
      NO_IO_CHECK='Both';
      NO_ASSERT_CHECK='TRUE';
      NO_DIR_CHECK='TRUE';
      ALLOW_CONNECT='TRUE';
    'VSS671':
      PIN_NUMBER='(0,0,0,0,0,0,0,0,0,0,0,0,0,0,0,0,0,0,0,0,0,0,0,0,0,0,0,0,0,0,0,0,0,0,0,CD12,0,0,0,0,0,0)';
      PINUSE='POWER';
      NO_LOAD_CHECK='Both';
      NO_IO_CHECK='Both';
      NO_ASSERT_CHECK='TRUE';
      NO_DIR_CHECK='TRUE';
      ALLOW_CONNECT='TRUE';
    'VSS670':
      PIN_NUMBER='(0,0,0,0,0,0,0,0,0,0,0,0,0,0,0,0,0,0,0,0,0,0,0,0,0,0,0,0,0,0,0,0,0,0,0,CC9,0,0,0,0,0,0)';
      PINUSE='POWER';
      NO_LOAD_CHECK='Both';
      NO_IO_CHECK='Both';
      NO_ASSERT_CHECK='TRUE';
      NO_DIR_CHECK='TRUE';
      ALLOW_CONNECT='TRUE';
    'VSS669':
      PIN_NUMBER='(0,0,0,0,0,0,0,0,0,0,0,0,0,0,0,0,0,0,0,0,0,0,0,0,0,0,0,0,0,0,0,0,0,0,0,CC74,0,0,0,0,0,0)';
      PINUSE='POWER';
      NO_LOAD_CHECK='Both';
      NO_IO_CHECK='Both';
      NO_ASSERT_CHECK='TRUE';
      NO_DIR_CHECK='TRUE';
      ALLOW_CONNECT='TRUE';
    'VSS668':
      PIN_NUMBER='(0,0,0,0,0,0,0,0,0,0,0,0,0,0,0,0,0,0,0,0,0,0,0,0,0,0,0,0,0,0,0,0,0,0,0,CC72,0,0,0,0,0,0)';
      PINUSE='POWER';
      NO_LOAD_CHECK='Both';
      NO_IO_CHECK='Both';
      NO_ASSERT_CHECK='TRUE';
      NO_DIR_CHECK='TRUE';
      ALLOW_CONNECT='TRUE';
    'VSS667':
      PIN_NUMBER='(0,0,0,0,0,0,0,0,0,0,0,0,0,0,0,0,0,0,0,0,0,0,0,0,0,0,0,0,0,0,0,0,0,0,0,CC70,0,0,0,0,0,0)';
      PINUSE='POWER';
      NO_LOAD_CHECK='Both';
      NO_IO_CHECK='Both';
      NO_ASSERT_CHECK='TRUE';
      NO_DIR_CHECK='TRUE';
      ALLOW_CONNECT='TRUE';
    'VSS666':
      PIN_NUMBER='(0,0,0,0,0,0,0,0,0,0,0,0,0,0,0,0,0,0,0,0,0,0,0,0,0,0,0,0,0,0,0,0,0,0,0,CC62,0,0,0,0,0,0)';
      PINUSE='POWER';
      NO_LOAD_CHECK='Both';
      NO_IO_CHECK='Both';
      NO_ASSERT_CHECK='TRUE';
      NO_DIR_CHECK='TRUE';
      ALLOW_CONNECT='TRUE';
    'VSS665':
      PIN_NUMBER='(0,0,0,0,0,0,0,0,0,0,0,0,0,0,0,0,0,0,0,0,0,0,0,0,0,0,0,0,0,0,0,0,0,0,0,CC5,0,0,0,0,0,0)';
      PINUSE='POWER';
      NO_LOAD_CHECK='Both';
      NO_IO_CHECK='Both';
      NO_ASSERT_CHECK='TRUE';
      NO_DIR_CHECK='TRUE';
      ALLOW_CONNECT='TRUE';
    'VSS664':
      PIN_NUMBER='(0,0,0,0,0,0,0,0,0,0,0,0,0,0,0,0,0,0,0,0,0,0,0,0,0,0,0,0,0,0,0,0,0,0,0,CC31,0,0,0,0,0,0)';
      PINUSE='POWER';
      NO_LOAD_CHECK='Both';
      NO_IO_CHECK='Both';
      NO_ASSERT_CHECK='TRUE';
      NO_DIR_CHECK='TRUE';
      ALLOW_CONNECT='TRUE';
    'VSS661':
      PIN_NUMBER='(0,0,0,0,0,0,0,0,0,0,0,0,0,0,0,0,0,0,0,0,0,0,0,0,0,0,0,0,0,0,0,0,0,0,0,CC17,0,0,0,0,0,0)';
      PINUSE='POWER';
      NO_LOAD_CHECK='Both';
      NO_IO_CHECK='Both';
      NO_ASSERT_CHECK='TRUE';
      NO_DIR_CHECK='TRUE';
      ALLOW_CONNECT='TRUE';
    'VSS660':
      PIN_NUMBER='(0,0,0,0,0,0,0,0,0,0,0,0,0,0,0,0,0,0,0,0,0,0,0,0,0,0,0,0,0,0,0,0,0,0,0,CC13,0,0,0,0,0,0)';
      PINUSE='POWER';
      NO_LOAD_CHECK='Both';
      NO_IO_CHECK='Both';
      NO_ASSERT_CHECK='TRUE';
      NO_DIR_CHECK='TRUE';
      ALLOW_CONNECT='TRUE';
    'VSS656':
      PIN_NUMBER='(0,0,0,0,0,0,0,0,0,0,0,0,0,0,0,0,0,0,0,0,0,0,0,0,0,0,0,0,0,0,0,0,0,0,0,CB89,0,0,0,0,0,0)';
      PINUSE='POWER';
      NO_LOAD_CHECK='Both';
      NO_IO_CHECK='Both';
      NO_ASSERT_CHECK='TRUE';
      NO_DIR_CHECK='TRUE';
      ALLOW_CONNECT='TRUE';
    'VSS655':
      PIN_NUMBER='(0,0,0,0,0,0,0,0,0,0,0,0,0,0,0,0,0,0,0,0,0,0,0,0,0,0,0,0,0,0,0,0,0,0,0,CB87,0,0,0,0,0,0)';
      PINUSE='POWER';
      NO_LOAD_CHECK='Both';
      NO_IO_CHECK='Both';
      NO_ASSERT_CHECK='TRUE';
      NO_DIR_CHECK='TRUE';
      ALLOW_CONNECT='TRUE';
    'VSS654':
      PIN_NUMBER='(0,0,0,0,0,0,0,0,0,0,0,0,0,0,0,0,0,0,0,0,0,0,0,0,0,0,0,0,0,0,0,0,0,0,0,CB85,0,0,0,0,0,0)';
      PINUSE='POWER';
      NO_LOAD_CHECK='Both';
      NO_IO_CHECK='Both';
      NO_ASSERT_CHECK='TRUE';
      NO_DIR_CHECK='TRUE';
      ALLOW_CONNECT='TRUE';
    'VSS653':
      PIN_NUMBER='(0,0,0,0,0,0,0,0,0,0,0,0,0,0,0,0,0,0,0,0,0,0,0,0,0,0,0,0,0,0,0,0,0,0,0,CB83,0,0,0,0,0,0)';
      PINUSE='POWER';
      NO_LOAD_CHECK='Both';
      NO_IO_CHECK='Both';
      NO_ASSERT_CHECK='TRUE';
      NO_DIR_CHECK='TRUE';
      ALLOW_CONNECT='TRUE';
    'VSS652':
      PIN_NUMBER='(0,0,0,0,0,0,0,0,0,0,0,0,0,0,0,0,0,0,0,0,0,0,0,0,0,0,0,0,0,0,0,0,0,0,0,CB81,0,0,0,0,0,0)';
      PINUSE='POWER';
      NO_LOAD_CHECK='Both';
      NO_IO_CHECK='Both';
      NO_ASSERT_CHECK='TRUE';
      NO_DIR_CHECK='TRUE';
      ALLOW_CONNECT='TRUE';
    'VSS651':
      PIN_NUMBER='(0,0,0,0,0,0,0,0,0,0,0,0,0,0,0,0,0,0,0,0,0,0,0,0,0,0,0,0,0,0,0,0,0,0,0,CB8,0,0,0,0,0,0)';
      PINUSE='POWER';
      NO_LOAD_CHECK='Both';
      NO_IO_CHECK='Both';
      NO_ASSERT_CHECK='TRUE';
      NO_DIR_CHECK='TRUE';
      ALLOW_CONNECT='TRUE';
    'VSS650':
      PIN_NUMBER='(0,0,0,0,0,0,0,0,0,0,0,0,0,0,0,0,0,0,0,0,0,0,0,0,0,0,0,0,0,0,0,0,0,0,0,CB79,0,0,0,0,0,0)';
      PINUSE='POWER';
      NO_LOAD_CHECK='Both';
      NO_IO_CHECK='Both';
      NO_ASSERT_CHECK='TRUE';
      NO_DIR_CHECK='TRUE';
      ALLOW_CONNECT='TRUE';
    'VSS649':
      PIN_NUMBER='(0,0,0,0,0,0,0,0,0,0,0,0,0,0,0,0,0,0,0,0,0,0,0,0,0,0,0,0,0,0,0,0,0,0,0,CB73,0,0,0,0,0,0)';
      PINUSE='POWER';
      NO_LOAD_CHECK='Both';
      NO_IO_CHECK='Both';
      NO_ASSERT_CHECK='TRUE';
      NO_DIR_CHECK='TRUE';
      ALLOW_CONNECT='TRUE';
    'VSS648':
      PIN_NUMBER='(0,0,0,0,0,0,0,0,0,0,0,0,0,0,0,0,0,0,0,0,0,0,0,0,0,0,0,0,0,0,0,0,0,0,0,CB71,0,0,0,0,0,0)';
      PINUSE='POWER';
      NO_LOAD_CHECK='Both';
      NO_IO_CHECK='Both';
      NO_ASSERT_CHECK='TRUE';
      NO_DIR_CHECK='TRUE';
      ALLOW_CONNECT='TRUE';
    'VSS647':
      PIN_NUMBER='(0,0,0,0,0,0,0,0,0,0,0,0,0,0,0,0,0,0,0,0,0,0,0,0,0,0,0,0,0,0,0,0,0,0,0,CB69,0,0,0,0,0,0)';
      PINUSE='POWER';
      NO_LOAD_CHECK='Both';
      NO_IO_CHECK='Both';
      NO_ASSERT_CHECK='TRUE';
      NO_DIR_CHECK='TRUE';
      ALLOW_CONNECT='TRUE';
    'VSS646':
      PIN_NUMBER='(0,0,0,0,0,0,0,0,0,0,0,0,0,0,0,0,0,0,0,0,0,0,0,0,0,0,0,0,0,0,0,0,0,0,0,CB67,0,0,0,0,0,0)';
      PINUSE='POWER';
      NO_LOAD_CHECK='Both';
      NO_IO_CHECK='Both';
      NO_ASSERT_CHECK='TRUE';
      NO_DIR_CHECK='TRUE';
      ALLOW_CONNECT='TRUE';
    'VSS645':
      PIN_NUMBER='(0,0,0,0,0,0,0,0,0,0,0,0,0,0,0,0,0,0,0,0,0,0,0,0,0,0,0,0,0,0,0,0,0,0,0,CB65,0,0,0,0,0,0)';
      PINUSE='POWER';
      NO_LOAD_CHECK='Both';
      NO_IO_CHECK='Both';
      NO_ASSERT_CHECK='TRUE';
      NO_DIR_CHECK='TRUE';
      ALLOW_CONNECT='TRUE';
    'VSS644':
      PIN_NUMBER='(0,0,0,0,0,0,0,0,0,0,0,0,0,0,0,0,0,0,0,0,0,0,0,0,0,0,0,0,0,0,0,0,0,0,0,CB63,0,0,0,0,0,0)';
      PINUSE='POWER';
      NO_LOAD_CHECK='Both';
      NO_IO_CHECK='Both';
      NO_ASSERT_CHECK='TRUE';
      NO_DIR_CHECK='TRUE';
      ALLOW_CONNECT='TRUE';
    'VSS643':
      PIN_NUMBER='(0,0,0,0,0,0,0,0,0,0,0,0,0,0,0,0,0,0,0,0,0,0,0,0,0,0,0,0,0,0,0,0,0,0,0,CB59,0,0,0,0,0,0)';
      PINUSE='POWER';
      NO_LOAD_CHECK='Both';
      NO_IO_CHECK='Both';
      NO_ASSERT_CHECK='TRUE';
      NO_DIR_CHECK='TRUE';
      ALLOW_CONNECT='TRUE';
    'VSS642':
      PIN_NUMBER='(0,0,0,0,0,0,0,0,0,0,0,0,0,0,0,0,0,0,0,0,0,0,0,0,0,0,0,0,0,0,0,0,0,0,0,CB57,0,0,0,0,0,0)';
      PINUSE='POWER';
      NO_LOAD_CHECK='Both';
      NO_IO_CHECK='Both';
      NO_ASSERT_CHECK='TRUE';
      NO_DIR_CHECK='TRUE';
      ALLOW_CONNECT='TRUE';
    'VSS641':
      PIN_NUMBER='(0,0,0,0,0,0,0,0,0,0,0,0,0,0,0,0,0,0,0,0,0,0,0,0,0,0,0,0,0,0,0,0,0,0,0,CB55,0,0,0,0,0,0)';
      PINUSE='POWER';
      NO_LOAD_CHECK='Both';
      NO_IO_CHECK='Both';
      NO_ASSERT_CHECK='TRUE';
      NO_DIR_CHECK='TRUE';
      ALLOW_CONNECT='TRUE';
    'VSS640':
      PIN_NUMBER='(0,0,0,0,0,0,0,0,0,0,0,0,0,0,0,0,0,0,0,0,0,0,0,0,0,0,0,0,0,0,0,0,0,0,0,CB53,0,0,0,0,0,0)';
      PINUSE='POWER';
      NO_LOAD_CHECK='Both';
      NO_IO_CHECK='Both';
      NO_ASSERT_CHECK='TRUE';
      NO_DIR_CHECK='TRUE';
      ALLOW_CONNECT='TRUE';
    'VSS639':
      PIN_NUMBER='(0,0,0,0,0,0,0,0,0,0,0,0,0,0,0,0,0,0,0,0,0,0,0,0,0,0,0,0,0,0,0,0,0,0,0,CB51,0,0,0,0,0,0)';
      PINUSE='POWER';
      NO_LOAD_CHECK='Both';
      NO_IO_CHECK='Both';
      NO_ASSERT_CHECK='TRUE';
      NO_DIR_CHECK='TRUE';
      ALLOW_CONNECT='TRUE';
    'VSS638':
      PIN_NUMBER='(0,0,0,0,0,0,0,0,0,0,0,0,0,0,0,0,0,0,0,0,0,0,0,0,0,0,0,0,0,0,0,0,0,0,0,CB49,0,0,0,0,0,0)';
      PINUSE='POWER';
      NO_LOAD_CHECK='Both';
      NO_IO_CHECK='Both';
      NO_ASSERT_CHECK='TRUE';
      NO_DIR_CHECK='TRUE';
      ALLOW_CONNECT='TRUE';
    'VSS637':
      PIN_NUMBER='(0,0,0,0,0,0,0,0,0,0,0,0,0,0,0,0,0,0,0,0,0,0,0,0,0,0,0,0,0,0,0,0,0,0,0,CB47,0,0,0,0,0,0)';
      PINUSE='POWER';
      NO_LOAD_CHECK='Both';
      NO_IO_CHECK='Both';
      NO_ASSERT_CHECK='TRUE';
      NO_DIR_CHECK='TRUE';
      ALLOW_CONNECT='TRUE';
    'VSS636':
      PIN_NUMBER='(0,0,0,0,0,0,0,0,0,0,0,0,0,0,0,0,0,0,0,0,0,0,0,0,0,0,0,0,0,0,0,0,0,0,0,CB44,0,0,0,0,0,0)';
      PINUSE='POWER';
      NO_LOAD_CHECK='Both';
      NO_IO_CHECK='Both';
      NO_ASSERT_CHECK='TRUE';
      NO_DIR_CHECK='TRUE';
      ALLOW_CONNECT='TRUE';
    'VSS635':
      PIN_NUMBER='(0,0,0,0,0,0,0,0,0,0,0,0,0,0,0,0,0,0,0,0,0,0,0,0,0,0,0,0,0,0,0,0,0,0,0,CB42,0,0,0,0,0,0)';
      PINUSE='POWER';
      NO_LOAD_CHECK='Both';
      NO_IO_CHECK='Both';
      NO_ASSERT_CHECK='TRUE';
      NO_DIR_CHECK='TRUE';
      ALLOW_CONNECT='TRUE';
    'VSS634':
      PIN_NUMBER='(0,0,0,0,0,0,0,0,0,0,0,0,0,0,0,0,0,0,0,0,0,0,0,0,0,0,0,0,0,0,0,0,0,0,0,CB40,0,0,0,0,0,0)';
      PINUSE='POWER';
      NO_LOAD_CHECK='Both';
      NO_IO_CHECK='Both';
      NO_ASSERT_CHECK='TRUE';
      NO_DIR_CHECK='TRUE';
      ALLOW_CONNECT='TRUE';
    'VSS633':
      PIN_NUMBER='(0,0,0,0,0,0,0,0,0,0,0,0,0,0,0,0,0,0,0,0,0,0,0,0,0,0,0,0,0,0,0,0,0,0,0,CB4,0,0,0,0,0,0)';
      PINUSE='POWER';
      NO_LOAD_CHECK='Both';
      NO_IO_CHECK='Both';
      NO_ASSERT_CHECK='TRUE';
      NO_DIR_CHECK='TRUE';
      ALLOW_CONNECT='TRUE';
    'VSS632':
      PIN_NUMBER='(0,0,0,0,0,0,0,0,0,0,0,0,0,0,0,0,0,0,0,0,0,0,0,0,0,0,0,0,0,0,0,0,0,0,0,CB38,0,0,0,0,0,0)';
      PINUSE='POWER';
      NO_LOAD_CHECK='Both';
      NO_IO_CHECK='Both';
      NO_ASSERT_CHECK='TRUE';
      NO_DIR_CHECK='TRUE';
      ALLOW_CONNECT='TRUE';
    'VSS631':
      PIN_NUMBER='(0,0,0,0,0,0,0,0,0,0,0,0,0,0,0,0,0,0,0,0,0,0,0,0,0,0,0,0,0,0,0,0,0,0,0,CB36,0,0,0,0,0,0)';
      PINUSE='POWER';
      NO_LOAD_CHECK='Both';
      NO_IO_CHECK='Both';
      NO_ASSERT_CHECK='TRUE';
      NO_DIR_CHECK='TRUE';
      ALLOW_CONNECT='TRUE';
    'VSS630':
      PIN_NUMBER='(0,0,0,0,0,0,0,0,0,0,0,0,0,0,0,0,0,0,0,0,0,0,0,0,0,0,0,0,0,0,0,0,0,0,0,CB34,0,0,0,0,0,0)';
      PINUSE='POWER';
      NO_LOAD_CHECK='Both';
      NO_IO_CHECK='Both';
      NO_ASSERT_CHECK='TRUE';
      NO_DIR_CHECK='TRUE';
      ALLOW_CONNECT='TRUE';
    'VSS629':
      PIN_NUMBER='(0,0,0,0,0,0,0,0,0,0,0,0,0,0,0,0,0,0,0,0,0,0,0,0,0,0,0,0,0,0,0,0,0,0,0,CB32,0,0,0,0,0,0)';
      PINUSE='POWER';
      NO_LOAD_CHECK='Both';
      NO_IO_CHECK='Both';
      NO_ASSERT_CHECK='TRUE';
      NO_DIR_CHECK='TRUE';
      ALLOW_CONNECT='TRUE';
    'VSS628':
      PIN_NUMBER='(0,0,0,0,0,0,0,0,0,0,0,0,0,0,0,0,0,0,0,0,0,0,0,0,0,0,0,0,0,0,0,0,0,0,0,CB28,0,0,0,0,0,0)';
      PINUSE='POWER';
      NO_LOAD_CHECK='Both';
      NO_IO_CHECK='Both';
      NO_ASSERT_CHECK='TRUE';
      NO_DIR_CHECK='TRUE';
      ALLOW_CONNECT='TRUE';
    'VSS627':
      PIN_NUMBER='(0,0,0,0,0,0,0,0,0,0,0,0,0,0,0,0,0,0,0,0,0,0,0,0,0,0,0,0,0,0,0,0,0,0,0,CB26,0,0,0,0,0,0)';
      PINUSE='POWER';
      NO_LOAD_CHECK='Both';
      NO_IO_CHECK='Both';
      NO_ASSERT_CHECK='TRUE';
      NO_DIR_CHECK='TRUE';
      ALLOW_CONNECT='TRUE';
    'VSS626':
      PIN_NUMBER='(0,0,0,0,0,0,0,0,0,0,0,0,0,0,0,0,0,0,0,0,0,0,0,0,0,0,0,0,0,0,0,0,0,0,0,CB24,0,0,0,0,0,0)';
      PINUSE='POWER';
      NO_LOAD_CHECK='Both';
      NO_IO_CHECK='Both';
      NO_ASSERT_CHECK='TRUE';
      NO_DIR_CHECK='TRUE';
      ALLOW_CONNECT='TRUE';
    'VSS625':
      PIN_NUMBER='(0,0,0,0,0,0,0,0,0,0,0,0,0,0,0,0,0,0,0,0,0,0,0,0,0,0,0,0,0,0,0,0,0,0,0,CB22,0,0,0,0,0,0)';
      PINUSE='POWER';
      NO_LOAD_CHECK='Both';
      NO_IO_CHECK='Both';
      NO_ASSERT_CHECK='TRUE';
      NO_DIR_CHECK='TRUE';
      ALLOW_CONNECT='TRUE';
    'VSS624':
      PIN_NUMBER='(0,0,0,0,0,0,0,0,0,0,0,0,0,0,0,0,0,0,0,0,0,0,0,0,0,0,0,0,0,0,0,0,0,0,0,CB20,0,0,0,0,0,0)';
      PINUSE='POWER';
      NO_LOAD_CHECK='Both';
      NO_IO_CHECK='Both';
      NO_ASSERT_CHECK='TRUE';
      NO_DIR_CHECK='TRUE';
      ALLOW_CONNECT='TRUE';
    'VSS623':
      PIN_NUMBER='(0,0,0,0,0,0,0,0,0,0,0,0,0,0,0,0,0,0,0,0,0,0,0,0,0,0,0,0,0,0,0,0,0,0,0,CB16,0,0,0,0,0,0)';
      PINUSE='POWER';
      NO_LOAD_CHECK='Both';
      NO_IO_CHECK='Both';
      NO_ASSERT_CHECK='TRUE';
      NO_DIR_CHECK='TRUE';
      ALLOW_CONNECT='TRUE';
    'VSS622':
      PIN_NUMBER='(0,0,0,0,0,0,0,0,0,0,0,0,0,0,0,0,0,0,0,0,0,0,0,0,0,0,0,0,0,0,0,0,0,0,0,CB12,0,0,0,0,0,0)';
      PINUSE='POWER';
      NO_LOAD_CHECK='Both';
      NO_IO_CHECK='Both';
      NO_ASSERT_CHECK='TRUE';
      NO_DIR_CHECK='TRUE';
      ALLOW_CONNECT='TRUE';
    'VSS621':
      PIN_NUMBER='(0,0,0,0,0,0,0,0,0,0,0,0,0,0,0,0,0,0,0,0,0,0,0,0,0,0,0,0,0,0,0,0,0,0,0,CA31,0,0,0,0,0,0)';
      PINUSE='POWER';
      NO_LOAD_CHECK='Both';
      NO_IO_CHECK='Both';
      NO_ASSERT_CHECK='TRUE';
      NO_DIR_CHECK='TRUE';
      ALLOW_CONNECT='TRUE';
    'VSS620':
      PIN_NUMBER='(0,0,0,0,0,0,0,0,0,0,0,0,0,0,0,0,0,0,0,0,0,0,0,0,0,0,0,0,0,0,0,0,0,0,0,CA3,0,0,0,0,0,0)';
      PINUSE='POWER';
      NO_LOAD_CHECK='Both';
      NO_IO_CHECK='Both';
      NO_ASSERT_CHECK='TRUE';
      NO_DIR_CHECK='TRUE';
      ALLOW_CONNECT='TRUE';
    'VSS608':
      PIN_NUMBER='(0,0,0,0,0,0,0,0,0,0,0,0,0,0,0,0,0,0,0,0,0,0,0,0,0,0,0,0,0,0,0,0,0,0,0,BY8,0,0,0,0,0,0)';
      PINUSE='POWER';
      NO_LOAD_CHECK='Both';
      NO_IO_CHECK='Both';
      NO_ASSERT_CHECK='TRUE';
      NO_DIR_CHECK='TRUE';
      ALLOW_CONNECT='TRUE';
    'VSS607':
      PIN_NUMBER='(0,0,0,0,0,0,0,0,0,0,0,0,0,0,0,0,0,0,0,0,0,0,0,0,0,0,0,0,0,0,0,0,0,0,0,BY4,0,0,0,0,0,0)';
      PINUSE='POWER';
      NO_LOAD_CHECK='Both';
      NO_IO_CHECK='Both';
      NO_ASSERT_CHECK='TRUE';
      NO_DIR_CHECK='TRUE';
      ALLOW_CONNECT='TRUE';
    'VSS606':
      PIN_NUMBER='(0,0,0,0,0,0,0,0,0,0,0,0,0,0,0,0,0,0,0,0,0,0,0,0,0,0,0,0,0,0,0,0,0,0,0,BY20,0,0,0,0,0,0)';
      PINUSE='POWER';
      NO_LOAD_CHECK='Both';
      NO_IO_CHECK='Both';
      NO_ASSERT_CHECK='TRUE';
      NO_DIR_CHECK='TRUE';
      ALLOW_CONNECT='TRUE';
    'VSS605':
      PIN_NUMBER='(0,0,0,0,0,0,0,0,0,0,0,0,0,0,0,0,0,0,0,0,0,0,0,0,0,0,0,0,0,0,0,0,0,0,0,BY16,0,0,0,0,0,0)';
      PINUSE='POWER';
      NO_LOAD_CHECK='Both';
      NO_IO_CHECK='Both';
      NO_ASSERT_CHECK='TRUE';
      NO_DIR_CHECK='TRUE';
      ALLOW_CONNECT='TRUE';
    'VSS604':
      PIN_NUMBER='(0,0,0,0,0,0,0,0,0,0,0,0,0,0,0,0,0,0,0,0,0,0,0,0,0,0,0,0,0,0,0,0,0,0,0,BY12,0,0,0,0,0,0)';
      PINUSE='POWER';
      NO_LOAD_CHECK='Both';
      NO_IO_CHECK='Both';
      NO_ASSERT_CHECK='TRUE';
      NO_DIR_CHECK='TRUE';
      ALLOW_CONNECT='TRUE';
    'VSS603':
      PIN_NUMBER='(0,0,0,0,0,0,0,0,0,0,0,0,0,0,0,0,0,0,0,0,0,0,0,0,0,0,0,0,0,0,0,0,0,0,0,BW9,0,0,0,0,0,0)';
      PINUSE='POWER';
      NO_LOAD_CHECK='Both';
      NO_IO_CHECK='Both';
      NO_ASSERT_CHECK='TRUE';
      NO_DIR_CHECK='TRUE';
      ALLOW_CONNECT='TRUE';
    'VSS602':
      PIN_NUMBER='(0,0,0,0,0,0,0,0,0,0,0,0,0,0,0,0,0,0,0,0,0,0,0,0,0,0,0,0,0,0,0,0,0,0,0,BW5,0,0,0,0,0,0)';
      PINUSE='POWER';
      NO_LOAD_CHECK='Both';
      NO_IO_CHECK='Both';
      NO_ASSERT_CHECK='TRUE';
      NO_DIR_CHECK='TRUE';
      ALLOW_CONNECT='TRUE';
    'VSS601':
      PIN_NUMBER='(0,0,0,0,0,0,0,0,0,0,0,0,0,0,0,0,0,0,0,0,0,0,0,0,0,0,0,0,0,0,0,0,0,0,0,BW31,0,0,0,0,0,0)';
      PINUSE='POWER';
      NO_LOAD_CHECK='Both';
      NO_IO_CHECK='Both';
      NO_ASSERT_CHECK='TRUE';
      NO_DIR_CHECK='TRUE';
      ALLOW_CONNECT='TRUE';
    'VSS600':
      PIN_NUMBER='(0,0,0,0,0,0,0,0,0,0,0,0,0,0,0,0,0,0,0,0,0,0,0,0,0,0,0,0,0,0,0,0,0,0,0,BW3,0,0,0,0,0,0)';
      PINUSE='POWER';
      NO_LOAD_CHECK='Both';
      NO_IO_CHECK='Both';
      NO_ASSERT_CHECK='TRUE';
      NO_DIR_CHECK='TRUE';
      ALLOW_CONNECT='TRUE';
    'VSS599':
      PIN_NUMBER='(0,0,0,0,0,0,0,0,0,0,0,0,0,0,0,0,0,0,0,0,0,0,0,0,0,0,0,0,0,0,0,0,0,0,0,BW29,0,0,0,0,0,0)';
      PINUSE='POWER';
      NO_LOAD_CHECK='Both';
      NO_IO_CHECK='Both';
      NO_ASSERT_CHECK='TRUE';
      NO_DIR_CHECK='TRUE';
      ALLOW_CONNECT='TRUE';
    'VSS598':
      PIN_NUMBER='(0,0,0,0,0,0,0,0,0,0,0,0,0,0,0,0,0,0,0,0,0,0,0,0,0,0,0,0,0,0,0,0,0,0,0,BW27,0,0,0,0,0,0)';
      PINUSE='POWER';
      NO_LOAD_CHECK='Both';
      NO_IO_CHECK='Both';
      NO_ASSERT_CHECK='TRUE';
      NO_DIR_CHECK='TRUE';
      ALLOW_CONNECT='TRUE';
    'VSS597':
      PIN_NUMBER='(0,0,0,0,0,0,0,0,0,0,0,0,0,0,0,0,0,0,0,0,0,0,0,0,0,0,0,0,0,0,0,0,0,0,0,BW17,0,0,0,0,0,0)';
      PINUSE='POWER';
      NO_LOAD_CHECK='Both';
      NO_IO_CHECK='Both';
      NO_ASSERT_CHECK='TRUE';
      NO_DIR_CHECK='TRUE';
      ALLOW_CONNECT='TRUE';
    'VSS596':
      PIN_NUMBER='(0,0,0,0,0,0,0,0,0,0,0,0,0,0,0,0,0,0,0,0,0,0,0,0,0,0,0,0,0,0,0,0,0,0,0,BW13,0,0,0,0,0,0)';
      PINUSE='POWER';
      NO_LOAD_CHECK='Both';
      NO_IO_CHECK='Both';
      NO_ASSERT_CHECK='TRUE';
      NO_DIR_CHECK='TRUE';
      ALLOW_CONNECT='TRUE';
    'VSS594':
      PIN_NUMBER='(0,0,0,0,0,0,0,0,0,0,0,0,0,0,0,0,0,0,0,0,0,0,0,0,0,0,0,0,0,0,0,0,0,0,0,BV8,0,0,0,0,0,0)';
      PINUSE='POWER';
      NO_LOAD_CHECK='Both';
      NO_IO_CHECK='Both';
      NO_ASSERT_CHECK='TRUE';
      NO_DIR_CHECK='TRUE';
      ALLOW_CONNECT='TRUE';
    'VSS593':
      PIN_NUMBER='(0,0,0,0,0,0,0,0,0,0,0,0,0,0,0,0,0,0,0,0,0,0,0,0,0,0,0,0,0,0,0,0,0,0,0,BV6,0,0,0,0,0,0)';
      PINUSE='POWER';
      NO_LOAD_CHECK='Both';
      NO_IO_CHECK='Both';
      NO_ASSERT_CHECK='TRUE';
      NO_DIR_CHECK='TRUE';
      ALLOW_CONNECT='TRUE';
    'VSS592':
      PIN_NUMBER='(0,0,0,0,0,0,0,0,0,0,0,0,0,0,0,0,0,0,0,0,0,0,0,0,0,0,0,0,0,0,0,0,0,0,0,BV4,0,0,0,0,0,0)';
      PINUSE='POWER';
      NO_LOAD_CHECK='Both';
      NO_IO_CHECK='Both';
      NO_ASSERT_CHECK='TRUE';
      NO_DIR_CHECK='TRUE';
      ALLOW_CONNECT='TRUE';
    'VSS591':
      PIN_NUMBER='(0,0,0,0,0,0,0,0,0,0,0,0,0,0,0,0,0,0,0,0,0,0,0,0,0,0,0,0,0,0,0,0,0,0,0,BV20,0,0,0,0,0,0)';
      PINUSE='POWER';
      NO_LOAD_CHECK='Both';
      NO_IO_CHECK='Both';
      NO_ASSERT_CHECK='TRUE';
      NO_DIR_CHECK='TRUE';
      ALLOW_CONNECT='TRUE';
    'VSS590':
      PIN_NUMBER='(0,0,0,0,0,0,0,0,0,0,0,0,0,0,0,0,0,0,0,0,0,0,0,0,0,0,0,0,0,0,0,0,0,0,0,BV2,0,0,0,0,0,0)';
      PINUSE='POWER';
      NO_LOAD_CHECK='Both';
      NO_IO_CHECK='Both';
      NO_ASSERT_CHECK='TRUE';
      NO_DIR_CHECK='TRUE';
      ALLOW_CONNECT='TRUE';
    'VSS589':
      PIN_NUMBER='(0,0,0,0,0,0,0,0,0,0,0,0,0,0,0,0,0,0,0,0,0,0,0,0,0,0,0,0,0,0,0,0,0,0,0,BV18,0,0,0,0,0,0)';
      PINUSE='POWER';
      NO_LOAD_CHECK='Both';
      NO_IO_CHECK='Both';
      NO_ASSERT_CHECK='TRUE';
      NO_DIR_CHECK='TRUE';
      ALLOW_CONNECT='TRUE';
    'VSS588':
      PIN_NUMBER='(0,0,0,0,0,0,0,0,0,0,0,0,0,0,0,0,0,0,0,0,0,0,0,0,0,0,0,0,0,0,0,0,0,0,0,BV16,0,0,0,0,0,0)';
      PINUSE='POWER';
      NO_LOAD_CHECK='Both';
      NO_IO_CHECK='Both';
      NO_ASSERT_CHECK='TRUE';
      NO_DIR_CHECK='TRUE';
      ALLOW_CONNECT='TRUE';
    'VSS587':
      PIN_NUMBER='(0,0,0,0,0,0,0,0,0,0,0,0,0,0,0,0,0,0,0,0,0,0,0,0,0,0,0,0,0,0,0,0,0,0,0,BV12,0,0,0,0,0,0)';
      PINUSE='POWER';
      NO_LOAD_CHECK='Both';
      NO_IO_CHECK='Both';
      NO_ASSERT_CHECK='TRUE';
      NO_DIR_CHECK='TRUE';
      ALLOW_CONNECT='TRUE';
    'VSS586':
      PIN_NUMBER='(0,0,0,0,0,0,0,0,0,0,0,0,0,0,0,0,0,0,0,0,0,0,0,0,0,0,0,0,0,0,0,0,0,0,0,BU7,0,0,0,0,0,0)';
      PINUSE='POWER';
      NO_LOAD_CHECK='Both';
      NO_IO_CHECK='Both';
      NO_ASSERT_CHECK='TRUE';
      NO_DIR_CHECK='TRUE';
      ALLOW_CONNECT='TRUE';
    'VSS585':
      PIN_NUMBER='(0,0,0,0,0,0,0,0,0,0,0,0,0,0,0,0,0,0,0,0,0,0,0,0,0,0,0,0,0,0,0,0,0,0,0,BU31,0,0,0,0,0,0)';
      PINUSE='POWER';
      NO_LOAD_CHECK='Both';
      NO_IO_CHECK='Both';
      NO_ASSERT_CHECK='TRUE';
      NO_DIR_CHECK='TRUE';
      ALLOW_CONNECT='TRUE';
    'VSS584':
      PIN_NUMBER='(0,0,0,0,0,0,0,0,0,0,0,0,0,0,0,0,0,0,0,0,0,0,0,0,0,0,0,0,0,0,0,0,0,0,0,BU25,0,0,0,0,0,0)';
      PINUSE='POWER';
      NO_LOAD_CHECK='Both';
      NO_IO_CHECK='Both';
      NO_ASSERT_CHECK='TRUE';
      NO_DIR_CHECK='TRUE';
      ALLOW_CONNECT='TRUE';
    'VSS582':
      PIN_NUMBER='(0,0,0,0,0,0,0,0,0,0,0,0,0,0,0,0,0,0,0,0,0,0,0,0,0,0,0,0,0,0,0,0,0,0,0,BU23,0,0,0,0,0,0)';
      PINUSE='POWER';
      NO_LOAD_CHECK='Both';
      NO_IO_CHECK='Both';
      NO_ASSERT_CHECK='TRUE';
      NO_DIR_CHECK='TRUE';
      ALLOW_CONNECT='TRUE';
    'VSS581':
      PIN_NUMBER='(0,0,0,0,0,0,0,0,0,0,0,0,0,0,0,0,0,0,0,0,0,0,0,0,0,0,0,0,0,0,0,0,0,0,0,BU21,0,0,0,0,0,0)';
      PINUSE='POWER';
      NO_LOAD_CHECK='Both';
      NO_IO_CHECK='Both';
      NO_ASSERT_CHECK='TRUE';
      NO_DIR_CHECK='TRUE';
      ALLOW_CONNECT='TRUE';
    'VSS580':
      PIN_NUMBER='(0,0,0,0,0,0,0,0,0,0,0,0,0,0,0,0,0,0,0,0,0,0,0,0,0,0,0,0,0,0,0,0,0,0,0,BU19,0,0,0,0,0,0)';
      PINUSE='POWER';
      NO_LOAD_CHECK='Both';
      NO_IO_CHECK='Both';
      NO_ASSERT_CHECK='TRUE';
      NO_DIR_CHECK='TRUE';
      ALLOW_CONNECT='TRUE';
    'VSS579':
      PIN_NUMBER='(0,0,0,0,0,0,0,0,0,0,0,0,0,0,0,0,0,0,0,0,0,0,0,0,0,0,0,0,0,0,0,0,0,0,0,BU15,0,0,0,0,0,0)';
      PINUSE='POWER';
      NO_LOAD_CHECK='Both';
      NO_IO_CHECK='Both';
      NO_ASSERT_CHECK='TRUE';
      NO_DIR_CHECK='TRUE';
      ALLOW_CONNECT='TRUE';
    'VSS578':
      PIN_NUMBER='(0,0,0,0,0,0,0,0,0,0,0,0,0,0,0,0,0,0,0,0,0,0,0,0,0,0,0,0,0,0,0,0,0,0,0,BT8,0,0,0,0,0,0)';
      PINUSE='POWER';
      NO_LOAD_CHECK='Both';
      NO_IO_CHECK='Both';
      NO_ASSERT_CHECK='TRUE';
      NO_DIR_CHECK='TRUE';
      ALLOW_CONNECT='TRUE';
    'VSS577':
      PIN_NUMBER='(0,0,0,0,0,0,0,0,0,0,0,0,0,0,0,0,0,0,0,0,0,0,0,0,0,0,0,0,0,0,0,0,0,0,0,BT4,0,0,0,0,0,0)';
      PINUSE='POWER';
      NO_LOAD_CHECK='Both';
      NO_IO_CHECK='Both';
      NO_ASSERT_CHECK='TRUE';
      NO_DIR_CHECK='TRUE';
      ALLOW_CONNECT='TRUE';
    'VSS576':
      PIN_NUMBER='(0,0,0,0,0,0,0,0,0,0,0,0,0,0,0,0,0,0,0,0,0,0,0,0,0,0,0,0,0,0,0,0,0,0,0,BT20,0,0,0,0,0,0)';
      PINUSE='POWER';
      NO_LOAD_CHECK='Both';
      NO_IO_CHECK='Both';
      NO_ASSERT_CHECK='TRUE';
      NO_DIR_CHECK='TRUE';
      ALLOW_CONNECT='TRUE';
    'VSS575':
      PIN_NUMBER='(0,0,0,0,0,0,0,0,0,0,0,0,0,0,0,0,0,0,0,0,0,0,0,0,0,0,0,0,0,0,0,0,0,0,0,BT16,0,0,0,0,0,0)';
      PINUSE='POWER';
      NO_LOAD_CHECK='Both';
      NO_IO_CHECK='Both';
      NO_ASSERT_CHECK='TRUE';
      NO_DIR_CHECK='TRUE';
      ALLOW_CONNECT='TRUE';
    'VSS574':
      PIN_NUMBER='(0,0,0,0,0,0,0,0,0,0,0,0,0,0,0,0,0,0,0,0,0,0,0,0,0,0,0,0,0,0,0,0,0,0,0,BT12,0,0,0,0,0,0)';
      PINUSE='POWER';
      NO_LOAD_CHECK='Both';
      NO_IO_CHECK='Both';
      NO_ASSERT_CHECK='TRUE';
      NO_DIR_CHECK='TRUE';
      ALLOW_CONNECT='TRUE';
    'VSS573':
      PIN_NUMBER='(0,0,0,0,0,0,0,0,0,0,0,0,0,0,0,0,0,0,0,0,0,0,0,0,0,0,0,0,0,0,0,0,0,0,0,BR90,0,0,0,0,0,0)';
      PINUSE='POWER';
      NO_LOAD_CHECK='Both';
      NO_IO_CHECK='Both';
      NO_ASSERT_CHECK='TRUE';
      NO_DIR_CHECK='TRUE';
      ALLOW_CONNECT='TRUE';
    'VSS570':
      PIN_NUMBER='(0,0,0,0,0,0,0,0,0,0,0,0,0,0,0,0,0,0,0,0,0,0,0,0,0,0,0,0,0,0,0,0,0,0,0,BR88,0,0,0,0,0,0)';
      PINUSE='POWER';
      NO_LOAD_CHECK='Both';
      NO_IO_CHECK='Both';
      NO_ASSERT_CHECK='TRUE';
      NO_DIR_CHECK='TRUE';
      ALLOW_CONNECT='TRUE';
    'VSS569':
      PIN_NUMBER='(0,0,0,0,0,0,0,0,0,0,0,0,0,0,0,0,0,0,0,0,0,0,0,0,0,0,0,0,0,0,0,0,0,0,0,BR86,0,0,0,0,0,0)';
      PINUSE='POWER';
      NO_LOAD_CHECK='Both';
      NO_IO_CHECK='Both';
      NO_ASSERT_CHECK='TRUE';
      NO_DIR_CHECK='TRUE';
      ALLOW_CONNECT='TRUE';
    'VSS568':
      PIN_NUMBER='(0,0,0,0,0,0,0,0,0,0,0,0,0,0,0,0,0,0,0,0,0,0,0,0,0,0,0,0,0,0,0,0,0,0,0,BR84,0,0,0,0,0,0)';
      PINUSE='POWER';
      NO_LOAD_CHECK='Both';
      NO_IO_CHECK='Both';
      NO_ASSERT_CHECK='TRUE';
      NO_DIR_CHECK='TRUE';
      ALLOW_CONNECT='TRUE';
    'VSS567':
      PIN_NUMBER='(0,0,0,0,0,0,0,0,0,0,0,0,0,0,0,0,0,0,0,0,0,0,0,0,0,0,0,0,0,0,0,0,0,0,0,BR82,0,0,0,0,0,0)';
      PINUSE='POWER';
      NO_LOAD_CHECK='Both';
      NO_IO_CHECK='Both';
      NO_ASSERT_CHECK='TRUE';
      NO_DIR_CHECK='TRUE';
      ALLOW_CONNECT='TRUE';
    'VSS566':
      PIN_NUMBER='(0,0,0,0,0,0,0,0,0,0,0,0,0,0,0,0,0,0,0,0,0,0,0,0,0,0,0,0,0,0,0,0,0,0,0,BR80,0,0,0,0,0,0)';
      PINUSE='POWER';
      NO_LOAD_CHECK='Both';
      NO_IO_CHECK='Both';
      NO_ASSERT_CHECK='TRUE';
      NO_DIR_CHECK='TRUE';
      ALLOW_CONNECT='TRUE';
    'VSS565':
      PIN_NUMBER='(0,0,0,0,0,0,0,0,0,0,0,0,0,0,0,0,0,0,0,0,0,0,0,0,0,0,0,0,0,0,0,0,0,0,0,BR76,0,0,0,0,0,0)';
      PINUSE='POWER';
      NO_LOAD_CHECK='Both';
      NO_IO_CHECK='Both';
      NO_ASSERT_CHECK='TRUE';
      NO_DIR_CHECK='TRUE';
      ALLOW_CONNECT='TRUE';
    'VSS564':
      PIN_NUMBER='(0,0,0,0,0,0,0,0,0,0,0,0,0,0,0,0,0,0,0,0,0,0,0,0,0,0,0,0,0,0,0,0,0,0,0,BR74,0,0,0,0,0,0)';
      PINUSE='POWER';
      NO_LOAD_CHECK='Both';
      NO_IO_CHECK='Both';
      NO_ASSERT_CHECK='TRUE';
      NO_DIR_CHECK='TRUE';
      ALLOW_CONNECT='TRUE';
    'VSS563':
      PIN_NUMBER='(0,0,0,0,0,0,0,0,0,0,0,0,0,0,0,0,0,0,0,0,0,0,0,0,0,0,0,0,0,0,0,0,0,0,0,BR72,0,0,0,0,0,0)';
      PINUSE='POWER';
      NO_LOAD_CHECK='Both';
      NO_IO_CHECK='Both';
      NO_ASSERT_CHECK='TRUE';
      NO_DIR_CHECK='TRUE';
      ALLOW_CONNECT='TRUE';
    'VSS561':
      PIN_NUMBER='(0,0,0,0,0,0,0,0,0,0,0,0,0,0,0,0,0,0,0,0,0,0,0,0,0,0,0,0,0,0,0,0,0,0,0,BR70,0,0,0,0,0,0)';
      PINUSE='POWER';
      NO_LOAD_CHECK='Both';
      NO_IO_CHECK='Both';
      NO_ASSERT_CHECK='TRUE';
      NO_DIR_CHECK='TRUE';
      ALLOW_CONNECT='TRUE';
    'VSS560':
      PIN_NUMBER='(0,0,0,0,0,0,0,0,0,0,0,0,0,0,0,0,0,0,0,0,0,0,0,0,0,0,0,0,0,0,0,0,0,0,0,BR68,0,0,0,0,0,0)';
      PINUSE='POWER';
      NO_LOAD_CHECK='Both';
      NO_IO_CHECK='Both';
      NO_ASSERT_CHECK='TRUE';
      NO_DIR_CHECK='TRUE';
      ALLOW_CONNECT='TRUE';
    'VSS559':
      PIN_NUMBER='(0,0,0,0,0,0,0,0,0,0,0,0,0,0,0,0,0,0,0,0,0,0,0,0,0,0,0,0,0,0,0,0,0,0,0,BR66,0,0,0,0,0,0)';
      PINUSE='POWER';
      NO_LOAD_CHECK='Both';
      NO_IO_CHECK='Both';
      NO_ASSERT_CHECK='TRUE';
      NO_DIR_CHECK='TRUE';
      ALLOW_CONNECT='TRUE';
    'VSS557':
      PIN_NUMBER='(0,0,0,0,0,0,0,0,0,0,0,0,0,0,0,0,0,0,0,0,0,0,0,0,0,0,0,0,0,0,0,0,0,0,0,BR64,0,0,0,0,0,0)';
      PINUSE='POWER';
      NO_LOAD_CHECK='Both';
      NO_IO_CHECK='Both';
      NO_ASSERT_CHECK='TRUE';
      NO_DIR_CHECK='TRUE';
      ALLOW_CONNECT='TRUE';
    'VSS556':
      PIN_NUMBER='(0,0,0,0,0,0,0,0,0,0,0,0,0,0,0,0,0,0,0,0,0,0,0,0,0,0,0,0,0,0,0,0,0,0,0,BR58,0,0,0,0,0,0)';
      PINUSE='POWER';
      NO_LOAD_CHECK='Both';
      NO_IO_CHECK='Both';
      NO_ASSERT_CHECK='TRUE';
      NO_DIR_CHECK='TRUE';
      ALLOW_CONNECT='TRUE';
    'VSS555':
      PIN_NUMBER='(0,0,0,0,0,0,0,0,0,0,0,0,0,0,0,0,0,0,0,0,0,0,0,0,0,0,0,0,0,0,0,0,0,0,0,BR56,0,0,0,0,0,0)';
      PINUSE='POWER';
      NO_LOAD_CHECK='Both';
      NO_IO_CHECK='Both';
      NO_ASSERT_CHECK='TRUE';
      NO_DIR_CHECK='TRUE';
      ALLOW_CONNECT='TRUE';
    'VSS552':
      PIN_NUMBER='(0,0,0,0,0,0,0,0,0,0,0,0,0,0,0,0,0,0,0,0,0,0,0,0,0,0,0,0,0,0,0,0,0,0,0,BR54,0,0,0,0,0,0)';
      PINUSE='POWER';
      NO_LOAD_CHECK='Both';
      NO_IO_CHECK='Both';
      NO_ASSERT_CHECK='TRUE';
      NO_DIR_CHECK='TRUE';
      ALLOW_CONNECT='TRUE';
    'VSS551':
      PIN_NUMBER='(0,0,0,0,0,0,0,0,0,0,0,0,0,0,0,0,0,0,0,0,0,0,0,0,0,0,0,0,0,0,0,0,0,0,0,BR52,0,0,0,0,0,0)';
      PINUSE='POWER';
      NO_LOAD_CHECK='Both';
      NO_IO_CHECK='Both';
      NO_ASSERT_CHECK='TRUE';
      NO_DIR_CHECK='TRUE';
      ALLOW_CONNECT='TRUE';
    'VSS550':
      PIN_NUMBER='(0,0,0,0,0,0,0,0,0,0,0,0,0,0,0,0,0,0,0,0,0,0,0,0,0,0,0,0,0,0,0,0,0,0,0,BR50,0,0,0,0,0,0)';
      PINUSE='POWER';
      NO_LOAD_CHECK='Both';
      NO_IO_CHECK='Both';
      NO_ASSERT_CHECK='TRUE';
      NO_DIR_CHECK='TRUE';
      ALLOW_CONNECT='TRUE';
    'VSS549':
      PIN_NUMBER='(0,0,0,0,0,0,0,0,0,0,0,0,0,0,0,0,0,0,0,0,0,0,0,0,0,0,0,0,0,0,0,0,0,0,0,BR48,0,0,0,0,0,0)';
      PINUSE='POWER';
      NO_LOAD_CHECK='Both';
      NO_IO_CHECK='Both';
      NO_ASSERT_CHECK='TRUE';
      NO_DIR_CHECK='TRUE';
      ALLOW_CONNECT='TRUE';
    'VSS548':
      PIN_NUMBER='(0,0,0,0,0,0,0,0,0,0,0,0,0,0,0,0,0,0,0,0,0,0,0,0,0,0,0,0,0,0,0,0,0,0,0,BR45,0,0,0,0,0,0)';
      PINUSE='POWER';
      NO_LOAD_CHECK='Both';
      NO_IO_CHECK='Both';
      NO_ASSERT_CHECK='TRUE';
      NO_DIR_CHECK='TRUE';
      ALLOW_CONNECT='TRUE';
    'VSS547':
      PIN_NUMBER='(0,0,0,0,0,0,0,0,0,0,0,0,0,0,0,0,0,0,0,0,0,0,0,0,0,0,0,0,0,0,0,0,0,0,0,BR43,0,0,0,0,0,0)';
      PINUSE='POWER';
      NO_LOAD_CHECK='Both';
      NO_IO_CHECK='Both';
      NO_ASSERT_CHECK='TRUE';
      NO_DIR_CHECK='TRUE';
      ALLOW_CONNECT='TRUE';
    'VSS546':
      PIN_NUMBER='(0,0,0,0,0,0,0,0,0,0,0,0,0,0,0,0,0,0,0,0,0,0,0,0,0,0,0,0,0,0,0,0,0,0,0,BR41,0,0,0,0,0,0)';
      PINUSE='POWER';
      NO_LOAD_CHECK='Both';
      NO_IO_CHECK='Both';
      NO_ASSERT_CHECK='TRUE';
      NO_DIR_CHECK='TRUE';
      ALLOW_CONNECT='TRUE';
    'VSS545':
      PIN_NUMBER='(0,0,0,0,0,0,0,0,0,0,0,0,0,0,0,0,0,0,0,0,0,0,0,0,0,0,0,0,0,0,0,0,0,0,0,BR39,0,0,0,0,0,0)';
      PINUSE='POWER';
      NO_LOAD_CHECK='Both';
      NO_IO_CHECK='Both';
      NO_ASSERT_CHECK='TRUE';
      NO_DIR_CHECK='TRUE';
      ALLOW_CONNECT='TRUE';
    'VSS543':
      PIN_NUMBER='(0,0,0,0,0,0,0,0,0,0,0,0,0,0,0,0,0,0,0,0,0,0,0,0,0,0,0,0,0,0,0,0,0,0,0,BR37,0,0,0,0,0,0)';
      PINUSE='POWER';
      NO_LOAD_CHECK='Both';
      NO_IO_CHECK='Both';
      NO_ASSERT_CHECK='TRUE';
      NO_DIR_CHECK='TRUE';
      ALLOW_CONNECT='TRUE';
    'VSS542':
      PIN_NUMBER='(0,0,0,0,0,0,0,0,0,0,0,0,0,0,0,0,0,0,0,0,0,0,0,0,0,0,0,0,0,0,0,0,0,0,0,BR35,0,0,0,0,0,0)';
      PINUSE='POWER';
      NO_LOAD_CHECK='Both';
      NO_IO_CHECK='Both';
      NO_ASSERT_CHECK='TRUE';
      NO_DIR_CHECK='TRUE';
      ALLOW_CONNECT='TRUE';
    'VSS396':
      PIN_NUMBER='(0,0,0,0,0,0,0,0,0,0,0,0,0,0,0,0,0,0,0,0,0,0,0,0,0,0,0,0,0,0,0,0,0,0,0,CK4,0,0,0,0,0,0)';
      PINUSE='POWER';
      NO_LOAD_CHECK='Both';
      NO_IO_CHECK='Both';
      NO_ASSERT_CHECK='TRUE';
      NO_DIR_CHECK='TRUE';
      ALLOW_CONNECT='TRUE';
    'VSS383':
      PIN_NUMBER='(0,0,0,0,0,0,0,0,0,0,0,0,0,0,0,0,0,0,0,0,0,0,0,0,0,0,0,0,0,0,0,0,0,0,0,CJ76,0,0,0,0,0,0)';
      PINUSE='POWER';
      NO_LOAD_CHECK='Both';
      NO_IO_CHECK='Both';
      NO_ASSERT_CHECK='TRUE';
      NO_DIR_CHECK='TRUE';
      ALLOW_CONNECT='TRUE';
    'VSS572':
      PIN_NUMBER='(0,0,0,0,0,0,0,0,0,0,0,0,0,0,0,0,0,0,0,0,0,0,0,0,0,0,0,0,0,0,0,0,0,0,0,0,BR9,0,0,0,0,0)';
      PINUSE='POWER';
      NO_LOAD_CHECK='Both';
      NO_IO_CHECK='Both';
      NO_ASSERT_CHECK='TRUE';
      NO_DIR_CHECK='TRUE';
      ALLOW_CONNECT='TRUE';
    'VSS541':
      PIN_NUMBER='(0,0,0,0,0,0,0,0,0,0,0,0,0,0,0,0,0,0,0,0,0,0,0,0,0,0,0,0,0,0,0,0,0,0,0,0,BR33,0,0,0,0,0)';
      PINUSE='POWER';
      NO_LOAD_CHECK='Both';
      NO_IO_CHECK='Both';
      NO_ASSERT_CHECK='TRUE';
      NO_DIR_CHECK='TRUE';
      ALLOW_CONNECT='TRUE';
    'VSS540':
      PIN_NUMBER='(0,0,0,0,0,0,0,0,0,0,0,0,0,0,0,0,0,0,0,0,0,0,0,0,0,0,0,0,0,0,0,0,0,0,0,0,BR31,0,0,0,0,0)';
      PINUSE='POWER';
      NO_LOAD_CHECK='Both';
      NO_IO_CHECK='Both';
      NO_ASSERT_CHECK='TRUE';
      NO_DIR_CHECK='TRUE';
      ALLOW_CONNECT='TRUE';
    'VSS539':
      PIN_NUMBER='(0,0,0,0,0,0,0,0,0,0,0,0,0,0,0,0,0,0,0,0,0,0,0,0,0,0,0,0,0,0,0,0,0,0,0,0,BR29,0,0,0,0,0)';
      PINUSE='POWER';
      NO_LOAD_CHECK='Both';
      NO_IO_CHECK='Both';
      NO_ASSERT_CHECK='TRUE';
      NO_DIR_CHECK='TRUE';
      ALLOW_CONNECT='TRUE';
    'VSS538':
      PIN_NUMBER='(0,0,0,0,0,0,0,0,0,0,0,0,0,0,0,0,0,0,0,0,0,0,0,0,0,0,0,0,0,0,0,0,0,0,0,0,BR27,0,0,0,0,0)';
      PINUSE='POWER';
      NO_LOAD_CHECK='Both';
      NO_IO_CHECK='Both';
      NO_ASSERT_CHECK='TRUE';
      NO_DIR_CHECK='TRUE';
      ALLOW_CONNECT='TRUE';
    'VSS536':
      PIN_NUMBER='(0,0,0,0,0,0,0,0,0,0,0,0,0,0,0,0,0,0,0,0,0,0,0,0,0,0,0,0,0,0,0,0,0,0,0,0,BR17,0,0,0,0,0)';
      PINUSE='POWER';
      NO_LOAD_CHECK='Both';
      NO_IO_CHECK='Both';
      NO_ASSERT_CHECK='TRUE';
      NO_DIR_CHECK='TRUE';
      ALLOW_CONNECT='TRUE';
    'VSS535':
      PIN_NUMBER='(0,0,0,0,0,0,0,0,0,0,0,0,0,0,0,0,0,0,0,0,0,0,0,0,0,0,0,0,0,0,0,0,0,0,0,0,BR13,0,0,0,0,0)';
      PINUSE='POWER';
      NO_LOAD_CHECK='Both';
      NO_IO_CHECK='Both';
      NO_ASSERT_CHECK='TRUE';
      NO_DIR_CHECK='TRUE';
      ALLOW_CONNECT='TRUE';
    'VSS533':
      PIN_NUMBER='(0,0,0,0,0,0,0,0,0,0,0,0,0,0,0,0,0,0,0,0,0,0,0,0,0,0,0,0,0,0,0,0,0,0,0,0,BP8,0,0,0,0,0)';
      PINUSE='POWER';
      NO_LOAD_CHECK='Both';
      NO_IO_CHECK='Both';
      NO_ASSERT_CHECK='TRUE';
      NO_DIR_CHECK='TRUE';
      ALLOW_CONNECT='TRUE';
    'VSS532':
      PIN_NUMBER='(0,0,0,0,0,0,0,0,0,0,0,0,0,0,0,0,0,0,0,0,0,0,0,0,0,0,0,0,0,0,0,0,0,0,0,0,BP77,0,0,0,0,0)';
      PINUSE='POWER';
      NO_LOAD_CHECK='Both';
      NO_IO_CHECK='Both';
      NO_ASSERT_CHECK='TRUE';
      NO_DIR_CHECK='TRUE';
      ALLOW_CONNECT='TRUE';
    'VSS531':
      PIN_NUMBER='(0,0,0,0,0,0,0,0,0,0,0,0,0,0,0,0,0,0,0,0,0,0,0,0,0,0,0,0,0,0,0,0,0,0,0,0,BP75,0,0,0,0,0)';
      PINUSE='POWER';
      NO_LOAD_CHECK='Both';
      NO_IO_CHECK='Both';
      NO_ASSERT_CHECK='TRUE';
      NO_DIR_CHECK='TRUE';
      ALLOW_CONNECT='TRUE';
    'VSS530':
      PIN_NUMBER='(0,0,0,0,0,0,0,0,0,0,0,0,0,0,0,0,0,0,0,0,0,0,0,0,0,0,0,0,0,0,0,0,0,0,0,0,BP73,0,0,0,0,0)';
      PINUSE='POWER';
      NO_LOAD_CHECK='Both';
      NO_IO_CHECK='Both';
      NO_ASSERT_CHECK='TRUE';
      NO_DIR_CHECK='TRUE';
      ALLOW_CONNECT='TRUE';
    'VSS529':
      PIN_NUMBER='(0,0,0,0,0,0,0,0,0,0,0,0,0,0,0,0,0,0,0,0,0,0,0,0,0,0,0,0,0,0,0,0,0,0,0,0,BP71,0,0,0,0,0)';
      PINUSE='POWER';
      NO_LOAD_CHECK='Both';
      NO_IO_CHECK='Both';
      NO_ASSERT_CHECK='TRUE';
      NO_DIR_CHECK='TRUE';
      ALLOW_CONNECT='TRUE';
    'VSS528':
      PIN_NUMBER='(0,0,0,0,0,0,0,0,0,0,0,0,0,0,0,0,0,0,0,0,0,0,0,0,0,0,0,0,0,0,0,0,0,0,0,0,BP63,0,0,0,0,0)';
      PINUSE='POWER';
      NO_LOAD_CHECK='Both';
      NO_IO_CHECK='Both';
      NO_ASSERT_CHECK='TRUE';
      NO_DIR_CHECK='TRUE';
      ALLOW_CONNECT='TRUE';
    'VSS527':
      PIN_NUMBER='(0,0,0,0,0,0,0,0,0,0,0,0,0,0,0,0,0,0,0,0,0,0,0,0,0,0,0,0,0,0,0,0,0,0,0,0,BP4,0,0,0,0,0)';
      PINUSE='POWER';
      NO_LOAD_CHECK='Both';
      NO_IO_CHECK='Both';
      NO_ASSERT_CHECK='TRUE';
      NO_DIR_CHECK='TRUE';
      ALLOW_CONNECT='TRUE';
    'VSS525':
      PIN_NUMBER='(0,0,0,0,0,0,0,0,0,0,0,0,0,0,0,0,0,0,0,0,0,0,0,0,0,0,0,0,0,0,0,0,0,0,0,0,BP20,0,0,0,0,0)';
      PINUSE='POWER';
      NO_LOAD_CHECK='Both';
      NO_IO_CHECK='Both';
      NO_ASSERT_CHECK='TRUE';
      NO_DIR_CHECK='TRUE';
      ALLOW_CONNECT='TRUE';
    'VSS524':
      PIN_NUMBER='(0,0,0,0,0,0,0,0,0,0,0,0,0,0,0,0,0,0,0,0,0,0,0,0,0,0,0,0,0,0,0,0,0,0,0,0,BP2,0,0,0,0,0)';
      PINUSE='POWER';
      NO_LOAD_CHECK='Both';
      NO_IO_CHECK='Both';
      NO_ASSERT_CHECK='TRUE';
      NO_DIR_CHECK='TRUE';
      ALLOW_CONNECT='TRUE';
    'VSS523':
      PIN_NUMBER='(0,0,0,0,0,0,0,0,0,0,0,0,0,0,0,0,0,0,0,0,0,0,0,0,0,0,0,0,0,0,0,0,0,0,0,0,BP16,0,0,0,0,0)';
      PINUSE='POWER';
      NO_LOAD_CHECK='Both';
      NO_IO_CHECK='Both';
      NO_ASSERT_CHECK='TRUE';
      NO_DIR_CHECK='TRUE';
      ALLOW_CONNECT='TRUE';
    'VSS522':
      PIN_NUMBER='(0,0,0,0,0,0,0,0,0,0,0,0,0,0,0,0,0,0,0,0,0,0,0,0,0,0,0,0,0,0,0,0,0,0,0,0,BP12,0,0,0,0,0)';
      PINUSE='POWER';
      NO_LOAD_CHECK='Both';
      NO_IO_CHECK='Both';
      NO_ASSERT_CHECK='TRUE';
      NO_DIR_CHECK='TRUE';
      ALLOW_CONNECT='TRUE';
    'VSS520':
      PIN_NUMBER='(0,0,0,0,0,0,0,0,0,0,0,0,0,0,0,0,0,0,0,0,0,0,0,0,0,0,0,0,0,0,0,0,0,0,0,0,BN70,0,0,0,0,0)';
      PINUSE='POWER';
      NO_LOAD_CHECK='Both';
      NO_IO_CHECK='Both';
      NO_ASSERT_CHECK='TRUE';
      NO_DIR_CHECK='TRUE';
      ALLOW_CONNECT='TRUE';
    'VSS519':
      PIN_NUMBER='(0,0,0,0,0,0,0,0,0,0,0,0,0,0,0,0,0,0,0,0,0,0,0,0,0,0,0,0,0,0,0,0,0,0,0,0,BN62,0,0,0,0,0)';
      PINUSE='POWER';
      NO_LOAD_CHECK='Both';
      NO_IO_CHECK='Both';
      NO_ASSERT_CHECK='TRUE';
      NO_DIR_CHECK='TRUE';
      ALLOW_CONNECT='TRUE';
    'VSS518':
      PIN_NUMBER='(0,0,0,0,0,0,0,0,0,0,0,0,0,0,0,0,0,0,0,0,0,0,0,0,0,0,0,0,0,0,0,0,0,0,0,0,BN31,0,0,0,0,0)';
      PINUSE='POWER';
      NO_LOAD_CHECK='Both';
      NO_IO_CHECK='Both';
      NO_ASSERT_CHECK='TRUE';
      NO_DIR_CHECK='TRUE';
      ALLOW_CONNECT='TRUE';
    'VSS517':
      PIN_NUMBER='(0,0,0,0,0,0,0,0,0,0,0,0,0,0,0,0,0,0,0,0,0,0,0,0,0,0,0,0,0,0,0,0,0,0,0,0,BM8,0,0,0,0,0)';
      PINUSE='POWER';
      NO_LOAD_CHECK='Both';
      NO_IO_CHECK='Both';
      NO_ASSERT_CHECK='TRUE';
      NO_DIR_CHECK='TRUE';
      ALLOW_CONNECT='TRUE';
    'VSS516':
      PIN_NUMBER='(0,0,0,0,0,0,0,0,0,0,0,0,0,0,0,0,0,0,0,0,0,0,0,0,0,0,0,0,0,0,0,0,0,0,0,0,BM77,0,0,0,0,0)';
      PINUSE='POWER';
      NO_LOAD_CHECK='Both';
      NO_IO_CHECK='Both';
      NO_ASSERT_CHECK='TRUE';
      NO_DIR_CHECK='TRUE';
      ALLOW_CONNECT='TRUE';
    'VSS515':
      PIN_NUMBER='(0,0,0,0,0,0,0,0,0,0,0,0,0,0,0,0,0,0,0,0,0,0,0,0,0,0,0,0,0,0,0,0,0,0,0,0,BM73,0,0,0,0,0)';
      PINUSE='POWER';
      NO_LOAD_CHECK='Both';
      NO_IO_CHECK='Both';
      NO_ASSERT_CHECK='TRUE';
      NO_DIR_CHECK='TRUE';
      ALLOW_CONNECT='TRUE';
    'VSS513':
      PIN_NUMBER='(0,0,0,0,0,0,0,0,0,0,0,0,0,0,0,0,0,0,0,0,0,0,0,0,0,0,0,0,0,0,0,0,0,0,0,0,BM61,0,0,0,0,0)';
      PINUSE='POWER';
      NO_LOAD_CHECK='Both';
      NO_IO_CHECK='Both';
      NO_ASSERT_CHECK='TRUE';
      NO_DIR_CHECK='TRUE';
      ALLOW_CONNECT='TRUE';
    'VSS512':
      PIN_NUMBER='(0,0,0,0,0,0,0,0,0,0,0,0,0,0,0,0,0,0,0,0,0,0,0,0,0,0,0,0,0,0,0,0,0,0,0,0,BM4,0,0,0,0,0)';
      PINUSE='POWER';
      NO_LOAD_CHECK='Both';
      NO_IO_CHECK='Both';
      NO_ASSERT_CHECK='TRUE';
      NO_DIR_CHECK='TRUE';
      ALLOW_CONNECT='TRUE';
    'VSS511':
      PIN_NUMBER='(0,0,0,0,0,0,0,0,0,0,0,0,0,0,0,0,0,0,0,0,0,0,0,0,0,0,0,0,0,0,0,0,0,0,0,0,BM26,0,0,0,0,0)';
      PINUSE='POWER';
      NO_LOAD_CHECK='Both';
      NO_IO_CHECK='Both';
      NO_ASSERT_CHECK='TRUE';
      NO_DIR_CHECK='TRUE';
      ALLOW_CONNECT='TRUE';
    'VSS510':
      PIN_NUMBER='(0,0,0,0,0,0,0,0,0,0,0,0,0,0,0,0,0,0,0,0,0,0,0,0,0,0,0,0,0,0,0,0,0,0,0,0,BM24,0,0,0,0,0)';
      PINUSE='POWER';
      NO_LOAD_CHECK='Both';
      NO_IO_CHECK='Both';
      NO_ASSERT_CHECK='TRUE';
      NO_DIR_CHECK='TRUE';
      ALLOW_CONNECT='TRUE';
    'VSS509':
      PIN_NUMBER='(0,0,0,0,0,0,0,0,0,0,0,0,0,0,0,0,0,0,0,0,0,0,0,0,0,0,0,0,0,0,0,0,0,0,0,0,BM22,0,0,0,0,0)';
      PINUSE='POWER';
      NO_LOAD_CHECK='Both';
      NO_IO_CHECK='Both';
      NO_ASSERT_CHECK='TRUE';
      NO_DIR_CHECK='TRUE';
      ALLOW_CONNECT='TRUE';
    'VSS508':
      PIN_NUMBER='(0,0,0,0,0,0,0,0,0,0,0,0,0,0,0,0,0,0,0,0,0,0,0,0,0,0,0,0,0,0,0,0,0,0,0,0,BM20,0,0,0,0,0)';
      PINUSE='POWER';
      NO_LOAD_CHECK='Both';
      NO_IO_CHECK='Both';
      NO_ASSERT_CHECK='TRUE';
      NO_DIR_CHECK='TRUE';
      ALLOW_CONNECT='TRUE';
    'VSS507':
      PIN_NUMBER='(0,0,0,0,0,0,0,0,0,0,0,0,0,0,0,0,0,0,0,0,0,0,0,0,0,0,0,0,0,0,0,0,0,0,0,0,BM16,0,0,0,0,0)';
      PINUSE='POWER';
      NO_LOAD_CHECK='Both';
      NO_IO_CHECK='Both';
      NO_ASSERT_CHECK='TRUE';
      NO_DIR_CHECK='TRUE';
      ALLOW_CONNECT='TRUE';
    'VSS506':
      PIN_NUMBER='(0,0,0,0,0,0,0,0,0,0,0,0,0,0,0,0,0,0,0,0,0,0,0,0,0,0,0,0,0,0,0,0,0,0,0,0,BM12,0,0,0,0,0)';
      PINUSE='POWER';
      NO_LOAD_CHECK='Both';
      NO_IO_CHECK='Both';
      NO_ASSERT_CHECK='TRUE';
      NO_DIR_CHECK='TRUE';
      ALLOW_CONNECT='TRUE';
    'VSS505':
      PIN_NUMBER='(0,0,0,0,0,0,0,0,0,0,0,0,0,0,0,0,0,0,0,0,0,0,0,0,0,0,0,0,0,0,0,0,0,0,0,0,BL9,0,0,0,0,0)';
      PINUSE='POWER';
      NO_LOAD_CHECK='Both';
      NO_IO_CHECK='Both';
      NO_ASSERT_CHECK='TRUE';
      NO_DIR_CHECK='TRUE';
      ALLOW_CONNECT='TRUE';
    'VSS504':
      PIN_NUMBER='(0,0,0,0,0,0,0,0,0,0,0,0,0,0,0,0,0,0,0,0,0,0,0,0,0,0,0,0,0,0,0,0,0,0,0,0,BL78,0,0,0,0,0)';
      PINUSE='POWER';
      NO_LOAD_CHECK='Both';
      NO_IO_CHECK='Both';
      NO_ASSERT_CHECK='TRUE';
      NO_DIR_CHECK='TRUE';
      ALLOW_CONNECT='TRUE';
    'VSS503':
      PIN_NUMBER='(0,0,0,0,0,0,0,0,0,0,0,0,0,0,0,0,0,0,0,0,0,0,0,0,0,0,0,0,0,0,0,0,0,0,0,0,BL72,0,0,0,0,0)';
      PINUSE='POWER';
      NO_LOAD_CHECK='Both';
      NO_IO_CHECK='Both';
      NO_ASSERT_CHECK='TRUE';
      NO_DIR_CHECK='TRUE';
      ALLOW_CONNECT='TRUE';
    'VSS502':
      PIN_NUMBER='(0,0,0,0,0,0,0,0,0,0,0,0,0,0,0,0,0,0,0,0,0,0,0,0,0,0,0,0,0,0,0,0,0,0,0,0,BL70,0,0,0,0,0)';
      PINUSE='POWER';
      NO_LOAD_CHECK='Both';
      NO_IO_CHECK='Both';
      NO_ASSERT_CHECK='TRUE';
      NO_DIR_CHECK='TRUE';
      ALLOW_CONNECT='TRUE';
    'VSS501':
      PIN_NUMBER='(0,0,0,0,0,0,0,0,0,0,0,0,0,0,0,0,0,0,0,0,0,0,0,0,0,0,0,0,0,0,0,0,0,0,0,0,BL68,0,0,0,0,0)';
      PINUSE='POWER';
      NO_LOAD_CHECK='Both';
      NO_IO_CHECK='Both';
      NO_ASSERT_CHECK='TRUE';
      NO_DIR_CHECK='TRUE';
      ALLOW_CONNECT='TRUE';
    'VSS500':
      PIN_NUMBER='(0,0,0,0,0,0,0,0,0,0,0,0,0,0,0,0,0,0,0,0,0,0,0,0,0,0,0,0,0,0,0,0,0,0,0,0,BL5,0,0,0,0,0)';
      PINUSE='POWER';
      NO_LOAD_CHECK='Both';
      NO_IO_CHECK='Both';
      NO_ASSERT_CHECK='TRUE';
      NO_DIR_CHECK='TRUE';
      ALLOW_CONNECT='TRUE';
    'VSS499':
      PIN_NUMBER='(0,0,0,0,0,0,0,0,0,0,0,0,0,0,0,0,0,0,0,0,0,0,0,0,0,0,0,0,0,0,0,0,0,0,0,0,BL17,0,0,0,0,0)';
      PINUSE='POWER';
      NO_LOAD_CHECK='Both';
      NO_IO_CHECK='Both';
      NO_ASSERT_CHECK='TRUE';
      NO_DIR_CHECK='TRUE';
      ALLOW_CONNECT='TRUE';
    'VSS498':
      PIN_NUMBER='(0,0,0,0,0,0,0,0,0,0,0,0,0,0,0,0,0,0,0,0,0,0,0,0,0,0,0,0,0,0,0,0,0,0,0,0,BL13,0,0,0,0,0)';
      PINUSE='POWER';
      NO_LOAD_CHECK='Both';
      NO_IO_CHECK='Both';
      NO_ASSERT_CHECK='TRUE';
      NO_DIR_CHECK='TRUE';
      ALLOW_CONNECT='TRUE';
    'VSS497':
      PIN_NUMBER='(0,0,0,0,0,0,0,0,0,0,0,0,0,0,0,0,0,0,0,0,0,0,0,0,0,0,0,0,0,0,0,0,0,0,0,0,BL1,0,0,0,0,0)';
      PINUSE='POWER';
      NO_LOAD_CHECK='Both';
      NO_IO_CHECK='Both';
      NO_ASSERT_CHECK='TRUE';
      NO_DIR_CHECK='TRUE';
      ALLOW_CONNECT='TRUE';
    'VSS496':
      PIN_NUMBER='(0,0,0,0,0,0,0,0,0,0,0,0,0,0,0,0,0,0,0,0,0,0,0,0,0,0,0,0,0,0,0,0,0,0,0,0,BK8,0,0,0,0,0)';
      PINUSE='POWER';
      NO_LOAD_CHECK='Both';
      NO_IO_CHECK='Both';
      NO_ASSERT_CHECK='TRUE';
      NO_DIR_CHECK='TRUE';
      ALLOW_CONNECT='TRUE';
    'VSS495':
      PIN_NUMBER='(0,0,0,0,0,0,0,0,0,0,0,0,0,0,0,0,0,0,0,0,0,0,0,0,0,0,0,0,0,0,0,0,0,0,0,0,BK79,0,0,0,0,0)';
      PINUSE='POWER';
      NO_LOAD_CHECK='Both';
      NO_IO_CHECK='Both';
      NO_ASSERT_CHECK='TRUE';
      NO_DIR_CHECK='TRUE';
      ALLOW_CONNECT='TRUE';
    'VSS494':
      PIN_NUMBER='(0,0,0,0,0,0,0,0,0,0,0,0,0,0,0,0,0,0,0,0,0,0,0,0,0,0,0,0,0,0,0,0,0,0,0,0,BK75,0,0,0,0,0)';
      PINUSE='POWER';
      NO_LOAD_CHECK='Both';
      NO_IO_CHECK='Both';
      NO_ASSERT_CHECK='TRUE';
      NO_DIR_CHECK='TRUE';
      ALLOW_CONNECT='TRUE';
    'VSS492':
      PIN_NUMBER='(0,0,0,0,0,0,0,0,0,0,0,0,0,0,0,0,0,0,0,0,0,0,0,0,0,0,0,0,0,0,0,0,0,0,0,0,BK71,0,0,0,0,0)';
      PINUSE='POWER';
      NO_LOAD_CHECK='Both';
      NO_IO_CHECK='Both';
      NO_ASSERT_CHECK='TRUE';
      NO_DIR_CHECK='TRUE';
      ALLOW_CONNECT='TRUE';
    'VSS491':
      PIN_NUMBER='(0,0,0,0,0,0,0,0,0,0,0,0,0,0,0,0,0,0,0,0,0,0,0,0,0,0,0,0,0,0,0,0,0,0,0,0,BK65,0,0,0,0,0)';
      PINUSE='POWER';
      NO_LOAD_CHECK='Both';
      NO_IO_CHECK='Both';
      NO_ASSERT_CHECK='TRUE';
      NO_DIR_CHECK='TRUE';
      ALLOW_CONNECT='TRUE';
    'VSS490':
      PIN_NUMBER='(0,0,0,0,0,0,0,0,0,0,0,0,0,0,0,0,0,0,0,0,0,0,0,0,0,0,0,0,0,0,0,0,0,0,0,0,BK4,0,0,0,0,0)';
      PINUSE='POWER';
      NO_LOAD_CHECK='Both';
      NO_IO_CHECK='Both';
      NO_ASSERT_CHECK='TRUE';
      NO_DIR_CHECK='TRUE';
      ALLOW_CONNECT='TRUE';
    'VSS489':
      PIN_NUMBER='(0,0,0,0,0,0,0,0,0,0,0,0,0,0,0,0,0,0,0,0,0,0,0,0,0,0,0,0,0,0,0,0,0,0,0,0,BK20,0,0,0,0,0)';
      PINUSE='POWER';
      NO_LOAD_CHECK='Both';
      NO_IO_CHECK='Both';
      NO_ASSERT_CHECK='TRUE';
      NO_DIR_CHECK='TRUE';
      ALLOW_CONNECT='TRUE';
    'VSS488':
      PIN_NUMBER='(0,0,0,0,0,0,0,0,0,0,0,0,0,0,0,0,0,0,0,0,0,0,0,0,0,0,0,0,0,0,0,0,0,0,0,0,BK16,0,0,0,0,0)';
      PINUSE='POWER';
      NO_LOAD_CHECK='Both';
      NO_IO_CHECK='Both';
      NO_ASSERT_CHECK='TRUE';
      NO_DIR_CHECK='TRUE';
      ALLOW_CONNECT='TRUE';
    'VSS487':
      PIN_NUMBER='(0,0,0,0,0,0,0,0,0,0,0,0,0,0,0,0,0,0,0,0,0,0,0,0,0,0,0,0,0,0,0,0,0,0,0,0,BK12,0,0,0,0,0)';
      PINUSE='POWER';
      NO_LOAD_CHECK='Both';
      NO_IO_CHECK='Both';
      NO_ASSERT_CHECK='TRUE';
      NO_DIR_CHECK='TRUE';
      ALLOW_CONNECT='TRUE';
    'VSS486':
      PIN_NUMBER='(0,0,0,0,0,0,0,0,0,0,0,0,0,0,0,0,0,0,0,0,0,0,0,0,0,0,0,0,0,0,0,0,0,0,0,0,BJ90,0,0,0,0,0)';
      PINUSE='POWER';
      NO_LOAD_CHECK='Both';
      NO_IO_CHECK='Both';
      NO_ASSERT_CHECK='TRUE';
      NO_DIR_CHECK='TRUE';
      ALLOW_CONNECT='TRUE';
    'VSS485':
      PIN_NUMBER='(0,0,0,0,0,0,0,0,0,0,0,0,0,0,0,0,0,0,0,0,0,0,0,0,0,0,0,0,0,0,0,0,0,0,0,0,BJ88,0,0,0,0,0)';
      PINUSE='POWER';
      NO_LOAD_CHECK='Both';
      NO_IO_CHECK='Both';
      NO_ASSERT_CHECK='TRUE';
      NO_DIR_CHECK='TRUE';
      ALLOW_CONNECT='TRUE';
    'VSS484':
      PIN_NUMBER='(0,0,0,0,0,0,0,0,0,0,0,0,0,0,0,0,0,0,0,0,0,0,0,0,0,0,0,0,0,0,0,0,0,0,0,0,BJ86,0,0,0,0,0)';
      PINUSE='POWER';
      NO_LOAD_CHECK='Both';
      NO_IO_CHECK='Both';
      NO_ASSERT_CHECK='TRUE';
      NO_DIR_CHECK='TRUE';
      ALLOW_CONNECT='TRUE';
    'VSS483':
      PIN_NUMBER='(0,0,0,0,0,0,0,0,0,0,0,0,0,0,0,0,0,0,0,0,0,0,0,0,0,0,0,0,0,0,0,0,0,0,0,0,BJ84,0,0,0,0,0)';
      PINUSE='POWER';
      NO_LOAD_CHECK='Both';
      NO_IO_CHECK='Both';
      NO_ASSERT_CHECK='TRUE';
      NO_DIR_CHECK='TRUE';
      ALLOW_CONNECT='TRUE';
    'VSS482':
      PIN_NUMBER='(0,0,0,0,0,0,0,0,0,0,0,0,0,0,0,0,0,0,0,0,0,0,0,0,0,0,0,0,0,0,0,0,0,0,0,0,BJ82,0,0,0,0,0)';
      PINUSE='POWER';
      NO_LOAD_CHECK='Both';
      NO_IO_CHECK='Both';
      NO_ASSERT_CHECK='TRUE';
      NO_DIR_CHECK='TRUE';
      ALLOW_CONNECT='TRUE';
    'VSS481':
      PIN_NUMBER='(0,0,0,0,0,0,0,0,0,0,0,0,0,0,0,0,0,0,0,0,0,0,0,0,0,0,0,0,0,0,0,0,0,0,0,0,BJ80,0,0,0,0,0)';
      PINUSE='POWER';
      NO_LOAD_CHECK='Both';
      NO_IO_CHECK='Both';
      NO_ASSERT_CHECK='TRUE';
      NO_DIR_CHECK='TRUE';
      ALLOW_CONNECT='TRUE';
    'VSS480':
      PIN_NUMBER='(0,0,0,0,0,0,0,0,0,0,0,0,0,0,0,0,0,0,0,0,0,0,0,0,0,0,0,0,0,0,0,0,0,0,0,0,BJ68,0,0,0,0,0)';
      PINUSE='POWER';
      NO_LOAD_CHECK='Both';
      NO_IO_CHECK='Both';
      NO_ASSERT_CHECK='TRUE';
      NO_DIR_CHECK='TRUE';
      ALLOW_CONNECT='TRUE';
    'VSS479':
      PIN_NUMBER='(0,0,0,0,0,0,0,0,0,0,0,0,0,0,0,0,0,0,0,0,0,0,0,0,0,0,0,0,0,0,0,0,0,0,0,0,BJ62,0,0,0,0,0)';
      PINUSE='POWER';
      NO_LOAD_CHECK='Both';
      NO_IO_CHECK='Both';
      NO_ASSERT_CHECK='TRUE';
      NO_DIR_CHECK='TRUE';
      ALLOW_CONNECT='TRUE';
    'VSS477':
      PIN_NUMBER='(0,0,0,0,0,0,0,0,0,0,0,0,0,0,0,0,0,0,0,0,0,0,0,0,0,0,0,0,0,0,0,0,0,0,0,0,BH83,0,0,0,0,0)';
      PINUSE='POWER';
      NO_LOAD_CHECK='Both';
      NO_IO_CHECK='Both';
      NO_ASSERT_CHECK='TRUE';
      NO_DIR_CHECK='TRUE';
      ALLOW_CONNECT='TRUE';
    'VSS476':
      PIN_NUMBER='(0,0,0,0,0,0,0,0,0,0,0,0,0,0,0,0,0,0,0,0,0,0,0,0,0,0,0,0,0,0,0,0,0,0,0,0,BH81,0,0,0,0,0)';
      PINUSE='POWER';
      NO_LOAD_CHECK='Both';
      NO_IO_CHECK='Both';
      NO_ASSERT_CHECK='TRUE';
      NO_DIR_CHECK='TRUE';
      ALLOW_CONNECT='TRUE';
    'VSS475':
      PIN_NUMBER='(0,0,0,0,0,0,0,0,0,0,0,0,0,0,0,0,0,0,0,0,0,0,0,0,0,0,0,0,0,0,0,0,0,0,0,0,BH8,0,0,0,0,0)';
      PINUSE='POWER';
      NO_LOAD_CHECK='Both';
      NO_IO_CHECK='Both';
      NO_ASSERT_CHECK='TRUE';
      NO_DIR_CHECK='TRUE';
      ALLOW_CONNECT='TRUE';
    'VSS474':
      PIN_NUMBER='(0,0,0,0,0,0,0,0,0,0,0,0,0,0,0,0,0,0,0,0,0,0,0,0,0,0,0,0,0,0,0,0,0,0,0,0,BH77,0,0,0,0,0)';
      PINUSE='POWER';
      NO_LOAD_CHECK='Both';
      NO_IO_CHECK='Both';
      NO_ASSERT_CHECK='TRUE';
      NO_DIR_CHECK='TRUE';
      ALLOW_CONNECT='TRUE';
    'VSS473':
      PIN_NUMBER='(0,0,0,0,0,0,0,0,0,0,0,0,0,0,0,0,0,0,0,0,0,0,0,0,0,0,0,0,0,0,0,0,0,0,0,0,BH73,0,0,0,0,0)';
      PINUSE='POWER';
      NO_LOAD_CHECK='Both';
      NO_IO_CHECK='Both';
      NO_ASSERT_CHECK='TRUE';
      NO_DIR_CHECK='TRUE';
      ALLOW_CONNECT='TRUE';
    'VSS472':
      PIN_NUMBER='(0,0,0,0,0,0,0,0,0,0,0,0,0,0,0,0,0,0,0,0,0,0,0,0,0,0,0,0,0,0,0,0,0,0,0,0,BH67,0,0,0,0,0)';
      PINUSE='POWER';
      NO_LOAD_CHECK='Both';
      NO_IO_CHECK='Both';
      NO_ASSERT_CHECK='TRUE';
      NO_DIR_CHECK='TRUE';
      ALLOW_CONNECT='TRUE';
    'VSS470':
      PIN_NUMBER='(0,0,0,0,0,0,0,0,0,0,0,0,0,0,0,0,0,0,0,0,0,0,0,0,0,0,0,0,0,0,0,0,0,0,0,0,BH4,0,0,0,0,0)';
      PINUSE='POWER';
      NO_LOAD_CHECK='Both';
      NO_IO_CHECK='Both';
      NO_ASSERT_CHECK='TRUE';
      NO_DIR_CHECK='TRUE';
      ALLOW_CONNECT='TRUE';
    'VSS469':
      PIN_NUMBER='(0,0,0,0,0,0,0,0,0,0,0,0,0,0,0,0,0,0,0,0,0,0,0,0,0,0,0,0,0,0,0,0,0,0,0,0,BH20,0,0,0,0,0)';
      PINUSE='POWER';
      NO_LOAD_CHECK='Both';
      NO_IO_CHECK='Both';
      NO_ASSERT_CHECK='TRUE';
      NO_DIR_CHECK='TRUE';
      ALLOW_CONNECT='TRUE';
    'VSS468':
      PIN_NUMBER='(0,0,0,0,0,0,0,0,0,0,0,0,0,0,0,0,0,0,0,0,0,0,0,0,0,0,0,0,0,0,0,0,0,0,0,0,BH16,0,0,0,0,0)';
      PINUSE='POWER';
      NO_LOAD_CHECK='Both';
      NO_IO_CHECK='Both';
      NO_ASSERT_CHECK='TRUE';
      NO_DIR_CHECK='TRUE';
      ALLOW_CONNECT='TRUE';
    'VSS467':
      PIN_NUMBER='(0,0,0,0,0,0,0,0,0,0,0,0,0,0,0,0,0,0,0,0,0,0,0,0,0,0,0,0,0,0,0,0,0,0,0,0,BH12,0,0,0,0,0)';
      PINUSE='POWER';
      NO_LOAD_CHECK='Both';
      NO_IO_CHECK='Both';
      NO_ASSERT_CHECK='TRUE';
      NO_DIR_CHECK='TRUE';
      ALLOW_CONNECT='TRUE';
    'VSS466':
      PIN_NUMBER='(0,0,0,0,0,0,0,0,0,0,0,0,0,0,0,0,0,0,0,0,0,0,0,0,0,0,0,0,0,0,0,0,0,0,0,0,BG9,0,0,0,0,0)';
      PINUSE='POWER';
      NO_LOAD_CHECK='Both';
      NO_IO_CHECK='Both';
      NO_ASSERT_CHECK='TRUE';
      NO_DIR_CHECK='TRUE';
      ALLOW_CONNECT='TRUE';
    'VSS465':
      PIN_NUMBER='(0,0,0,0,0,0,0,0,0,0,0,0,0,0,0,0,0,0,0,0,0,0,0,0,0,0,0,0,0,0,0,0,0,0,0,0,BG70,0,0,0,0,0)';
      PINUSE='POWER';
      NO_LOAD_CHECK='Both';
      NO_IO_CHECK='Both';
      NO_ASSERT_CHECK='TRUE';
      NO_DIR_CHECK='TRUE';
      ALLOW_CONNECT='TRUE';
    'VSS464':
      PIN_NUMBER='(0,0,0,0,0,0,0,0,0,0,0,0,0,0,0,0,0,0,0,0,0,0,0,0,0,0,0,0,0,0,0,0,0,0,0,0,BG5,0,0,0,0,0)';
      PINUSE='POWER';
      NO_LOAD_CHECK='Both';
      NO_IO_CHECK='Both';
      NO_ASSERT_CHECK='TRUE';
      NO_DIR_CHECK='TRUE';
      ALLOW_CONNECT='TRUE';
    'VSS463':
      PIN_NUMBER='(0,0,0,0,0,0,0,0,0,0,0,0,0,0,0,0,0,0,0,0,0,0,0,0,0,0,0,0,0,0,0,0,0,0,0,0,BG25,0,0,0,0,0)';
      PINUSE='POWER';
      NO_LOAD_CHECK='Both';
      NO_IO_CHECK='Both';
      NO_ASSERT_CHECK='TRUE';
      NO_DIR_CHECK='TRUE';
      ALLOW_CONNECT='TRUE';
    'VSS462':
      PIN_NUMBER='(0,0,0,0,0,0,0,0,0,0,0,0,0,0,0,0,0,0,0,0,0,0,0,0,0,0,0,0,0,0,0,0,0,0,0,0,BG23,0,0,0,0,0)';
      PINUSE='POWER';
      NO_LOAD_CHECK='Both';
      NO_IO_CHECK='Both';
      NO_ASSERT_CHECK='TRUE';
      NO_DIR_CHECK='TRUE';
      ALLOW_CONNECT='TRUE';
    'VSS461':
      PIN_NUMBER='(0,0,0,0,0,0,0,0,0,0,0,0,0,0,0,0,0,0,0,0,0,0,0,0,0,0,0,0,0,0,0,0,0,0,0,0,BG21,0,0,0,0,0)';
      PINUSE='POWER';
      NO_LOAD_CHECK='Both';
      NO_IO_CHECK='Both';
      NO_ASSERT_CHECK='TRUE';
      NO_DIR_CHECK='TRUE';
      ALLOW_CONNECT='TRUE';
    'VSS460':
      PIN_NUMBER='(0,0,0,0,0,0,0,0,0,0,0,0,0,0,0,0,0,0,0,0,0,0,0,0,0,0,0,0,0,0,0,0,0,0,0,0,BG17,0,0,0,0,0)';
      PINUSE='POWER';
      NO_LOAD_CHECK='Both';
      NO_IO_CHECK='Both';
      NO_ASSERT_CHECK='TRUE';
      NO_DIR_CHECK='TRUE';
      ALLOW_CONNECT='TRUE';
    'VSS459':
      PIN_NUMBER='(0,0,0,0,0,0,0,0,0,0,0,0,0,0,0,0,0,0,0,0,0,0,0,0,0,0,0,0,0,0,0,0,0,0,0,0,BG13,0,0,0,0,0)';
      PINUSE='POWER';
      NO_LOAD_CHECK='Both';
      NO_IO_CHECK='Both';
      NO_ASSERT_CHECK='TRUE';
      NO_DIR_CHECK='TRUE';
      ALLOW_CONNECT='TRUE';
    'VSS458':
      PIN_NUMBER='(0,0,0,0,0,0,0,0,0,0,0,0,0,0,0,0,0,0,0,0,0,0,0,0,0,0,0,0,0,0,0,0,0,0,0,0,BG1,0,0,0,0,0)';
      PINUSE='POWER';
      NO_LOAD_CHECK='Both';
      NO_IO_CHECK='Both';
      NO_ASSERT_CHECK='TRUE';
      NO_DIR_CHECK='TRUE';
      ALLOW_CONNECT='TRUE';
    'VSS457':
      PIN_NUMBER='(0,0,0,0,0,0,0,0,0,0,0,0,0,0,0,0,0,0,0,0,0,0,0,0,0,0,0,0,0,0,0,0,0,0,0,0,BF83,0,0,0,0,0)';
      PINUSE='POWER';
      NO_LOAD_CHECK='Both';
      NO_IO_CHECK='Both';
      NO_ASSERT_CHECK='TRUE';
      NO_DIR_CHECK='TRUE';
      ALLOW_CONNECT='TRUE';
    'VSS456':
      PIN_NUMBER='(0,0,0,0,0,0,0,0,0,0,0,0,0,0,0,0,0,0,0,0,0,0,0,0,0,0,0,0,0,0,0,0,0,0,0,0,BF8,0,0,0,0,0)';
      PINUSE='POWER';
      NO_LOAD_CHECK='Both';
      NO_IO_CHECK='Both';
      NO_ASSERT_CHECK='TRUE';
      NO_DIR_CHECK='TRUE';
      ALLOW_CONNECT='TRUE';
    'VSS455':
      PIN_NUMBER='(0,0,0,0,0,0,0,0,0,0,0,0,0,0,0,0,0,0,0,0,0,0,0,0,0,0,0,0,0,0,0,0,0,0,0,0,BF79,0,0,0,0,0)';
      PINUSE='POWER';
      NO_LOAD_CHECK='Both';
      NO_IO_CHECK='Both';
      NO_ASSERT_CHECK='TRUE';
      NO_DIR_CHECK='TRUE';
      ALLOW_CONNECT='TRUE';
    'VSS454':
      PIN_NUMBER='(0,0,0,0,0,0,0,0,0,0,0,0,0,0,0,0,0,0,0,0,0,0,0,0,0,0,0,0,0,0,0,0,0,0,0,0,BF75,0,0,0,0,0)';
      PINUSE='POWER';
      NO_LOAD_CHECK='Both';
      NO_IO_CHECK='Both';
      NO_ASSERT_CHECK='TRUE';
      NO_DIR_CHECK='TRUE';
      ALLOW_CONNECT='TRUE';
    'VSS453':
      PIN_NUMBER='(0,0,0,0,0,0,0,0,0,0,0,0,0,0,0,0,0,0,0,0,0,0,0,0,0,0,0,0,0,0,0,0,0,0,0,0,BF73,0,0,0,0,0)';
      PINUSE='POWER';
      NO_LOAD_CHECK='Both';
      NO_IO_CHECK='Both';
      NO_ASSERT_CHECK='TRUE';
      NO_DIR_CHECK='TRUE';
      ALLOW_CONNECT='TRUE';
    'VSS452':
      PIN_NUMBER='(0,0,0,0,0,0,0,0,0,0,0,0,0,0,0,0,0,0,0,0,0,0,0,0,0,0,0,0,0,0,0,0,0,0,0,0,BF63,0,0,0,0,0)';
      PINUSE='POWER';
      NO_LOAD_CHECK='Both';
      NO_IO_CHECK='Both';
      NO_ASSERT_CHECK='TRUE';
      NO_DIR_CHECK='TRUE';
      ALLOW_CONNECT='TRUE';
    'VSS451':
      PIN_NUMBER='(0,0,0,0,0,0,0,0,0,0,0,0,0,0,0,0,0,0,0,0,0,0,0,0,0,0,0,0,0,0,0,0,0,0,0,0,BF61,0,0,0,0,0)';
      PINUSE='POWER';
      NO_LOAD_CHECK='Both';
      NO_IO_CHECK='Both';
      NO_ASSERT_CHECK='TRUE';
      NO_DIR_CHECK='TRUE';
      ALLOW_CONNECT='TRUE';
    'VSS450':
      PIN_NUMBER='(0,0,0,0,0,0,0,0,0,0,0,0,0,0,0,0,0,0,0,0,0,0,0,0,0,0,0,0,0,0,0,0,0,0,0,0,BF4,0,0,0,0,0)';
      PINUSE='POWER';
      NO_LOAD_CHECK='Both';
      NO_IO_CHECK='Both';
      NO_ASSERT_CHECK='TRUE';
      NO_DIR_CHECK='TRUE';
      ALLOW_CONNECT='TRUE';
    'VSS449':
      PIN_NUMBER='(0,0,0,0,0,0,0,0,0,0,0,0,0,0,0,0,0,0,0,0,0,0,0,0,0,0,0,0,0,0,0,0,0,0,0,0,BF20,0,0,0,0,0)';
      PINUSE='POWER';
      NO_LOAD_CHECK='Both';
      NO_IO_CHECK='Both';
      NO_ASSERT_CHECK='TRUE';
      NO_DIR_CHECK='TRUE';
      ALLOW_CONNECT='TRUE';
    'VSS448':
      PIN_NUMBER='(0,0,0,0,0,0,0,0,0,0,0,0,0,0,0,0,0,0,0,0,0,0,0,0,0,0,0,0,0,0,0,0,0,0,0,0,BF16,0,0,0,0,0)';
      PINUSE='POWER';
      NO_LOAD_CHECK='Both';
      NO_IO_CHECK='Both';
      NO_ASSERT_CHECK='TRUE';
      NO_DIR_CHECK='TRUE';
      ALLOW_CONNECT='TRUE';
    'VSS447':
      PIN_NUMBER='(0,0,0,0,0,0,0,0,0,0,0,0,0,0,0,0,0,0,0,0,0,0,0,0,0,0,0,0,0,0,0,0,0,0,0,0,BF12,0,0,0,0,0)';
      PINUSE='POWER';
      NO_LOAD_CHECK='Both';
      NO_IO_CHECK='Both';
      NO_ASSERT_CHECK='TRUE';
      NO_DIR_CHECK='TRUE';
      ALLOW_CONNECT='TRUE';
    'VSS446':
      PIN_NUMBER='(0,0,0,0,0,0,0,0,0,0,0,0,0,0,0,0,0,0,0,0,0,0,0,0,0,0,0,0,0,0,0,0,0,0,0,0,BE84,0,0,0,0,0)';
      PINUSE='POWER';
      NO_LOAD_CHECK='Both';
      NO_IO_CHECK='Both';
      NO_ASSERT_CHECK='TRUE';
      NO_DIR_CHECK='TRUE';
      ALLOW_CONNECT='TRUE';
    'VSS445':
      PIN_NUMBER='(0,0,0,0,0,0,0,0,0,0,0,0,0,0,0,0,0,0,0,0,0,0,0,0,0,0,0,0,0,0,0,0,0,0,0,0,BE78,0,0,0,0,0)';
      PINUSE='POWER';
      NO_LOAD_CHECK='Both';
      NO_IO_CHECK='Both';
      NO_ASSERT_CHECK='TRUE';
      NO_DIR_CHECK='TRUE';
      ALLOW_CONNECT='TRUE';
    'VSS444':
      PIN_NUMBER='(0,0,0,0,0,0,0,0,0,0,0,0,0,0,0,0,0,0,0,0,0,0,0,0,0,0,0,0,0,0,0,0,0,0,0,0,BE76,0,0,0,0,0)';
      PINUSE='POWER';
      NO_LOAD_CHECK='Both';
      NO_IO_CHECK='Both';
      NO_ASSERT_CHECK='TRUE';
      NO_DIR_CHECK='TRUE';
      ALLOW_CONNECT='TRUE';
    'VSS443':
      PIN_NUMBER='(0,0,0,0,0,0,0,0,0,0,0,0,0,0,0,0,0,0,0,0,0,0,0,0,0,0,0,0,0,0,0,0,0,0,0,0,BE74,0,0,0,0,0)';
      PINUSE='POWER';
      NO_LOAD_CHECK='Both';
      NO_IO_CHECK='Both';
      NO_ASSERT_CHECK='TRUE';
      NO_DIR_CHECK='TRUE';
      ALLOW_CONNECT='TRUE';
    'VSS442':
      PIN_NUMBER='(0,0,0,0,0,0,0,0,0,0,0,0,0,0,0,0,0,0,0,0,0,0,0,0,0,0,0,0,0,0,0,0,0,0,0,0,BE68,0,0,0,0,0)';
      PINUSE='POWER';
      NO_LOAD_CHECK='Both';
      NO_IO_CHECK='Both';
      NO_ASSERT_CHECK='TRUE';
      NO_DIR_CHECK='TRUE';
      ALLOW_CONNECT='TRUE';
    'VSS441':
      PIN_NUMBER='(0,0,0,0,0,0,0,0,0,0,0,0,0,0,0,0,0,0,0,0,0,0,0,0,0,0,0,0,0,0,0,0,0,0,0,0,BE66,0,0,0,0,0)';
      PINUSE='POWER';
      NO_LOAD_CHECK='Both';
      NO_IO_CHECK='Both';
      NO_ASSERT_CHECK='TRUE';
      NO_DIR_CHECK='TRUE';
      ALLOW_CONNECT='TRUE';
    'VSS440':
      PIN_NUMBER='(0,0,0,0,0,0,0,0,0,0,0,0,0,0,0,0,0,0,0,0,0,0,0,0,0,0,0,0,0,0,0,0,0,0,0,0,BE64,0,0,0,0,0)';
      PINUSE='POWER';
      NO_LOAD_CHECK='Both';
      NO_IO_CHECK='Both';
      NO_ASSERT_CHECK='TRUE';
      NO_DIR_CHECK='TRUE';
      ALLOW_CONNECT='TRUE';
    'VSS439':
      PIN_NUMBER='(0,0,0,0,0,0,0,0,0,0,0,0,0,0,0,0,0,0,0,0,0,0,0,0,0,0,0,0,0,0,0,0,0,0,0,0,BD89,0,0,0,0,0)';
      PINUSE='POWER';
      NO_LOAD_CHECK='Both';
      NO_IO_CHECK='Both';
      NO_ASSERT_CHECK='TRUE';
      NO_DIR_CHECK='TRUE';
      ALLOW_CONNECT='TRUE';
    'VSS437':
      PIN_NUMBER='(0,0,0,0,0,0,0,0,0,0,0,0,0,0,0,0,0,0,0,0,0,0,0,0,0,0,0,0,0,0,0,0,0,0,0,0,BD85,0,0,0,0,0)';
      PINUSE='POWER';
      NO_LOAD_CHECK='Both';
      NO_IO_CHECK='Both';
      NO_ASSERT_CHECK='TRUE';
      NO_DIR_CHECK='TRUE';
      ALLOW_CONNECT='TRUE';
    'VSS435':
      PIN_NUMBER='(0,0,0,0,0,0,0,0,0,0,0,0,0,0,0,0,0,0,0,0,0,0,0,0,0,0,0,0,0,0,0,0,0,0,0,0,BD81,0,0,0,0,0)';
      PINUSE='POWER';
      NO_LOAD_CHECK='Both';
      NO_IO_CHECK='Both';
      NO_ASSERT_CHECK='TRUE';
      NO_DIR_CHECK='TRUE';
      ALLOW_CONNECT='TRUE';
    'VSS434':
      PIN_NUMBER='(0,0,0,0,0,0,0,0,0,0,0,0,0,0,0,0,0,0,0,0,0,0,0,0,0,0,0,0,0,0,0,0,0,0,0,0,BD8,0,0,0,0,0)';
      PINUSE='POWER';
      NO_LOAD_CHECK='Both';
      NO_IO_CHECK='Both';
      NO_ASSERT_CHECK='TRUE';
      NO_DIR_CHECK='TRUE';
      ALLOW_CONNECT='TRUE';
    'VSS433':
      PIN_NUMBER='(0,0,0,0,0,0,0,0,0,0,0,0,0,0,0,0,0,0,0,0,0,0,0,0,0,0,0,0,0,0,0,0,0,0,0,0,BD4,0,0,0,0,0)';
      PINUSE='POWER';
      NO_LOAD_CHECK='Both';
      NO_IO_CHECK='Both';
      NO_ASSERT_CHECK='TRUE';
      NO_DIR_CHECK='TRUE';
      ALLOW_CONNECT='TRUE';
    'VSS432':
      PIN_NUMBER='(0,0,0,0,0,0,0,0,0,0,0,0,0,0,0,0,0,0,0,0,0,0,0,0,0,0,0,0,0,0,0,0,0,0,0,0,BD20,0,0,0,0,0)';
      PINUSE='POWER';
      NO_LOAD_CHECK='Both';
      NO_IO_CHECK='Both';
      NO_ASSERT_CHECK='TRUE';
      NO_DIR_CHECK='TRUE';
      ALLOW_CONNECT='TRUE';
    'VSS431':
      PIN_NUMBER='(0,0,0,0,0,0,0,0,0,0,0,0,0,0,0,0,0,0,0,0,0,0,0,0,0,0,0,0,0,0,0,0,0,0,0,0,BD16,0,0,0,0,0)';
      PINUSE='POWER';
      NO_LOAD_CHECK='Both';
      NO_IO_CHECK='Both';
      NO_ASSERT_CHECK='TRUE';
      NO_DIR_CHECK='TRUE';
      ALLOW_CONNECT='TRUE';
    'VSS430':
      PIN_NUMBER='(0,0,0,0,0,0,0,0,0,0,0,0,0,0,0,0,0,0,0,0,0,0,0,0,0,0,0,0,0,0,0,0,0,0,0,0,BD12,0,0,0,0,0)';
      PINUSE='POWER';
      NO_LOAD_CHECK='Both';
      NO_IO_CHECK='Both';
      NO_ASSERT_CHECK='TRUE';
      NO_DIR_CHECK='TRUE';
      ALLOW_CONNECT='TRUE';
    'VSS429':
      PIN_NUMBER='(0,0,0,0,0,0,0,0,0,0,0,0,0,0,0,0,0,0,0,0,0,0,0,0,0,0,0,0,0,0,0,0,0,0,0,0,BC9,0,0,0,0,0)';
      PINUSE='POWER';
      NO_LOAD_CHECK='Both';
      NO_IO_CHECK='Both';
      NO_ASSERT_CHECK='TRUE';
      NO_DIR_CHECK='TRUE';
      ALLOW_CONNECT='TRUE';
    'VSS428':
      PIN_NUMBER='(0,0,0,0,0,0,0,0,0,0,0,0,0,0,0,0,0,0,0,0,0,0,0,0,0,0,0,0,0,0,0,0,0,0,0,0,BC88,0,0,0,0,0)';
      PINUSE='POWER';
      NO_LOAD_CHECK='Both';
      NO_IO_CHECK='Both';
      NO_ASSERT_CHECK='TRUE';
      NO_DIR_CHECK='TRUE';
      ALLOW_CONNECT='TRUE';
    'VSS427':
      PIN_NUMBER='(0,0,0,0,0,0,0,0,0,0,0,0,0,0,0,0,0,0,0,0,0,0,0,0,0,0,0,0,0,0,0,0,0,0,0,0,BC86,0,0,0,0,0)';
      PINUSE='POWER';
      NO_LOAD_CHECK='Both';
      NO_IO_CHECK='Both';
      NO_ASSERT_CHECK='TRUE';
      NO_DIR_CHECK='TRUE';
      ALLOW_CONNECT='TRUE';
    'VSS426':
      PIN_NUMBER='(0,0,0,0,0,0,0,0,0,0,0,0,0,0,0,0,0,0,0,0,0,0,0,0,0,0,0,0,0,0,0,0,0,0,0,0,BC84,0,0,0,0,0)';
      PINUSE='POWER';
      NO_LOAD_CHECK='Both';
      NO_IO_CHECK='Both';
      NO_ASSERT_CHECK='TRUE';
      NO_DIR_CHECK='TRUE';
      ALLOW_CONNECT='TRUE';
    'VSS425':
      PIN_NUMBER='(0,0,0,0,0,0,0,0,0,0,0,0,0,0,0,0,0,0,0,0,0,0,0,0,0,0,0,0,0,0,0,0,0,0,0,0,BC78,0,0,0,0,0)';
      PINUSE='POWER';
      NO_LOAD_CHECK='Both';
      NO_IO_CHECK='Both';
      NO_ASSERT_CHECK='TRUE';
      NO_DIR_CHECK='TRUE';
      ALLOW_CONNECT='TRUE';
    'VSS424':
      PIN_NUMBER='(0,0,0,0,0,0,0,0,0,0,0,0,0,0,0,0,0,0,0,0,0,0,0,0,0,0,0,0,0,0,0,0,0,0,0,0,BC76,0,0,0,0,0)';
      PINUSE='POWER';
      NO_LOAD_CHECK='Both';
      NO_IO_CHECK='Both';
      NO_ASSERT_CHECK='TRUE';
      NO_DIR_CHECK='TRUE';
      ALLOW_CONNECT='TRUE';
    'VSS423':
      PIN_NUMBER='(0,0,0,0,0,0,0,0,0,0,0,0,0,0,0,0,0,0,0,0,0,0,0,0,0,0,0,0,0,0,0,0,0,0,0,0,BC72,0,0,0,0,0)';
      PINUSE='POWER';
      NO_LOAD_CHECK='Both';
      NO_IO_CHECK='Both';
      NO_ASSERT_CHECK='TRUE';
      NO_DIR_CHECK='TRUE';
      ALLOW_CONNECT='TRUE';
    'VSS422':
      PIN_NUMBER='(0,0,0,0,0,0,0,0,0,0,0,0,0,0,0,0,0,0,0,0,0,0,0,0,0,0,0,0,0,0,0,0,0,0,0,0,BC66,0,0,0,0,0)';
      PINUSE='POWER';
      NO_LOAD_CHECK='Both';
      NO_IO_CHECK='Both';
      NO_ASSERT_CHECK='TRUE';
      NO_DIR_CHECK='TRUE';
      ALLOW_CONNECT='TRUE';
    'VSS421':
      PIN_NUMBER='(0,0,0,0,0,0,0,0,0,0,0,0,0,0,0,0,0,0,0,0,0,0,0,0,0,0,0,0,0,0,0,0,0,0,0,0,BC62,0,0,0,0,0)';
      PINUSE='POWER';
      NO_LOAD_CHECK='Both';
      NO_IO_CHECK='Both';
      NO_ASSERT_CHECK='TRUE';
      NO_DIR_CHECK='TRUE';
      ALLOW_CONNECT='TRUE';
    'VSS420':
      PIN_NUMBER='(0,0,0,0,0,0,0,0,0,0,0,0,0,0,0,0,0,0,0,0,0,0,0,0,0,0,0,0,0,0,0,0,0,0,0,0,BC5,0,0,0,0,0)';
      PINUSE='POWER';
      NO_LOAD_CHECK='Both';
      NO_IO_CHECK='Both';
      NO_ASSERT_CHECK='TRUE';
      NO_DIR_CHECK='TRUE';
      ALLOW_CONNECT='TRUE';
    'VSS419':
      PIN_NUMBER='(0,0,0,0,0,0,0,0,0,0,0,0,0,0,0,0,0,0,0,0,0,0,0,0,0,0,0,0,0,0,0,0,0,0,0,0,BC17,0,0,0,0,0)';
      PINUSE='POWER';
      NO_LOAD_CHECK='Both';
      NO_IO_CHECK='Both';
      NO_ASSERT_CHECK='TRUE';
      NO_DIR_CHECK='TRUE';
      ALLOW_CONNECT='TRUE';
    'VSS418':
      PIN_NUMBER='(0,0,0,0,0,0,0,0,0,0,0,0,0,0,0,0,0,0,0,0,0,0,0,0,0,0,0,0,0,0,0,0,0,0,0,0,BC13,0,0,0,0,0)';
      PINUSE='POWER';
      NO_LOAD_CHECK='Both';
      NO_IO_CHECK='Both';
      NO_ASSERT_CHECK='TRUE';
      NO_DIR_CHECK='TRUE';
      ALLOW_CONNECT='TRUE';
    'VSS417':
      PIN_NUMBER='(0,0,0,0,0,0,0,0,0,0,0,0,0,0,0,0,0,0,0,0,0,0,0,0,0,0,0,0,0,0,0,0,0,0,0,0,BC1,0,0,0,0,0)';
      PINUSE='POWER';
      NO_LOAD_CHECK='Both';
      NO_IO_CHECK='Both';
      NO_ASSERT_CHECK='TRUE';
      NO_DIR_CHECK='TRUE';
      ALLOW_CONNECT='TRUE';
    'VSS416':
      PIN_NUMBER='(0,0,0,0,0,0,0,0,0,0,0,0,0,0,0,0,0,0,0,0,0,0,0,0,0,0,0,0,0,0,0,0,0,0,0,0,BB91,0,0,0,0,0)';
      PINUSE='POWER';
      NO_LOAD_CHECK='Both';
      NO_IO_CHECK='Both';
      NO_ASSERT_CHECK='TRUE';
      NO_DIR_CHECK='TRUE';
      ALLOW_CONNECT='TRUE';
    'VSS415':
      PIN_NUMBER='(0,0,0,0,0,0,0,0,0,0,0,0,0,0,0,0,0,0,0,0,0,0,0,0,0,0,0,0,0,0,0,0,0,0,0,0,BB87,0,0,0,0,0)';
      PINUSE='POWER';
      NO_LOAD_CHECK='Both';
      NO_IO_CHECK='Both';
      NO_ASSERT_CHECK='TRUE';
      NO_DIR_CHECK='TRUE';
      ALLOW_CONNECT='TRUE';
    'VSS414':
      PIN_NUMBER='(0,0,0,0,0,0,0,0,0,0,0,0,0,0,0,0,0,0,0,0,0,0,0,0,0,0,0,0,0,0,0,0,0,0,0,0,BB83,0,0,0,0,0)';
      PINUSE='POWER';
      NO_LOAD_CHECK='Both';
      NO_IO_CHECK='Both';
      NO_ASSERT_CHECK='TRUE';
      NO_DIR_CHECK='TRUE';
      ALLOW_CONNECT='TRUE';
    'VSS413':
      PIN_NUMBER='(0,0,0,0,0,0,0,0,0,0,0,0,0,0,0,0,0,0,0,0,0,0,0,0,0,0,0,0,0,0,0,0,0,0,0,0,BB8,0,0,0,0,0)';
      PINUSE='POWER';
      NO_LOAD_CHECK='Both';
      NO_IO_CHECK='Both';
      NO_ASSERT_CHECK='TRUE';
      NO_DIR_CHECK='TRUE';
      ALLOW_CONNECT='TRUE';
    'VSS412':
      PIN_NUMBER='(0,0,0,0,0,0,0,0,0,0,0,0,0,0,0,0,0,0,0,0,0,0,0,0,0,0,0,0,0,0,0,0,0,0,0,0,BB79,0,0,0,0,0)';
      PINUSE='POWER';
      NO_LOAD_CHECK='Both';
      NO_IO_CHECK='Both';
      NO_ASSERT_CHECK='TRUE';
      NO_DIR_CHECK='TRUE';
      ALLOW_CONNECT='TRUE';
    'VSS411':
      PIN_NUMBER='(0,0,0,0,0,0,0,0,0,0,0,0,0,0,0,0,0,0,0,0,0,0,0,0,0,0,0,0,0,0,0,0,0,0,0,0,BB77,0,0,0,0,0)';
      PINUSE='POWER';
      NO_LOAD_CHECK='Both';
      NO_IO_CHECK='Both';
      NO_ASSERT_CHECK='TRUE';
      NO_DIR_CHECK='TRUE';
      ALLOW_CONNECT='TRUE';
    'VSS410':
      PIN_NUMBER='(0,0,0,0,0,0,0,0,0,0,0,0,0,0,0,0,0,0,0,0,0,0,0,0,0,0,0,0,0,0,0,0,0,0,0,0,BB71,0,0,0,0,0)';
      PINUSE='POWER';
      NO_LOAD_CHECK='Both';
      NO_IO_CHECK='Both';
      NO_ASSERT_CHECK='TRUE';
      NO_DIR_CHECK='TRUE';
      ALLOW_CONNECT='TRUE';
    'VSS409':
      PIN_NUMBER='(0,0,0,0,0,0,0,0,0,0,0,0,0,0,0,0,0,0,0,0,0,0,0,0,0,0,0,0,0,0,0,0,0,0,0,0,BB69,0,0,0,0,0)';
      PINUSE='POWER';
      NO_LOAD_CHECK='Both';
      NO_IO_CHECK='Both';
      NO_ASSERT_CHECK='TRUE';
      NO_DIR_CHECK='TRUE';
      ALLOW_CONNECT='TRUE';
    'VSS408':
      PIN_NUMBER='(0,0,0,0,0,0,0,0,0,0,0,0,0,0,0,0,0,0,0,0,0,0,0,0,0,0,0,0,0,0,0,0,0,0,0,0,BB63,0,0,0,0,0)';
      PINUSE='POWER';
      NO_LOAD_CHECK='Both';
      NO_IO_CHECK='Both';
      NO_ASSERT_CHECK='TRUE';
      NO_DIR_CHECK='TRUE';
      ALLOW_CONNECT='TRUE';
    'VSS407':
      PIN_NUMBER='(0,0,0,0,0,0,0,0,0,0,0,0,0,0,0,0,0,0,0,0,0,0,0,0,0,0,0,0,0,0,0,0,0,0,0,0,BB4,0,0,0,0,0)';
      PINUSE='POWER';
      NO_LOAD_CHECK='Both';
      NO_IO_CHECK='Both';
      NO_ASSERT_CHECK='TRUE';
      NO_DIR_CHECK='TRUE';
      ALLOW_CONNECT='TRUE';
    'VSS406':
      PIN_NUMBER='(0,0,0,0,0,0,0,0,0,0,0,0,0,0,0,0,0,0,0,0,0,0,0,0,0,0,0,0,0,0,0,0,0,0,0,0,BB26,0,0,0,0,0)';
      PINUSE='POWER';
      NO_LOAD_CHECK='Both';
      NO_IO_CHECK='Both';
      NO_ASSERT_CHECK='TRUE';
      NO_DIR_CHECK='TRUE';
      ALLOW_CONNECT='TRUE';
    'VSS405':
      PIN_NUMBER='(0,0,0,0,0,0,0,0,0,0,0,0,0,0,0,0,0,0,0,0,0,0,0,0,0,0,0,0,0,0,0,0,0,0,0,0,BB24,0,0,0,0,0)';
      PINUSE='POWER';
      NO_LOAD_CHECK='Both';
      NO_IO_CHECK='Both';
      NO_ASSERT_CHECK='TRUE';
      NO_DIR_CHECK='TRUE';
      ALLOW_CONNECT='TRUE';
    'VSS404':
      PIN_NUMBER='(0,0,0,0,0,0,0,0,0,0,0,0,0,0,0,0,0,0,0,0,0,0,0,0,0,0,0,0,0,0,0,0,0,0,0,0,BB22,0,0,0,0,0)';
      PINUSE='POWER';
      NO_LOAD_CHECK='Both';
      NO_IO_CHECK='Both';
      NO_ASSERT_CHECK='TRUE';
      NO_DIR_CHECK='TRUE';
      ALLOW_CONNECT='TRUE';
    'VSS403':
      PIN_NUMBER='(0,0,0,0,0,0,0,0,0,0,0,0,0,0,0,0,0,0,0,0,0,0,0,0,0,0,0,0,0,0,0,0,0,0,0,0,BB20,0,0,0,0,0)';
      PINUSE='POWER';
      NO_LOAD_CHECK='Both';
      NO_IO_CHECK='Both';
      NO_ASSERT_CHECK='TRUE';
      NO_DIR_CHECK='TRUE';
      ALLOW_CONNECT='TRUE';
    'VSS402':
      PIN_NUMBER='(0,0,0,0,0,0,0,0,0,0,0,0,0,0,0,0,0,0,0,0,0,0,0,0,0,0,0,0,0,0,0,0,0,0,0,0,BB16,0,0,0,0,0)';
      PINUSE='POWER';
      NO_LOAD_CHECK='Both';
      NO_IO_CHECK='Both';
      NO_ASSERT_CHECK='TRUE';
      NO_DIR_CHECK='TRUE';
      ALLOW_CONNECT='TRUE';
    'VSS401':
      PIN_NUMBER='(0,0,0,0,0,0,0,0,0,0,0,0,0,0,0,0,0,0,0,0,0,0,0,0,0,0,0,0,0,0,0,0,0,0,0,0,BB12,0,0,0,0,0)';
      PINUSE='POWER';
      NO_LOAD_CHECK='Both';
      NO_IO_CHECK='Both';
      NO_ASSERT_CHECK='TRUE';
      NO_DIR_CHECK='TRUE';
      ALLOW_CONNECT='TRUE';
    'VSS400':
      PIN_NUMBER='(0,0,0,0,0,0,0,0,0,0,0,0,0,0,0,0,0,0,0,0,0,0,0,0,0,0,0,0,0,0,0,0,0,0,0,0,BB10,0,0,0,0,0)';
      PINUSE='POWER';
      NO_LOAD_CHECK='Both';
      NO_IO_CHECK='Both';
      NO_ASSERT_CHECK='TRUE';
      NO_DIR_CHECK='TRUE';
      ALLOW_CONNECT='TRUE';
    'VSS399':
      PIN_NUMBER='(0,0,0,0,0,0,0,0,0,0,0,0,0,0,0,0,0,0,0,0,0,0,0,0,0,0,0,0,0,0,0,0,0,0,0,0,BA88,0,0,0,0,0)';
      PINUSE='POWER';
      NO_LOAD_CHECK='Both';
      NO_IO_CHECK='Both';
      NO_ASSERT_CHECK='TRUE';
      NO_DIR_CHECK='TRUE';
      ALLOW_CONNECT='TRUE';
    'VSS398':
      PIN_NUMBER='(0,0,0,0,0,0,0,0,0,0,0,0,0,0,0,0,0,0,0,0,0,0,0,0,0,0,0,0,0,0,0,0,0,0,0,0,BA84,0,0,0,0,0)';
      PINUSE='POWER';
      NO_LOAD_CHECK='Both';
      NO_IO_CHECK='Both';
      NO_ASSERT_CHECK='TRUE';
      NO_DIR_CHECK='TRUE';
      ALLOW_CONNECT='TRUE';
    'VSS397':
      PIN_NUMBER='(0,0,0,0,0,0,0,0,0,0,0,0,0,0,0,0,0,0,0,0,0,0,0,0,0,0,0,0,0,0,0,0,0,0,0,0,BA74,0,0,0,0,0)';
      PINUSE='POWER';
      NO_LOAD_CHECK='Both';
      NO_IO_CHECK='Both';
      NO_ASSERT_CHECK='TRUE';
      NO_DIR_CHECK='TRUE';
      ALLOW_CONNECT='TRUE';
    'VSS395':
      PIN_NUMBER='(0,0,0,0,0,0,0,0,0,0,0,0,0,0,0,0,0,0,0,0,0,0,0,0,0,0,0,0,0,0,0,0,0,0,0,0,BA64,0,0,0,0,0)';
      PINUSE='POWER';
      NO_LOAD_CHECK='Both';
      NO_IO_CHECK='Both';
      NO_ASSERT_CHECK='TRUE';
      NO_DIR_CHECK='TRUE';
      ALLOW_CONNECT='TRUE';
    'VSS394':
      PIN_NUMBER='(0,0,0,0,0,0,0,0,0,0,0,0,0,0,0,0,0,0,0,0,0,0,0,0,0,0,0,0,0,0,0,0,0,0,0,0,BA60,0,0,0,0,0)';
      PINUSE='POWER';
      NO_LOAD_CHECK='Both';
      NO_IO_CHECK='Both';
      NO_ASSERT_CHECK='TRUE';
      NO_DIR_CHECK='TRUE';
      ALLOW_CONNECT='TRUE';
    'VSS393':
      PIN_NUMBER='(0,0,0,0,0,0,0,0,0,0,0,0,0,0,0,0,0,0,0,0,0,0,0,0,0,0,0,0,0,0,0,0,0,0,0,0,BA17,0,0,0,0,0)';
      PINUSE='POWER';
      NO_LOAD_CHECK='Both';
      NO_IO_CHECK='Both';
      NO_ASSERT_CHECK='TRUE';
      NO_DIR_CHECK='TRUE';
      ALLOW_CONNECT='TRUE';
    'VSS377':
      PIN_NUMBER='(0,0,0,0,0,0,0,0,0,0,0,0,0,0,0,0,0,0,0,0,0,0,0,0,0,0,0,0,0,0,0,0,0,0,0,0,AY83,0,0,0,0,0)';
      PINUSE='POWER';
      NO_LOAD_CHECK='Both';
      NO_IO_CHECK='Both';
      NO_ASSERT_CHECK='TRUE';
      NO_DIR_CHECK='TRUE';
      ALLOW_CONNECT='TRUE';
    'VSS376':
      PIN_NUMBER='(0,0,0,0,0,0,0,0,0,0,0,0,0,0,0,0,0,0,0,0,0,0,0,0,0,0,0,0,0,0,0,0,0,0,0,0,AY81,0,0,0,0,0)';
      PINUSE='POWER';
      NO_LOAD_CHECK='Both';
      NO_IO_CHECK='Both';
      NO_ASSERT_CHECK='TRUE';
      NO_DIR_CHECK='TRUE';
      ALLOW_CONNECT='TRUE';
    'VSS375':
      PIN_NUMBER='(0,0,0,0,0,0,0,0,0,0,0,0,0,0,0,0,0,0,0,0,0,0,0,0,0,0,0,0,0,0,0,0,0,0,0,0,AY8,0,0,0,0,0)';
      PINUSE='POWER';
      NO_LOAD_CHECK='Both';
      NO_IO_CHECK='Both';
      NO_ASSERT_CHECK='TRUE';
      NO_DIR_CHECK='TRUE';
      ALLOW_CONNECT='TRUE';
    'VSS374':
      PIN_NUMBER='(0,0,0,0,0,0,0,0,0,0,0,0,0,0,0,0,0,0,0,0,0,0,0,0,0,0,0,0,0,0,0,0,0,0,0,0,AY79,0,0,0,0,0)';
      PINUSE='POWER';
      NO_LOAD_CHECK='Both';
      NO_IO_CHECK='Both';
      NO_ASSERT_CHECK='TRUE';
      NO_DIR_CHECK='TRUE';
      ALLOW_CONNECT='TRUE';
    'VSS373':
      PIN_NUMBER='(0,0,0,0,0,0,0,0,0,0,0,0,0,0,0,0,0,0,0,0,0,0,0,0,0,0,0,0,0,0,0,0,0,0,0,0,AY77,0,0,0,0,0)';
      PINUSE='POWER';
      NO_LOAD_CHECK='Both';
      NO_IO_CHECK='Both';
      NO_ASSERT_CHECK='TRUE';
      NO_DIR_CHECK='TRUE';
      ALLOW_CONNECT='TRUE';
    'VSS372':
      PIN_NUMBER='(0,0,0,0,0,0,0,0,0,0,0,0,0,0,0,0,0,0,0,0,0,0,0,0,0,0,0,0,0,0,0,0,0,0,0,0,AY71,0,0,0,0,0)';
      PINUSE='POWER';
      NO_LOAD_CHECK='Both';
      NO_IO_CHECK='Both';
      NO_ASSERT_CHECK='TRUE';
      NO_DIR_CHECK='TRUE';
      ALLOW_CONNECT='TRUE';
    'VSS371':
      PIN_NUMBER='(0,0,0,0,0,0,0,0,0,0,0,0,0,0,0,0,0,0,0,0,0,0,0,0,0,0,0,0,0,0,0,0,0,0,0,0,AY4,0,0,0,0,0)';
      PINUSE='POWER';
      NO_LOAD_CHECK='Both';
      NO_IO_CHECK='Both';
      NO_ASSERT_CHECK='TRUE';
      NO_DIR_CHECK='TRUE';
      ALLOW_CONNECT='TRUE';
    'VSS370':
      PIN_NUMBER='(0,0,0,0,0,0,0,0,0,0,0,0,0,0,0,0,0,0,0,0,0,0,0,0,0,0,0,0,0,0,0,0,0,0,0,0,AY16,0,0,0,0,0)';
      PINUSE='POWER';
      NO_LOAD_CHECK='Both';
      NO_IO_CHECK='Both';
      NO_ASSERT_CHECK='TRUE';
      NO_DIR_CHECK='TRUE';
      ALLOW_CONNECT='TRUE';
    'VSS369':
      PIN_NUMBER='(0,0,0,0,0,0,0,0,0,0,0,0,0,0,0,0,0,0,0,0,0,0,0,0,0,0,0,0,0,0,0,0,0,0,0,0,AY12,0,0,0,0,0)';
      PINUSE='POWER';
      NO_LOAD_CHECK='Both';
      NO_IO_CHECK='Both';
      NO_ASSERT_CHECK='TRUE';
      NO_DIR_CHECK='TRUE';
      ALLOW_CONNECT='TRUE';
    'VSS367':
      PIN_NUMBER='(0,0,0,0,0,0,0,0,0,0,0,0,0,0,0,0,0,0,0,0,0,0,0,0,0,0,0,0,0,0,0,0,0,0,0,0,AW88,0,0,0,0,0)';
      PINUSE='POWER';
      NO_LOAD_CHECK='Both';
      NO_IO_CHECK='Both';
      NO_ASSERT_CHECK='TRUE';
      NO_DIR_CHECK='TRUE';
      ALLOW_CONNECT='TRUE';
    'VSS366':
      PIN_NUMBER='(0,0,0,0,0,0,0,0,0,0,0,0,0,0,0,0,0,0,0,0,0,0,0,0,0,0,0,0,0,0,0,0,0,0,0,0,AW84,0,0,0,0,0)';
      PINUSE='POWER';
      NO_LOAD_CHECK='Both';
      NO_IO_CHECK='Both';
      NO_ASSERT_CHECK='TRUE';
      NO_DIR_CHECK='TRUE';
      ALLOW_CONNECT='TRUE';
    'VSS365':
      PIN_NUMBER='(0,0,0,0,0,0,0,0,0,0,0,0,0,0,0,0,0,0,0,0,0,0,0,0,0,0,0,0,0,0,0,0,0,0,0,0,AW82,0,0,0,0,0)';
      PINUSE='POWER';
      NO_LOAD_CHECK='Both';
      NO_IO_CHECK='Both';
      NO_ASSERT_CHECK='TRUE';
      NO_DIR_CHECK='TRUE';
      ALLOW_CONNECT='TRUE';
    'VSS364':
      PIN_NUMBER='(0,0,0,0,0,0,0,0,0,0,0,0,0,0,0,0,0,0,0,0,0,0,0,0,0,0,0,0,0,0,0,0,0,0,0,0,AW80,0,0,0,0,0)';
      PINUSE='POWER';
      NO_LOAD_CHECK='Both';
      NO_IO_CHECK='Both';
      NO_ASSERT_CHECK='TRUE';
      NO_DIR_CHECK='TRUE';
      ALLOW_CONNECT='TRUE';
    'VSS363':
      PIN_NUMBER='(0,0,0,0,0,0,0,0,0,0,0,0,0,0,0,0,0,0,0,0,0,0,0,0,0,0,0,0,0,0,0,0,0,0,0,0,AW72,0,0,0,0,0)';
      PINUSE='POWER';
      NO_LOAD_CHECK='Both';
      NO_IO_CHECK='Both';
      NO_ASSERT_CHECK='TRUE';
      NO_DIR_CHECK='TRUE';
      ALLOW_CONNECT='TRUE';
    'VSS362':
      PIN_NUMBER='(0,0,0,0,0,0,0,0,0,0,0,0,0,0,0,0,0,0,0,0,0,0,0,0,0,0,0,0,0,0,0,0,0,0,0,0,AW68,0,0,0,0,0)';
      PINUSE='POWER';
      NO_LOAD_CHECK='Both';
      NO_IO_CHECK='Both';
      NO_ASSERT_CHECK='TRUE';
      NO_DIR_CHECK='TRUE';
      ALLOW_CONNECT='TRUE';
    'VSS361':
      PIN_NUMBER='(0,0,0,0,0,0,0,0,0,0,0,0,0,0,0,0,0,0,0,0,0,0,0,0,0,0,0,0,0,0,0,0,0,0,0,0,AW66,0,0,0,0,0)';
      PINUSE='POWER';
      NO_LOAD_CHECK='Both';
      NO_IO_CHECK='Both';
      NO_ASSERT_CHECK='TRUE';
      NO_DIR_CHECK='TRUE';
      ALLOW_CONNECT='TRUE';
    'VSS360':
      PIN_NUMBER='(0,0,0,0,0,0,0,0,0,0,0,0,0,0,0,0,0,0,0,0,0,0,0,0,0,0,0,0,0,0,0,0,0,0,0,0,AW62,0,0,0,0,0)';
      PINUSE='POWER';
      NO_LOAD_CHECK='Both';
      NO_IO_CHECK='Both';
      NO_ASSERT_CHECK='TRUE';
      NO_DIR_CHECK='TRUE';
      ALLOW_CONNECT='TRUE';
    'VSS358':
      PIN_NUMBER='(0,0,0,0,0,0,0,0,0,0,0,0,0,0,0,0,0,0,0,0,0,0,0,0,0,0,0,0,0,0,0,0,0,0,0,0,AW25,0,0,0,0,0)';
      PINUSE='POWER';
      NO_LOAD_CHECK='Both';
      NO_IO_CHECK='Both';
      NO_ASSERT_CHECK='TRUE';
      NO_DIR_CHECK='TRUE';
      ALLOW_CONNECT='TRUE';
    'VSS357':
      PIN_NUMBER='(0,0,0,0,0,0,0,0,0,0,0,0,0,0,0,0,0,0,0,0,0,0,0,0,0,0,0,0,0,0,0,0,0,0,0,0,AW23,0,0,0,0,0)';
      PINUSE='POWER';
      NO_LOAD_CHECK='Both';
      NO_IO_CHECK='Both';
      NO_ASSERT_CHECK='TRUE';
      NO_DIR_CHECK='TRUE';
      ALLOW_CONNECT='TRUE';
    'VSS356':
      PIN_NUMBER='(0,0,0,0,0,0,0,0,0,0,0,0,0,0,0,0,0,0,0,0,0,0,0,0,0,0,0,0,0,0,0,0,0,0,0,0,AW21,0,0,0,0,0)';
      PINUSE='POWER';
      NO_LOAD_CHECK='Both';
      NO_IO_CHECK='Both';
      NO_ASSERT_CHECK='TRUE';
      NO_DIR_CHECK='TRUE';
      ALLOW_CONNECT='TRUE';
    'VSS0':
      PIN_NUMBER='(0,0,0,0,0,0,0,0,0,0,0,0,0,0,0,0,0,0,0,0,0,0,0,0,0,0,0,0,0,0,0,0,0,0,0,0,BR5,0,0,0,0,0)';
      PINUSE='POWER';
      NO_LOAD_CHECK='Both';
      NO_IO_CHECK='Both';
      NO_ASSERT_CHECK='TRUE';
      NO_DIR_CHECK='TRUE';
      ALLOW_CONNECT='TRUE';
    'VSS368':
      PIN_NUMBER='(0,0,0,0,0,0,0,0,0,0,0,0,0,0,0,0,0,0,0,0,0,0,0,0,0,0,0,0,0,0,0,0,0,0,0,0,0,AW9,0,0,0,0)';
      PINUSE='POWER';
      NO_LOAD_CHECK='Both';
      NO_IO_CHECK='Both';
      NO_ASSERT_CHECK='TRUE';
      NO_DIR_CHECK='TRUE';
      ALLOW_CONNECT='TRUE';
    'VSS359':
      PIN_NUMBER='(0,0,0,0,0,0,0,0,0,0,0,0,0,0,0,0,0,0,0,0,0,0,0,0,0,0,0,0,0,0,0,0,0,0,0,0,0,AW5,0,0,0,0)';
      PINUSE='POWER';
      NO_LOAD_CHECK='Both';
      NO_IO_CHECK='Both';
      NO_ASSERT_CHECK='TRUE';
      NO_DIR_CHECK='TRUE';
      ALLOW_CONNECT='TRUE';
    'VSS355':
      PIN_NUMBER='(0,0,0,0,0,0,0,0,0,0,0,0,0,0,0,0,0,0,0,0,0,0,0,0,0,0,0,0,0,0,0,0,0,0,0,0,0,AW13,0,0,0,0)';
      PINUSE='POWER';
      NO_LOAD_CHECK='Both';
      NO_IO_CHECK='Both';
      NO_ASSERT_CHECK='TRUE';
      NO_DIR_CHECK='TRUE';
      ALLOW_CONNECT='TRUE';
    'VSS354':
      PIN_NUMBER='(0,0,0,0,0,0,0,0,0,0,0,0,0,0,0,0,0,0,0,0,0,0,0,0,0,0,0,0,0,0,0,0,0,0,0,0,0,AW1,0,0,0,0)';
      PINUSE='POWER';
      NO_LOAD_CHECK='Both';
      NO_IO_CHECK='Both';
      NO_ASSERT_CHECK='TRUE';
      NO_DIR_CHECK='TRUE';
      ALLOW_CONNECT='TRUE';
    'VSS353':
      PIN_NUMBER='(0,0,0,0,0,0,0,0,0,0,0,0,0,0,0,0,0,0,0,0,0,0,0,0,0,0,0,0,0,0,0,0,0,0,0,0,0,AV91,0,0,0,0)';
      PINUSE='POWER';
      NO_LOAD_CHECK='Both';
      NO_IO_CHECK='Both';
      NO_ASSERT_CHECK='TRUE';
      NO_DIR_CHECK='TRUE';
      ALLOW_CONNECT='TRUE';
    'VSS352':
      PIN_NUMBER='(0,0,0,0,0,0,0,0,0,0,0,0,0,0,0,0,0,0,0,0,0,0,0,0,0,0,0,0,0,0,0,0,0,0,0,0,0,AV87,0,0,0,0)';
      PINUSE='POWER';
      NO_LOAD_CHECK='Both';
      NO_IO_CHECK='Both';
      NO_ASSERT_CHECK='TRUE';
      NO_DIR_CHECK='TRUE';
      ALLOW_CONNECT='TRUE';
    'VSS351':
      PIN_NUMBER='(0,0,0,0,0,0,0,0,0,0,0,0,0,0,0,0,0,0,0,0,0,0,0,0,0,0,0,0,0,0,0,0,0,0,0,0,0,AV8,0,0,0,0)';
      PINUSE='POWER';
      NO_LOAD_CHECK='Both';
      NO_IO_CHECK='Both';
      NO_ASSERT_CHECK='TRUE';
      NO_DIR_CHECK='TRUE';
      ALLOW_CONNECT='TRUE';
    'VSS350':
      PIN_NUMBER='(0,0,0,0,0,0,0,0,0,0,0,0,0,0,0,0,0,0,0,0,0,0,0,0,0,0,0,0,0,0,0,0,0,0,0,0,0,AV77,0,0,0,0)';
      PINUSE='POWER';
      NO_LOAD_CHECK='Both';
      NO_IO_CHECK='Both';
      NO_ASSERT_CHECK='TRUE';
      NO_DIR_CHECK='TRUE';
      ALLOW_CONNECT='TRUE';
    'VSS349':
      PIN_NUMBER='(0,0,0,0,0,0,0,0,0,0,0,0,0,0,0,0,0,0,0,0,0,0,0,0,0,0,0,0,0,0,0,0,0,0,0,0,0,AV4,0,0,0,0)';
      PINUSE='POWER';
      NO_LOAD_CHECK='Both';
      NO_IO_CHECK='Both';
      NO_ASSERT_CHECK='TRUE';
      NO_DIR_CHECK='TRUE';
      ALLOW_CONNECT='TRUE';
    'VSS348':
      PIN_NUMBER='(0,0,0,0,0,0,0,0,0,0,0,0,0,0,0,0,0,0,0,0,0,0,0,0,0,0,0,0,0,0,0,0,0,0,0,0,0,AV16,0,0,0,0)';
      PINUSE='POWER';
      NO_LOAD_CHECK='Both';
      NO_IO_CHECK='Both';
      NO_ASSERT_CHECK='TRUE';
      NO_DIR_CHECK='TRUE';
      ALLOW_CONNECT='TRUE';
    'VSS347':
      PIN_NUMBER='(0,0,0,0,0,0,0,0,0,0,0,0,0,0,0,0,0,0,0,0,0,0,0,0,0,0,0,0,0,0,0,0,0,0,0,0,0,AV12,0,0,0,0)';
      PINUSE='POWER';
      NO_LOAD_CHECK='Both';
      NO_IO_CHECK='Both';
      NO_ASSERT_CHECK='TRUE';
      NO_DIR_CHECK='TRUE';
      ALLOW_CONNECT='TRUE';
    'VSS346':
      PIN_NUMBER='(0,0,0,0,0,0,0,0,0,0,0,0,0,0,0,0,0,0,0,0,0,0,0,0,0,0,0,0,0,0,0,0,0,0,0,0,0,AU88,0,0,0,0)';
      PINUSE='POWER';
      NO_LOAD_CHECK='Both';
      NO_IO_CHECK='Both';
      NO_ASSERT_CHECK='TRUE';
      NO_DIR_CHECK='TRUE';
      ALLOW_CONNECT='TRUE';
    'VSS345':
      PIN_NUMBER='(0,0,0,0,0,0,0,0,0,0,0,0,0,0,0,0,0,0,0,0,0,0,0,0,0,0,0,0,0,0,0,0,0,0,0,0,0,AU84,0,0,0,0)';
      PINUSE='POWER';
      NO_LOAD_CHECK='Both';
      NO_IO_CHECK='Both';
      NO_ASSERT_CHECK='TRUE';
      NO_DIR_CHECK='TRUE';
      ALLOW_CONNECT='TRUE';
    'VSS344':
      PIN_NUMBER='(0,0,0,0,0,0,0,0,0,0,0,0,0,0,0,0,0,0,0,0,0,0,0,0,0,0,0,0,0,0,0,0,0,0,0,0,0,AU80,0,0,0,0)';
      PINUSE='POWER';
      NO_LOAD_CHECK='Both';
      NO_IO_CHECK='Both';
      NO_ASSERT_CHECK='TRUE';
      NO_DIR_CHECK='TRUE';
      ALLOW_CONNECT='TRUE';
    'VSS343':
      PIN_NUMBER='(0,0,0,0,0,0,0,0,0,0,0,0,0,0,0,0,0,0,0,0,0,0,0,0,0,0,0,0,0,0,0,0,0,0,0,0,0,AU76,0,0,0,0)';
      PINUSE='POWER';
      NO_LOAD_CHECK='Both';
      NO_IO_CHECK='Both';
      NO_ASSERT_CHECK='TRUE';
      NO_DIR_CHECK='TRUE';
      ALLOW_CONNECT='TRUE';
    'VSS342':
      PIN_NUMBER='(0,0,0,0,0,0,0,0,0,0,0,0,0,0,0,0,0,0,0,0,0,0,0,0,0,0,0,0,0,0,0,0,0,0,0,0,0,AU74,0,0,0,0)';
      PINUSE='POWER';
      NO_LOAD_CHECK='Both';
      NO_IO_CHECK='Both';
      NO_ASSERT_CHECK='TRUE';
      NO_DIR_CHECK='TRUE';
      ALLOW_CONNECT='TRUE';
    'VSS341':
      PIN_NUMBER='(0,0,0,0,0,0,0,0,0,0,0,0,0,0,0,0,0,0,0,0,0,0,0,0,0,0,0,0,0,0,0,0,0,0,0,0,0,AU72,0,0,0,0)';
      PINUSE='POWER';
      NO_LOAD_CHECK='Both';
      NO_IO_CHECK='Both';
      NO_ASSERT_CHECK='TRUE';
      NO_DIR_CHECK='TRUE';
      ALLOW_CONNECT='TRUE';
    'VSS340':
      PIN_NUMBER='(0,0,0,0,0,0,0,0,0,0,0,0,0,0,0,0,0,0,0,0,0,0,0,0,0,0,0,0,0,0,0,0,0,0,0,0,0,AU70,0,0,0,0)';
      PINUSE='POWER';
      NO_LOAD_CHECK='Both';
      NO_IO_CHECK='Both';
      NO_ASSERT_CHECK='TRUE';
      NO_DIR_CHECK='TRUE';
      ALLOW_CONNECT='TRUE';
    'VSS339':
      PIN_NUMBER='(0,0,0,0,0,0,0,0,0,0,0,0,0,0,0,0,0,0,0,0,0,0,0,0,0,0,0,0,0,0,0,0,0,0,0,0,0,AU48,0,0,0,0)';
      PINUSE='POWER';
      NO_LOAD_CHECK='Both';
      NO_IO_CHECK='Both';
      NO_ASSERT_CHECK='TRUE';
      NO_DIR_CHECK='TRUE';
      ALLOW_CONNECT='TRUE';
    'VSS338':
      PIN_NUMBER='(0,0,0,0,0,0,0,0,0,0,0,0,0,0,0,0,0,0,0,0,0,0,0,0,0,0,0,0,0,0,0,0,0,0,0,0,0,AU45,0,0,0,0)';
      PINUSE='POWER';
      NO_LOAD_CHECK='Both';
      NO_IO_CHECK='Both';
      NO_ASSERT_CHECK='TRUE';
      NO_DIR_CHECK='TRUE';
      ALLOW_CONNECT='TRUE';
    'VSS337':
      PIN_NUMBER='(0,0,0,0,0,0,0,0,0,0,0,0,0,0,0,0,0,0,0,0,0,0,0,0,0,0,0,0,0,0,0,0,0,0,0,0,0,AU41,0,0,0,0)';
      PINUSE='POWER';
      NO_LOAD_CHECK='Both';
      NO_IO_CHECK='Both';
      NO_ASSERT_CHECK='TRUE';
      NO_DIR_CHECK='TRUE';
      ALLOW_CONNECT='TRUE';
    'VSS336':
      PIN_NUMBER='(0,0,0,0,0,0,0,0,0,0,0,0,0,0,0,0,0,0,0,0,0,0,0,0,0,0,0,0,0,0,0,0,0,0,0,0,0,AU39,0,0,0,0)';
      PINUSE='POWER';
      NO_LOAD_CHECK='Both';
      NO_IO_CHECK='Both';
      NO_ASSERT_CHECK='TRUE';
      NO_DIR_CHECK='TRUE';
      ALLOW_CONNECT='TRUE';
    'VSS335':
      PIN_NUMBER='(0,0,0,0,0,0,0,0,0,0,0,0,0,0,0,0,0,0,0,0,0,0,0,0,0,0,0,0,0,0,0,0,0,0,0,0,0,AU37,0,0,0,0)';
      PINUSE='POWER';
      NO_LOAD_CHECK='Both';
      NO_IO_CHECK='Both';
      NO_ASSERT_CHECK='TRUE';
      NO_DIR_CHECK='TRUE';
      ALLOW_CONNECT='TRUE';
    'VSS334':
      PIN_NUMBER='(0,0,0,0,0,0,0,0,0,0,0,0,0,0,0,0,0,0,0,0,0,0,0,0,0,0,0,0,0,0,0,0,0,0,0,0,0,AU31,0,0,0,0)';
      PINUSE='POWER';
      NO_LOAD_CHECK='Both';
      NO_IO_CHECK='Both';
      NO_ASSERT_CHECK='TRUE';
      NO_DIR_CHECK='TRUE';
      ALLOW_CONNECT='TRUE';
    'VSS333':
      PIN_NUMBER='(0,0,0,0,0,0,0,0,0,0,0,0,0,0,0,0,0,0,0,0,0,0,0,0,0,0,0,0,0,0,0,0,0,0,0,0,0,AU27,0,0,0,0)';
      PINUSE='POWER';
      NO_LOAD_CHECK='Both';
      NO_IO_CHECK='Both';
      NO_ASSERT_CHECK='TRUE';
      NO_DIR_CHECK='TRUE';
      ALLOW_CONNECT='TRUE';
    'VSS332':
      PIN_NUMBER='(0,0,0,0,0,0,0,0,0,0,0,0,0,0,0,0,0,0,0,0,0,0,0,0,0,0,0,0,0,0,0,0,0,0,0,0,0,AT8,0,0,0,0)';
      PINUSE='POWER';
      NO_LOAD_CHECK='Both';
      NO_IO_CHECK='Both';
      NO_ASSERT_CHECK='TRUE';
      NO_DIR_CHECK='TRUE';
      ALLOW_CONNECT='TRUE';
    'VSS331':
      PIN_NUMBER='(0,0,0,0,0,0,0,0,0,0,0,0,0,0,0,0,0,0,0,0,0,0,0,0,0,0,0,0,0,0,0,0,0,0,0,0,0,AT79,0,0,0,0)';
      PINUSE='POWER';
      NO_LOAD_CHECK='Both';
      NO_IO_CHECK='Both';
      NO_ASSERT_CHECK='TRUE';
      NO_DIR_CHECK='TRUE';
      ALLOW_CONNECT='TRUE';
    'VSS330':
      PIN_NUMBER='(0,0,0,0,0,0,0,0,0,0,0,0,0,0,0,0,0,0,0,0,0,0,0,0,0,0,0,0,0,0,0,0,0,0,0,0,0,AT77,0,0,0,0)';
      PINUSE='POWER';
      NO_LOAD_CHECK='Both';
      NO_IO_CHECK='Both';
      NO_ASSERT_CHECK='TRUE';
      NO_DIR_CHECK='TRUE';
      ALLOW_CONNECT='TRUE';
    'VSS329':
      PIN_NUMBER='(0,0,0,0,0,0,0,0,0,0,0,0,0,0,0,0,0,0,0,0,0,0,0,0,0,0,0,0,0,0,0,0,0,0,0,0,0,AT75,0,0,0,0)';
      PINUSE='POWER';
      NO_LOAD_CHECK='Both';
      NO_IO_CHECK='Both';
      NO_ASSERT_CHECK='TRUE';
      NO_DIR_CHECK='TRUE';
      ALLOW_CONNECT='TRUE';
    'VSS328':
      PIN_NUMBER='(0,0,0,0,0,0,0,0,0,0,0,0,0,0,0,0,0,0,0,0,0,0,0,0,0,0,0,0,0,0,0,0,0,0,0,0,0,AT71,0,0,0,0)';
      PINUSE='POWER';
      NO_LOAD_CHECK='Both';
      NO_IO_CHECK='Both';
      NO_ASSERT_CHECK='TRUE';
      NO_DIR_CHECK='TRUE';
      ALLOW_CONNECT='TRUE';
    'VSS327':
      PIN_NUMBER='(0,0,0,0,0,0,0,0,0,0,0,0,0,0,0,0,0,0,0,0,0,0,0,0,0,0,0,0,0,0,0,0,0,0,0,0,0,AT69,0,0,0,0)';
      PINUSE='POWER';
      NO_LOAD_CHECK='Both';
      NO_IO_CHECK='Both';
      NO_ASSERT_CHECK='TRUE';
      NO_DIR_CHECK='TRUE';
      ALLOW_CONNECT='TRUE';
    'VSS326':
      PIN_NUMBER='(0,0,0,0,0,0,0,0,0,0,0,0,0,0,0,0,0,0,0,0,0,0,0,0,0,0,0,0,0,0,0,0,0,0,0,0,0,AT65,0,0,0,0)';
      PINUSE='POWER';
      NO_LOAD_CHECK='Both';
      NO_IO_CHECK='Both';
      NO_ASSERT_CHECK='TRUE';
      NO_DIR_CHECK='TRUE';
      ALLOW_CONNECT='TRUE';
    'VSS325':
      PIN_NUMBER='(0,0,0,0,0,0,0,0,0,0,0,0,0,0,0,0,0,0,0,0,0,0,0,0,0,0,0,0,0,0,0,0,0,0,0,0,0,AT63,0,0,0,0)';
      PINUSE='POWER';
      NO_LOAD_CHECK='Both';
      NO_IO_CHECK='Both';
      NO_ASSERT_CHECK='TRUE';
      NO_DIR_CHECK='TRUE';
      ALLOW_CONNECT='TRUE';
    'VSS324':
      PIN_NUMBER='(0,0,0,0,0,0,0,0,0,0,0,0,0,0,0,0,0,0,0,0,0,0,0,0,0,0,0,0,0,0,0,0,0,0,0,0,0,AT59,0,0,0,0)';
      PINUSE='POWER';
      NO_LOAD_CHECK='Both';
      NO_IO_CHECK='Both';
      NO_ASSERT_CHECK='TRUE';
      NO_DIR_CHECK='TRUE';
      ALLOW_CONNECT='TRUE';
    'VSS323':
      PIN_NUMBER='(0,0,0,0,0,0,0,0,0,0,0,0,0,0,0,0,0,0,0,0,0,0,0,0,0,0,0,0,0,0,0,0,0,0,0,0,0,AT57,0,0,0,0)';
      PINUSE='POWER';
      NO_LOAD_CHECK='Both';
      NO_IO_CHECK='Both';
      NO_ASSERT_CHECK='TRUE';
      NO_DIR_CHECK='TRUE';
      ALLOW_CONNECT='TRUE';
    'VSS322':
      PIN_NUMBER='(0,0,0,0,0,0,0,0,0,0,0,0,0,0,0,0,0,0,0,0,0,0,0,0,0,0,0,0,0,0,0,0,0,0,0,0,0,AT53,0,0,0,0)';
      PINUSE='POWER';
      NO_LOAD_CHECK='Both';
      NO_IO_CHECK='Both';
      NO_ASSERT_CHECK='TRUE';
      NO_DIR_CHECK='TRUE';
      ALLOW_CONNECT='TRUE';
    'VSS321':
      PIN_NUMBER='(0,0,0,0,0,0,0,0,0,0,0,0,0,0,0,0,0,0,0,0,0,0,0,0,0,0,0,0,0,0,0,0,0,0,0,0,0,AT51,0,0,0,0)';
      PINUSE='POWER';
      NO_LOAD_CHECK='Both';
      NO_IO_CHECK='Both';
      NO_ASSERT_CHECK='TRUE';
      NO_DIR_CHECK='TRUE';
      ALLOW_CONNECT='TRUE';
    'VSS320':
      PIN_NUMBER='(0,0,0,0,0,0,0,0,0,0,0,0,0,0,0,0,0,0,0,0,0,0,0,0,0,0,0,0,0,0,0,0,0,0,0,0,0,AT44,0,0,0,0)';
      PINUSE='POWER';
      NO_LOAD_CHECK='Both';
      NO_IO_CHECK='Both';
      NO_ASSERT_CHECK='TRUE';
      NO_DIR_CHECK='TRUE';
      ALLOW_CONNECT='TRUE';
    'VSS319':
      PIN_NUMBER='(0,0,0,0,0,0,0,0,0,0,0,0,0,0,0,0,0,0,0,0,0,0,0,0,0,0,0,0,0,0,0,0,0,0,0,0,0,AT40,0,0,0,0)';
      PINUSE='POWER';
      NO_LOAD_CHECK='Both';
      NO_IO_CHECK='Both';
      NO_ASSERT_CHECK='TRUE';
      NO_DIR_CHECK='TRUE';
      ALLOW_CONNECT='TRUE';
    'VSS318':
      PIN_NUMBER='(0,0,0,0,0,0,0,0,0,0,0,0,0,0,0,0,0,0,0,0,0,0,0,0,0,0,0,0,0,0,0,0,0,0,0,0,0,AT4,0,0,0,0)';
      PINUSE='POWER';
      NO_LOAD_CHECK='Both';
      NO_IO_CHECK='Both';
      NO_ASSERT_CHECK='TRUE';
      NO_DIR_CHECK='TRUE';
      ALLOW_CONNECT='TRUE';
    'VSS317':
      PIN_NUMBER='(0,0,0,0,0,0,0,0,0,0,0,0,0,0,0,0,0,0,0,0,0,0,0,0,0,0,0,0,0,0,0,0,0,0,0,0,0,AT38,0,0,0,0)';
      PINUSE='POWER';
      NO_LOAD_CHECK='Both';
      NO_IO_CHECK='Both';
      NO_ASSERT_CHECK='TRUE';
      NO_DIR_CHECK='TRUE';
      ALLOW_CONNECT='TRUE';
    'VSS316':
      PIN_NUMBER='(0,0,0,0,0,0,0,0,0,0,0,0,0,0,0,0,0,0,0,0,0,0,0,0,0,0,0,0,0,0,0,0,0,0,0,0,0,AT34,0,0,0,0)';
      PINUSE='POWER';
      NO_LOAD_CHECK='Both';
      NO_IO_CHECK='Both';
      NO_ASSERT_CHECK='TRUE';
      NO_DIR_CHECK='TRUE';
      ALLOW_CONNECT='TRUE';
    'VSS315':
      PIN_NUMBER='(0,0,0,0,0,0,0,0,0,0,0,0,0,0,0,0,0,0,0,0,0,0,0,0,0,0,0,0,0,0,0,0,0,0,0,0,0,AT32,0,0,0,0)';
      PINUSE='POWER';
      NO_LOAD_CHECK='Both';
      NO_IO_CHECK='Both';
      NO_ASSERT_CHECK='TRUE';
      NO_DIR_CHECK='TRUE';
      ALLOW_CONNECT='TRUE';
    'VSS314':
      PIN_NUMBER='(0,0,0,0,0,0,0,0,0,0,0,0,0,0,0,0,0,0,0,0,0,0,0,0,0,0,0,0,0,0,0,0,0,0,0,0,0,AT28,0,0,0,0)';
      PINUSE='POWER';
      NO_LOAD_CHECK='Both';
      NO_IO_CHECK='Both';
      NO_ASSERT_CHECK='TRUE';
      NO_DIR_CHECK='TRUE';
      ALLOW_CONNECT='TRUE';
    'VSS313':
      PIN_NUMBER='(0,0,0,0,0,0,0,0,0,0,0,0,0,0,0,0,0,0,0,0,0,0,0,0,0,0,0,0,0,0,0,0,0,0,0,0,0,AT26,0,0,0,0)';
      PINUSE='POWER';
      NO_LOAD_CHECK='Both';
      NO_IO_CHECK='Both';
      NO_ASSERT_CHECK='TRUE';
      NO_DIR_CHECK='TRUE';
      ALLOW_CONNECT='TRUE';
    'VSS312':
      PIN_NUMBER='(0,0,0,0,0,0,0,0,0,0,0,0,0,0,0,0,0,0,0,0,0,0,0,0,0,0,0,0,0,0,0,0,0,0,0,0,0,AT22,0,0,0,0)';
      PINUSE='POWER';
      NO_LOAD_CHECK='Both';
      NO_IO_CHECK='Both';
      NO_ASSERT_CHECK='TRUE';
      NO_DIR_CHECK='TRUE';
      ALLOW_CONNECT='TRUE';
    'VSS311':
      PIN_NUMBER='(0,0,0,0,0,0,0,0,0,0,0,0,0,0,0,0,0,0,0,0,0,0,0,0,0,0,0,0,0,0,0,0,0,0,0,0,0,AT20,0,0,0,0)';
      PINUSE='POWER';
      NO_LOAD_CHECK='Both';
      NO_IO_CHECK='Both';
      NO_ASSERT_CHECK='TRUE';
      NO_DIR_CHECK='TRUE';
      ALLOW_CONNECT='TRUE';
    'VSS310':
      PIN_NUMBER='(0,0,0,0,0,0,0,0,0,0,0,0,0,0,0,0,0,0,0,0,0,0,0,0,0,0,0,0,0,0,0,0,0,0,0,0,0,AT16,0,0,0,0)';
      PINUSE='POWER';
      NO_LOAD_CHECK='Both';
      NO_IO_CHECK='Both';
      NO_ASSERT_CHECK='TRUE';
      NO_DIR_CHECK='TRUE';
      ALLOW_CONNECT='TRUE';
    'VSS309':
      PIN_NUMBER='(0,0,0,0,0,0,0,0,0,0,0,0,0,0,0,0,0,0,0,0,0,0,0,0,0,0,0,0,0,0,0,0,0,0,0,0,0,AT12,0,0,0,0)';
      PINUSE='POWER';
      NO_LOAD_CHECK='Both';
      NO_IO_CHECK='Both';
      NO_ASSERT_CHECK='TRUE';
      NO_DIR_CHECK='TRUE';
      ALLOW_CONNECT='TRUE';
    'VSS308':
      PIN_NUMBER='(0,0,0,0,0,0,0,0,0,0,0,0,0,0,0,0,0,0,0,0,0,0,0,0,0,0,0,0,0,0,0,0,0,0,0,0,0,AR9,0,0,0,0)';
      PINUSE='POWER';
      NO_LOAD_CHECK='Both';
      NO_IO_CHECK='Both';
      NO_ASSERT_CHECK='TRUE';
      NO_DIR_CHECK='TRUE';
      ALLOW_CONNECT='TRUE';
    'VSS307':
      PIN_NUMBER='(0,0,0,0,0,0,0,0,0,0,0,0,0,0,0,0,0,0,0,0,0,0,0,0,0,0,0,0,0,0,0,0,0,0,0,0,0,AR88,0,0,0,0)';
      PINUSE='POWER';
      NO_LOAD_CHECK='Both';
      NO_IO_CHECK='Both';
      NO_ASSERT_CHECK='TRUE';
      NO_DIR_CHECK='TRUE';
      ALLOW_CONNECT='TRUE';
    'VSS306':
      PIN_NUMBER='(0,0,0,0,0,0,0,0,0,0,0,0,0,0,0,0,0,0,0,0,0,0,0,0,0,0,0,0,0,0,0,0,0,0,0,0,0,AR84,0,0,0,0)';
      PINUSE='POWER';
      NO_LOAD_CHECK='Both';
      NO_IO_CHECK='Both';
      NO_ASSERT_CHECK='TRUE';
      NO_DIR_CHECK='TRUE';
      ALLOW_CONNECT='TRUE';
    'VSS305':
      PIN_NUMBER='(0,0,0,0,0,0,0,0,0,0,0,0,0,0,0,0,0,0,0,0,0,0,0,0,0,0,0,0,0,0,0,0,0,0,0,0,0,AR82,0,0,0,0)';
      PINUSE='POWER';
      NO_LOAD_CHECK='Both';
      NO_IO_CHECK='Both';
      NO_ASSERT_CHECK='TRUE';
      NO_DIR_CHECK='TRUE';
      ALLOW_CONNECT='TRUE';
    'VSS304':
      PIN_NUMBER='(0,0,0,0,0,0,0,0,0,0,0,0,0,0,0,0,0,0,0,0,0,0,0,0,0,0,0,0,0,0,0,0,0,0,0,0,0,AR78,0,0,0,0)';
      PINUSE='POWER';
      NO_LOAD_CHECK='Both';
      NO_IO_CHECK='Both';
      NO_ASSERT_CHECK='TRUE';
      NO_DIR_CHECK='TRUE';
      ALLOW_CONNECT='TRUE';
    'VSS303':
      PIN_NUMBER='(0,0,0,0,0,0,0,0,0,0,0,0,0,0,0,0,0,0,0,0,0,0,0,0,0,0,0,0,0,0,0,0,0,0,0,0,0,AR74,0,0,0,0)';
      PINUSE='POWER';
      NO_LOAD_CHECK='Both';
      NO_IO_CHECK='Both';
      NO_ASSERT_CHECK='TRUE';
      NO_DIR_CHECK='TRUE';
      ALLOW_CONNECT='TRUE';
    'VSS302':
      PIN_NUMBER='(0,0,0,0,0,0,0,0,0,0,0,0,0,0,0,0,0,0,0,0,0,0,0,0,0,0,0,0,0,0,0,0,0,0,0,0,0,AR72,0,0,0,0)';
      PINUSE='POWER';
      NO_LOAD_CHECK='Both';
      NO_IO_CHECK='Both';
      NO_ASSERT_CHECK='TRUE';
      NO_DIR_CHECK='TRUE';
      ALLOW_CONNECT='TRUE';
    'VSS301':
      PIN_NUMBER='(0,0,0,0,0,0,0,0,0,0,0,0,0,0,0,0,0,0,0,0,0,0,0,0,0,0,0,0,0,0,0,0,0,0,0,0,0,AR68,0,0,0,0)';
      PINUSE='POWER';
      NO_LOAD_CHECK='Both';
      NO_IO_CHECK='Both';
      NO_ASSERT_CHECK='TRUE';
      NO_DIR_CHECK='TRUE';
      ALLOW_CONNECT='TRUE';
    'VSS300':
      PIN_NUMBER='(0,0,0,0,0,0,0,0,0,0,0,0,0,0,0,0,0,0,0,0,0,0,0,0,0,0,0,0,0,0,0,0,0,0,0,0,0,AR66,0,0,0,0)';
      PINUSE='POWER';
      NO_LOAD_CHECK='Both';
      NO_IO_CHECK='Both';
      NO_ASSERT_CHECK='TRUE';
      NO_DIR_CHECK='TRUE';
      ALLOW_CONNECT='TRUE';
    'VSS299':
      PIN_NUMBER='(0,0,0,0,0,0,0,0,0,0,0,0,0,0,0,0,0,0,0,0,0,0,0,0,0,0,0,0,0,0,0,0,0,0,0,0,0,AR62,0,0,0,0)';
      PINUSE='POWER';
      NO_LOAD_CHECK='Both';
      NO_IO_CHECK='Both';
      NO_ASSERT_CHECK='TRUE';
      NO_DIR_CHECK='TRUE';
      ALLOW_CONNECT='TRUE';
    'VSS298':
      PIN_NUMBER='(0,0,0,0,0,0,0,0,0,0,0,0,0,0,0,0,0,0,0,0,0,0,0,0,0,0,0,0,0,0,0,0,0,0,0,0,0,AR60,0,0,0,0)';
      PINUSE='POWER';
      NO_LOAD_CHECK='Both';
      NO_IO_CHECK='Both';
      NO_ASSERT_CHECK='TRUE';
      NO_DIR_CHECK='TRUE';
      ALLOW_CONNECT='TRUE';
    'VSS297':
      PIN_NUMBER='(0,0,0,0,0,0,0,0,0,0,0,0,0,0,0,0,0,0,0,0,0,0,0,0,0,0,0,0,0,0,0,0,0,0,0,0,0,AR56,0,0,0,0)';
      PINUSE='POWER';
      NO_LOAD_CHECK='Both';
      NO_IO_CHECK='Both';
      NO_ASSERT_CHECK='TRUE';
      NO_DIR_CHECK='TRUE';
      ALLOW_CONNECT='TRUE';
    'VSS296':
      PIN_NUMBER='(0,0,0,0,0,0,0,0,0,0,0,0,0,0,0,0,0,0,0,0,0,0,0,0,0,0,0,0,0,0,0,0,0,0,0,0,0,AR54,0,0,0,0)';
      PINUSE='POWER';
      NO_LOAD_CHECK='Both';
      NO_IO_CHECK='Both';
      NO_ASSERT_CHECK='TRUE';
      NO_DIR_CHECK='TRUE';
      ALLOW_CONNECT='TRUE';
    'VSS295':
      PIN_NUMBER='(0,0,0,0,0,0,0,0,0,0,0,0,0,0,0,0,0,0,0,0,0,0,0,0,0,0,0,0,0,0,0,0,0,0,0,0,0,AR50,0,0,0,0)';
      PINUSE='POWER';
      NO_LOAD_CHECK='Both';
      NO_IO_CHECK='Both';
      NO_ASSERT_CHECK='TRUE';
      NO_DIR_CHECK='TRUE';
      ALLOW_CONNECT='TRUE';
    'VSS294':
      PIN_NUMBER='(0,0,0,0,0,0,0,0,0,0,0,0,0,0,0,0,0,0,0,0,0,0,0,0,0,0,0,0,0,0,0,0,0,0,0,0,0,AR5,0,0,0,0)';
      PINUSE='POWER';
      NO_LOAD_CHECK='Both';
      NO_IO_CHECK='Both';
      NO_ASSERT_CHECK='TRUE';
      NO_DIR_CHECK='TRUE';
      ALLOW_CONNECT='TRUE';
    'VSS293':
      PIN_NUMBER='(0,0,0,0,0,0,0,0,0,0,0,0,0,0,0,0,0,0,0,0,0,0,0,0,0,0,0,0,0,0,0,0,0,0,0,0,0,AR48,0,0,0,0)';
      PINUSE='POWER';
      NO_LOAD_CHECK='Both';
      NO_IO_CHECK='Both';
      NO_ASSERT_CHECK='TRUE';
      NO_DIR_CHECK='TRUE';
      ALLOW_CONNECT='TRUE';
    'VSS292':
      PIN_NUMBER='(0,0,0,0,0,0,0,0,0,0,0,0,0,0,0,0,0,0,0,0,0,0,0,0,0,0,0,0,0,0,0,0,0,0,0,0,0,AR43,0,0,0,0)';
      PINUSE='POWER';
      NO_LOAD_CHECK='Both';
      NO_IO_CHECK='Both';
      NO_ASSERT_CHECK='TRUE';
      NO_DIR_CHECK='TRUE';
      ALLOW_CONNECT='TRUE';
    'VSS291':
      PIN_NUMBER='(0,0,0,0,0,0,0,0,0,0,0,0,0,0,0,0,0,0,0,0,0,0,0,0,0,0,0,0,0,0,0,0,0,0,0,0,0,AR41,0,0,0,0)';
      PINUSE='POWER';
      NO_LOAD_CHECK='Both';
      NO_IO_CHECK='Both';
      NO_ASSERT_CHECK='TRUE';
      NO_DIR_CHECK='TRUE';
      ALLOW_CONNECT='TRUE';
    'VSS290':
      PIN_NUMBER='(0,0,0,0,0,0,0,0,0,0,0,0,0,0,0,0,0,0,0,0,0,0,0,0,0,0,0,0,0,0,0,0,0,0,0,0,0,AR37,0,0,0,0)';
      PINUSE='POWER';
      NO_LOAD_CHECK='Both';
      NO_IO_CHECK='Both';
      NO_ASSERT_CHECK='TRUE';
      NO_DIR_CHECK='TRUE';
      ALLOW_CONNECT='TRUE';
    'VSS289':
      PIN_NUMBER='(0,0,0,0,0,0,0,0,0,0,0,0,0,0,0,0,0,0,0,0,0,0,0,0,0,0,0,0,0,0,0,0,0,0,0,0,0,AR35,0,0,0,0)';
      PINUSE='POWER';
      NO_LOAD_CHECK='Both';
      NO_IO_CHECK='Both';
      NO_ASSERT_CHECK='TRUE';
      NO_DIR_CHECK='TRUE';
      ALLOW_CONNECT='TRUE';
    'VSS288':
      PIN_NUMBER='(0,0,0,0,0,0,0,0,0,0,0,0,0,0,0,0,0,0,0,0,0,0,0,0,0,0,0,0,0,0,0,0,0,0,0,0,0,AR31,0,0,0,0)';
      PINUSE='POWER';
      NO_LOAD_CHECK='Both';
      NO_IO_CHECK='Both';
      NO_ASSERT_CHECK='TRUE';
      NO_DIR_CHECK='TRUE';
      ALLOW_CONNECT='TRUE';
    'VSS287':
      PIN_NUMBER='(0,0,0,0,0,0,0,0,0,0,0,0,0,0,0,0,0,0,0,0,0,0,0,0,0,0,0,0,0,0,0,0,0,0,0,0,0,AR29,0,0,0,0)';
      PINUSE='POWER';
      NO_LOAD_CHECK='Both';
      NO_IO_CHECK='Both';
      NO_ASSERT_CHECK='TRUE';
      NO_DIR_CHECK='TRUE';
      ALLOW_CONNECT='TRUE';
    'VSS286':
      PIN_NUMBER='(0,0,0,0,0,0,0,0,0,0,0,0,0,0,0,0,0,0,0,0,0,0,0,0,0,0,0,0,0,0,0,0,0,0,0,0,0,AR25,0,0,0,0)';
      PINUSE='POWER';
      NO_LOAD_CHECK='Both';
      NO_IO_CHECK='Both';
      NO_ASSERT_CHECK='TRUE';
      NO_DIR_CHECK='TRUE';
      ALLOW_CONNECT='TRUE';
    'VSS285':
      PIN_NUMBER='(0,0,0,0,0,0,0,0,0,0,0,0,0,0,0,0,0,0,0,0,0,0,0,0,0,0,0,0,0,0,0,0,0,0,0,0,0,AR23,0,0,0,0)';
      PINUSE='POWER';
      NO_LOAD_CHECK='Both';
      NO_IO_CHECK='Both';
      NO_ASSERT_CHECK='TRUE';
      NO_DIR_CHECK='TRUE';
      ALLOW_CONNECT='TRUE';
    'VSS284':
      PIN_NUMBER='(0,0,0,0,0,0,0,0,0,0,0,0,0,0,0,0,0,0,0,0,0,0,0,0,0,0,0,0,0,0,0,0,0,0,0,0,0,AR19,0,0,0,0)';
      PINUSE='POWER';
      NO_LOAD_CHECK='Both';
      NO_IO_CHECK='Both';
      NO_ASSERT_CHECK='TRUE';
      NO_DIR_CHECK='TRUE';
      ALLOW_CONNECT='TRUE';
    'VSS283':
      PIN_NUMBER='(0,0,0,0,0,0,0,0,0,0,0,0,0,0,0,0,0,0,0,0,0,0,0,0,0,0,0,0,0,0,0,0,0,0,0,0,0,AR13,0,0,0,0)';
      PINUSE='POWER';
      NO_LOAD_CHECK='Both';
      NO_IO_CHECK='Both';
      NO_ASSERT_CHECK='TRUE';
      NO_DIR_CHECK='TRUE';
      ALLOW_CONNECT='TRUE';
    'VSS282':
      PIN_NUMBER='(0,0,0,0,0,0,0,0,0,0,0,0,0,0,0,0,0,0,0,0,0,0,0,0,0,0,0,0,0,0,0,0,0,0,0,0,0,AR1,0,0,0,0)';
      PINUSE='POWER';
      NO_LOAD_CHECK='Both';
      NO_IO_CHECK='Both';
      NO_ASSERT_CHECK='TRUE';
      NO_DIR_CHECK='TRUE';
      ALLOW_CONNECT='TRUE';
    'VSS281':
      PIN_NUMBER='(0,0,0,0,0,0,0,0,0,0,0,0,0,0,0,0,0,0,0,0,0,0,0,0,0,0,0,0,0,0,0,0,0,0,0,0,0,AP91,0,0,0,0)';
      PINUSE='POWER';
      NO_LOAD_CHECK='Both';
      NO_IO_CHECK='Both';
      NO_ASSERT_CHECK='TRUE';
      NO_DIR_CHECK='TRUE';
      ALLOW_CONNECT='TRUE';
    'VSS280':
      PIN_NUMBER='(0,0,0,0,0,0,0,0,0,0,0,0,0,0,0,0,0,0,0,0,0,0,0,0,0,0,0,0,0,0,0,0,0,0,0,0,0,AP87,0,0,0,0)';
      PINUSE='POWER';
      NO_LOAD_CHECK='Both';
      NO_IO_CHECK='Both';
      NO_ASSERT_CHECK='TRUE';
      NO_DIR_CHECK='TRUE';
      ALLOW_CONNECT='TRUE';
    'VSS279':
      PIN_NUMBER='(0,0,0,0,0,0,0,0,0,0,0,0,0,0,0,0,0,0,0,0,0,0,0,0,0,0,0,0,0,0,0,0,0,0,0,0,0,AP83,0,0,0,0)';
      PINUSE='POWER';
      NO_LOAD_CHECK='Both';
      NO_IO_CHECK='Both';
      NO_ASSERT_CHECK='TRUE';
      NO_DIR_CHECK='TRUE';
      ALLOW_CONNECT='TRUE';
    'VSS278':
      PIN_NUMBER='(0,0,0,0,0,0,0,0,0,0,0,0,0,0,0,0,0,0,0,0,0,0,0,0,0,0,0,0,0,0,0,0,0,0,0,0,0,AP8,0,0,0,0)';
      PINUSE='POWER';
      NO_LOAD_CHECK='Both';
      NO_IO_CHECK='Both';
      NO_ASSERT_CHECK='TRUE';
      NO_DIR_CHECK='TRUE';
      ALLOW_CONNECT='TRUE';
    'VSS277':
      PIN_NUMBER='(0,0,0,0,0,0,0,0,0,0,0,0,0,0,0,0,0,0,0,0,0,0,0,0,0,0,0,0,0,0,0,0,0,0,0,0,0,AP79,0,0,0,0)';
      PINUSE='POWER';
      NO_LOAD_CHECK='Both';
      NO_IO_CHECK='Both';
      NO_ASSERT_CHECK='TRUE';
      NO_DIR_CHECK='TRUE';
      ALLOW_CONNECT='TRUE';
    'VSS276':
      PIN_NUMBER='(0,0,0,0,0,0,0,0,0,0,0,0,0,0,0,0,0,0,0,0,0,0,0,0,0,0,0,0,0,0,0,0,0,0,0,0,0,AP73,0,0,0,0)';
      PINUSE='POWER';
      NO_LOAD_CHECK='Both';
      NO_IO_CHECK='Both';
      NO_ASSERT_CHECK='TRUE';
      NO_DIR_CHECK='TRUE';
      ALLOW_CONNECT='TRUE';
    'VSS275':
      PIN_NUMBER='(0,0,0,0,0,0,0,0,0,0,0,0,0,0,0,0,0,0,0,0,0,0,0,0,0,0,0,0,0,0,0,0,0,0,0,0,0,AP67,0,0,0,0)';
      PINUSE='POWER';
      NO_LOAD_CHECK='Both';
      NO_IO_CHECK='Both';
      NO_ASSERT_CHECK='TRUE';
      NO_DIR_CHECK='TRUE';
      ALLOW_CONNECT='TRUE';
    'VSS274':
      PIN_NUMBER='(0,0,0,0,0,0,0,0,0,0,0,0,0,0,0,0,0,0,0,0,0,0,0,0,0,0,0,0,0,0,0,0,0,0,0,0,0,AP61,0,0,0,0)';
      PINUSE='POWER';
      NO_LOAD_CHECK='Both';
      NO_IO_CHECK='Both';
      NO_ASSERT_CHECK='TRUE';
      NO_DIR_CHECK='TRUE';
      ALLOW_CONNECT='TRUE';
    'VSS273':
      PIN_NUMBER='(0,0,0,0,0,0,0,0,0,0,0,0,0,0,0,0,0,0,0,0,0,0,0,0,0,0,0,0,0,0,0,0,0,0,0,0,0,AP55,0,0,0,0)';
      PINUSE='POWER';
      NO_LOAD_CHECK='Both';
      NO_IO_CHECK='Both';
      NO_ASSERT_CHECK='TRUE';
      NO_DIR_CHECK='TRUE';
      ALLOW_CONNECT='TRUE';
    'VSS272':
      PIN_NUMBER='(0,0,0,0,0,0,0,0,0,0,0,0,0,0,0,0,0,0,0,0,0,0,0,0,0,0,0,0,0,0,0,0,0,0,0,0,0,AP49,0,0,0,0)';
      PINUSE='POWER';
      NO_LOAD_CHECK='Both';
      NO_IO_CHECK='Both';
      NO_ASSERT_CHECK='TRUE';
      NO_DIR_CHECK='TRUE';
      ALLOW_CONNECT='TRUE';
    'VSS271':
      PIN_NUMBER='(0,0,0,0,0,0,0,0,0,0,0,0,0,0,0,0,0,0,0,0,0,0,0,0,0,0,0,0,0,0,0,0,0,0,0,0,0,AP42,0,0,0,0)';
      PINUSE='POWER';
      NO_LOAD_CHECK='Both';
      NO_IO_CHECK='Both';
      NO_ASSERT_CHECK='TRUE';
      NO_DIR_CHECK='TRUE';
      ALLOW_CONNECT='TRUE';
    'VSS270':
      PIN_NUMBER='(0,0,0,0,0,0,0,0,0,0,0,0,0,0,0,0,0,0,0,0,0,0,0,0,0,0,0,0,0,0,0,0,0,0,0,0,0,AP4,0,0,0,0)';
      PINUSE='POWER';
      NO_LOAD_CHECK='Both';
      NO_IO_CHECK='Both';
      NO_ASSERT_CHECK='TRUE';
      NO_DIR_CHECK='TRUE';
      ALLOW_CONNECT='TRUE';
    'VSS269':
      PIN_NUMBER='(0,0,0,0,0,0,0,0,0,0,0,0,0,0,0,0,0,0,0,0,0,0,0,0,0,0,0,0,0,0,0,0,0,0,0,0,0,AP36,0,0,0,0)';
      PINUSE='POWER';
      NO_LOAD_CHECK='Both';
      NO_IO_CHECK='Both';
      NO_ASSERT_CHECK='TRUE';
      NO_DIR_CHECK='TRUE';
      ALLOW_CONNECT='TRUE';
    'VSS268':
      PIN_NUMBER='(0,0,0,0,0,0,0,0,0,0,0,0,0,0,0,0,0,0,0,0,0,0,0,0,0,0,0,0,0,0,0,0,0,0,0,0,0,AP30,0,0,0,0)';
      PINUSE='POWER';
      NO_LOAD_CHECK='Both';
      NO_IO_CHECK='Both';
      NO_ASSERT_CHECK='TRUE';
      NO_DIR_CHECK='TRUE';
      ALLOW_CONNECT='TRUE';
    'VSS267':
      PIN_NUMBER='(0,0,0,0,0,0,0,0,0,0,0,0,0,0,0,0,0,0,0,0,0,0,0,0,0,0,0,0,0,0,0,0,0,0,0,0,0,AP24,0,0,0,0)';
      PINUSE='POWER';
      NO_LOAD_CHECK='Both';
      NO_IO_CHECK='Both';
      NO_ASSERT_CHECK='TRUE';
      NO_DIR_CHECK='TRUE';
      ALLOW_CONNECT='TRUE';
    'VSS266':
      PIN_NUMBER='(0,0,0,0,0,0,0,0,0,0,0,0,0,0,0,0,0,0,0,0,0,0,0,0,0,0,0,0,0,0,0,0,0,0,0,0,0,AP18,0,0,0,0)';
      PINUSE='POWER';
      NO_LOAD_CHECK='Both';
      NO_IO_CHECK='Both';
      NO_ASSERT_CHECK='TRUE';
      NO_DIR_CHECK='TRUE';
      ALLOW_CONNECT='TRUE';
    'VSS265':
      PIN_NUMBER='(0,0,0,0,0,0,0,0,0,0,0,0,0,0,0,0,0,0,0,0,0,0,0,0,0,0,0,0,0,0,0,0,0,0,0,0,0,AP16,0,0,0,0)';
      PINUSE='POWER';
      NO_LOAD_CHECK='Both';
      NO_IO_CHECK='Both';
      NO_ASSERT_CHECK='TRUE';
      NO_DIR_CHECK='TRUE';
      ALLOW_CONNECT='TRUE';
    'VSS264':
      PIN_NUMBER='(0,0,0,0,0,0,0,0,0,0,0,0,0,0,0,0,0,0,0,0,0,0,0,0,0,0,0,0,0,0,0,0,0,0,0,0,0,AP12,0,0,0,0)';
      PINUSE='POWER';
      NO_LOAD_CHECK='Both';
      NO_IO_CHECK='Both';
      NO_ASSERT_CHECK='TRUE';
      NO_DIR_CHECK='TRUE';
      ALLOW_CONNECT='TRUE';
    'VSS263':
      PIN_NUMBER='(0,0,0,0,0,0,0,0,0,0,0,0,0,0,0,0,0,0,0,0,0,0,0,0,0,0,0,0,0,0,0,0,0,0,0,0,0,AN88,0,0,0,0)';
      PINUSE='POWER';
      NO_LOAD_CHECK='Both';
      NO_IO_CHECK='Both';
      NO_ASSERT_CHECK='TRUE';
      NO_DIR_CHECK='TRUE';
      ALLOW_CONNECT='TRUE';
    'VSS262':
      PIN_NUMBER='(0,0,0,0,0,0,0,0,0,0,0,0,0,0,0,0,0,0,0,0,0,0,0,0,0,0,0,0,0,0,0,0,0,0,0,0,0,AN84,0,0,0,0)';
      PINUSE='POWER';
      NO_LOAD_CHECK='Both';
      NO_IO_CHECK='Both';
      NO_ASSERT_CHECK='TRUE';
      NO_DIR_CHECK='TRUE';
      ALLOW_CONNECT='TRUE';
    'VSS261':
      PIN_NUMBER='(0,0,0,0,0,0,0,0,0,0,0,0,0,0,0,0,0,0,0,0,0,0,0,0,0,0,0,0,0,0,0,0,0,0,0,0,0,AN52,0,0,0,0)';
      PINUSE='POWER';
      NO_LOAD_CHECK='Both';
      NO_IO_CHECK='Both';
      NO_ASSERT_CHECK='TRUE';
      NO_DIR_CHECK='TRUE';
      ALLOW_CONNECT='TRUE';
    'VSS260':
      PIN_NUMBER='(0,0,0,0,0,0,0,0,0,0,0,0,0,0,0,0,0,0,0,0,0,0,0,0,0,0,0,0,0,0,0,0,0,0,0,0,0,AM8,0,0,0,0)';
      PINUSE='POWER';
      NO_LOAD_CHECK='Both';
      NO_IO_CHECK='Both';
      NO_ASSERT_CHECK='TRUE';
      NO_DIR_CHECK='TRUE';
      ALLOW_CONNECT='TRUE';
    'VSS259':
      PIN_NUMBER='(0,0,0,0,0,0,0,0,0,0,0,0,0,0,0,0,0,0,0,0,0,0,0,0,0,0,0,0,0,0,0,0,0,0,0,0,0,AM77,0,0,0,0)';
      PINUSE='POWER';
      NO_LOAD_CHECK='Both';
      NO_IO_CHECK='Both';
      NO_ASSERT_CHECK='TRUE';
      NO_DIR_CHECK='TRUE';
      ALLOW_CONNECT='TRUE';
    'VSS258':
      PIN_NUMBER='(0,0,0,0,0,0,0,0,0,0,0,0,0,0,0,0,0,0,0,0,0,0,0,0,0,0,0,0,0,0,0,0,0,0,0,0,0,AM75,0,0,0,0)';
      PINUSE='POWER';
      NO_LOAD_CHECK='Both';
      NO_IO_CHECK='Both';
      NO_ASSERT_CHECK='TRUE';
      NO_DIR_CHECK='TRUE';
      ALLOW_CONNECT='TRUE';
    'VSS257':
      PIN_NUMBER='(0,0,0,0,0,0,0,0,0,0,0,0,0,0,0,0,0,0,0,0,0,0,0,0,0,0,0,0,0,0,0,0,0,0,0,0,0,AM73,0,0,0,0)';
      PINUSE='POWER';
      NO_LOAD_CHECK='Both';
      NO_IO_CHECK='Both';
      NO_ASSERT_CHECK='TRUE';
      NO_DIR_CHECK='TRUE';
      ALLOW_CONNECT='TRUE';
    'VSS256':
      PIN_NUMBER='(0,0,0,0,0,0,0,0,0,0,0,0,0,0,0,0,0,0,0,0,0,0,0,0,0,0,0,0,0,0,0,0,0,0,0,0,0,AM71,0,0,0,0)';
      PINUSE='POWER';
      NO_LOAD_CHECK='Both';
      NO_IO_CHECK='Both';
      NO_ASSERT_CHECK='TRUE';
      NO_DIR_CHECK='TRUE';
      ALLOW_CONNECT='TRUE';
    'VSS255':
      PIN_NUMBER='(0,0,0,0,0,0,0,0,0,0,0,0,0,0,0,0,0,0,0,0,0,0,0,0,0,0,0,0,0,0,0,0,0,0,0,0,0,AM69,0,0,0,0)';
      PINUSE='POWER';
      NO_LOAD_CHECK='Both';
      NO_IO_CHECK='Both';
      NO_ASSERT_CHECK='TRUE';
      NO_DIR_CHECK='TRUE';
      ALLOW_CONNECT='TRUE';
    'VSS254':
      PIN_NUMBER='(0,0,0,0,0,0,0,0,0,0,0,0,0,0,0,0,0,0,0,0,0,0,0,0,0,0,0,0,0,0,0,0,0,0,0,0,0,AM67,0,0,0,0)';
      PINUSE='POWER';
      NO_LOAD_CHECK='Both';
      NO_IO_CHECK='Both';
      NO_ASSERT_CHECK='TRUE';
      NO_DIR_CHECK='TRUE';
      ALLOW_CONNECT='TRUE';
    'VSS253':
      PIN_NUMBER='(0,0,0,0,0,0,0,0,0,0,0,0,0,0,0,0,0,0,0,0,0,0,0,0,0,0,0,0,0,0,0,0,0,0,0,0,0,AM65,0,0,0,0)';
      PINUSE='POWER';
      NO_LOAD_CHECK='Both';
      NO_IO_CHECK='Both';
      NO_ASSERT_CHECK='TRUE';
      NO_DIR_CHECK='TRUE';
      ALLOW_CONNECT='TRUE';
    'VSS252':
      PIN_NUMBER='(0,0,0,0,0,0,0,0,0,0,0,0,0,0,0,0,0,0,0,0,0,0,0,0,0,0,0,0,0,0,0,0,0,0,0,0,0,AM63,0,0,0,0)';
      PINUSE='POWER';
      NO_LOAD_CHECK='Both';
      NO_IO_CHECK='Both';
      NO_ASSERT_CHECK='TRUE';
      NO_DIR_CHECK='TRUE';
      ALLOW_CONNECT='TRUE';
    'VSS251':
      PIN_NUMBER='(0,0,0,0,0,0,0,0,0,0,0,0,0,0,0,0,0,0,0,0,0,0,0,0,0,0,0,0,0,0,0,0,0,0,0,0,0,AM61,0,0,0,0)';
      PINUSE='POWER';
      NO_LOAD_CHECK='Both';
      NO_IO_CHECK='Both';
      NO_ASSERT_CHECK='TRUE';
      NO_DIR_CHECK='TRUE';
      ALLOW_CONNECT='TRUE';
    'VSS250':
      PIN_NUMBER='(0,0,0,0,0,0,0,0,0,0,0,0,0,0,0,0,0,0,0,0,0,0,0,0,0,0,0,0,0,0,0,0,0,0,0,0,0,AM59,0,0,0,0)';
      PINUSE='POWER';
      NO_LOAD_CHECK='Both';
      NO_IO_CHECK='Both';
      NO_ASSERT_CHECK='TRUE';
      NO_DIR_CHECK='TRUE';
      ALLOW_CONNECT='TRUE';
    'VSS249':
      PIN_NUMBER='(0,0,0,0,0,0,0,0,0,0,0,0,0,0,0,0,0,0,0,0,0,0,0,0,0,0,0,0,0,0,0,0,0,0,0,0,0,AM57,0,0,0,0)';
      PINUSE='POWER';
      NO_LOAD_CHECK='Both';
      NO_IO_CHECK='Both';
      NO_ASSERT_CHECK='TRUE';
      NO_DIR_CHECK='TRUE';
      ALLOW_CONNECT='TRUE';
    'VSS248':
      PIN_NUMBER='(0,0,0,0,0,0,0,0,0,0,0,0,0,0,0,0,0,0,0,0,0,0,0,0,0,0,0,0,0,0,0,0,0,0,0,0,0,AM55,0,0,0,0)';
      PINUSE='POWER';
      NO_LOAD_CHECK='Both';
      NO_IO_CHECK='Both';
      NO_ASSERT_CHECK='TRUE';
      NO_DIR_CHECK='TRUE';
      ALLOW_CONNECT='TRUE';
    'VSS247':
      PIN_NUMBER='(0,0,0,0,0,0,0,0,0,0,0,0,0,0,0,0,0,0,0,0,0,0,0,0,0,0,0,0,0,0,0,0,0,0,0,0,0,AM53,0,0,0,0)';
      PINUSE='POWER';
      NO_LOAD_CHECK='Both';
      NO_IO_CHECK='Both';
      NO_ASSERT_CHECK='TRUE';
      NO_DIR_CHECK='TRUE';
      ALLOW_CONNECT='TRUE';
    'VSS246':
      PIN_NUMBER='(0,0,0,0,0,0,0,0,0,0,0,0,0,0,0,0,0,0,0,0,0,0,0,0,0,0,0,0,0,0,0,0,0,0,0,0,0,AM51,0,0,0,0)';
      PINUSE='POWER';
      NO_LOAD_CHECK='Both';
      NO_IO_CHECK='Both';
      NO_ASSERT_CHECK='TRUE';
      NO_DIR_CHECK='TRUE';
      ALLOW_CONNECT='TRUE';
    'VSS245':
      PIN_NUMBER='(0,0,0,0,0,0,0,0,0,0,0,0,0,0,0,0,0,0,0,0,0,0,0,0,0,0,0,0,0,0,0,0,0,0,0,0,0,AM49,0,0,0,0)';
      PINUSE='POWER';
      NO_LOAD_CHECK='Both';
      NO_IO_CHECK='Both';
      NO_ASSERT_CHECK='TRUE';
      NO_DIR_CHECK='TRUE';
      ALLOW_CONNECT='TRUE';
    'VSS244':
      PIN_NUMBER='(0,0,0,0,0,0,0,0,0,0,0,0,0,0,0,0,0,0,0,0,0,0,0,0,0,0,0,0,0,0,0,0,0,0,0,0,0,AM47,0,0,0,0)';
      PINUSE='POWER';
      NO_LOAD_CHECK='Both';
      NO_IO_CHECK='Both';
      NO_ASSERT_CHECK='TRUE';
      NO_DIR_CHECK='TRUE';
      ALLOW_CONNECT='TRUE';
    'VSS243':
      PIN_NUMBER='(0,0,0,0,0,0,0,0,0,0,0,0,0,0,0,0,0,0,0,0,0,0,0,0,0,0,0,0,0,0,0,0,0,0,0,0,0,AM44,0,0,0,0)';
      PINUSE='POWER';
      NO_LOAD_CHECK='Both';
      NO_IO_CHECK='Both';
      NO_ASSERT_CHECK='TRUE';
      NO_DIR_CHECK='TRUE';
      ALLOW_CONNECT='TRUE';
    'VSS242':
      PIN_NUMBER='(0,0,0,0,0,0,0,0,0,0,0,0,0,0,0,0,0,0,0,0,0,0,0,0,0,0,0,0,0,0,0,0,0,0,0,0,0,AM42,0,0,0,0)';
      PINUSE='POWER';
      NO_LOAD_CHECK='Both';
      NO_IO_CHECK='Both';
      NO_ASSERT_CHECK='TRUE';
      NO_DIR_CHECK='TRUE';
      ALLOW_CONNECT='TRUE';
    'VSS241':
      PIN_NUMBER='(0,0,0,0,0,0,0,0,0,0,0,0,0,0,0,0,0,0,0,0,0,0,0,0,0,0,0,0,0,0,0,0,0,0,0,0,0,AM40,0,0,0,0)';
      PINUSE='POWER';
      NO_LOAD_CHECK='Both';
      NO_IO_CHECK='Both';
      NO_ASSERT_CHECK='TRUE';
      NO_DIR_CHECK='TRUE';
      ALLOW_CONNECT='TRUE';
    'VSS240':
      PIN_NUMBER='(0,0,0,0,0,0,0,0,0,0,0,0,0,0,0,0,0,0,0,0,0,0,0,0,0,0,0,0,0,0,0,0,0,0,0,0,0,AM4,0,0,0,0)';
      PINUSE='POWER';
      NO_LOAD_CHECK='Both';
      NO_IO_CHECK='Both';
      NO_ASSERT_CHECK='TRUE';
      NO_DIR_CHECK='TRUE';
      ALLOW_CONNECT='TRUE';
    'VSS239':
      PIN_NUMBER='(0,0,0,0,0,0,0,0,0,0,0,0,0,0,0,0,0,0,0,0,0,0,0,0,0,0,0,0,0,0,0,0,0,0,0,0,0,AM38,0,0,0,0)';
      PINUSE='POWER';
      NO_LOAD_CHECK='Both';
      NO_IO_CHECK='Both';
      NO_ASSERT_CHECK='TRUE';
      NO_DIR_CHECK='TRUE';
      ALLOW_CONNECT='TRUE';
    'VSS238':
      PIN_NUMBER='(0,0,0,0,0,0,0,0,0,0,0,0,0,0,0,0,0,0,0,0,0,0,0,0,0,0,0,0,0,0,0,0,0,0,0,0,0,AM36,0,0,0,0)';
      PINUSE='POWER';
      NO_LOAD_CHECK='Both';
      NO_IO_CHECK='Both';
      NO_ASSERT_CHECK='TRUE';
      NO_DIR_CHECK='TRUE';
      ALLOW_CONNECT='TRUE';
    'VSS237':
      PIN_NUMBER='(0,0,0,0,0,0,0,0,0,0,0,0,0,0,0,0,0,0,0,0,0,0,0,0,0,0,0,0,0,0,0,0,0,0,0,0,0,AM34,0,0,0,0)';
      PINUSE='POWER';
      NO_LOAD_CHECK='Both';
      NO_IO_CHECK='Both';
      NO_ASSERT_CHECK='TRUE';
      NO_DIR_CHECK='TRUE';
      ALLOW_CONNECT='TRUE';
    'VSS236':
      PIN_NUMBER='(0,0,0,0,0,0,0,0,0,0,0,0,0,0,0,0,0,0,0,0,0,0,0,0,0,0,0,0,0,0,0,0,0,0,0,0,0,AM32,0,0,0,0)';
      PINUSE='POWER';
      NO_LOAD_CHECK='Both';
      NO_IO_CHECK='Both';
      NO_ASSERT_CHECK='TRUE';
      NO_DIR_CHECK='TRUE';
      ALLOW_CONNECT='TRUE';
    'VSS235':
      PIN_NUMBER='(0,0,0,0,0,0,0,0,0,0,0,0,0,0,0,0,0,0,0,0,0,0,0,0,0,0,0,0,0,0,0,0,0,0,0,0,0,AM30,0,0,0,0)';
      PINUSE='POWER';
      NO_LOAD_CHECK='Both';
      NO_IO_CHECK='Both';
      NO_ASSERT_CHECK='TRUE';
      NO_DIR_CHECK='TRUE';
      ALLOW_CONNECT='TRUE';
    'VSS234':
      PIN_NUMBER='(0,0,0,0,0,0,0,0,0,0,0,0,0,0,0,0,0,0,0,0,0,0,0,0,0,0,0,0,0,0,0,0,0,0,0,0,0,AM28,0,0,0,0)';
      PINUSE='POWER';
      NO_LOAD_CHECK='Both';
      NO_IO_CHECK='Both';
      NO_ASSERT_CHECK='TRUE';
      NO_DIR_CHECK='TRUE';
      ALLOW_CONNECT='TRUE';
    'VSS233':
      PIN_NUMBER='(0,0,0,0,0,0,0,0,0,0,0,0,0,0,0,0,0,0,0,0,0,0,0,0,0,0,0,0,0,0,0,0,0,0,0,0,0,AM26,0,0,0,0)';
      PINUSE='POWER';
      NO_LOAD_CHECK='Both';
      NO_IO_CHECK='Both';
      NO_ASSERT_CHECK='TRUE';
      NO_DIR_CHECK='TRUE';
      ALLOW_CONNECT='TRUE';
    'VSS232':
      PIN_NUMBER='(0,0,0,0,0,0,0,0,0,0,0,0,0,0,0,0,0,0,0,0,0,0,0,0,0,0,0,0,0,0,0,0,0,0,0,0,0,AM24,0,0,0,0)';
      PINUSE='POWER';
      NO_LOAD_CHECK='Both';
      NO_IO_CHECK='Both';
      NO_ASSERT_CHECK='TRUE';
      NO_DIR_CHECK='TRUE';
      ALLOW_CONNECT='TRUE';
    'VSS231':
      PIN_NUMBER='(0,0,0,0,0,0,0,0,0,0,0,0,0,0,0,0,0,0,0,0,0,0,0,0,0,0,0,0,0,0,0,0,0,0,0,0,0,AM22,0,0,0,0)';
      PINUSE='POWER';
      NO_LOAD_CHECK='Both';
      NO_IO_CHECK='Both';
      NO_ASSERT_CHECK='TRUE';
      NO_DIR_CHECK='TRUE';
      ALLOW_CONNECT='TRUE';
    'VSS230':
      PIN_NUMBER='(0,0,0,0,0,0,0,0,0,0,0,0,0,0,0,0,0,0,0,0,0,0,0,0,0,0,0,0,0,0,0,0,0,0,0,0,0,AM20,0,0,0,0)';
      PINUSE='POWER';
      NO_LOAD_CHECK='Both';
      NO_IO_CHECK='Both';
      NO_ASSERT_CHECK='TRUE';
      NO_DIR_CHECK='TRUE';
      ALLOW_CONNECT='TRUE';
    'VSS229':
      PIN_NUMBER='(0,0,0,0,0,0,0,0,0,0,0,0,0,0,0,0,0,0,0,0,0,0,0,0,0,0,0,0,0,0,0,0,0,0,0,0,0,AM18,0,0,0,0)';
      PINUSE='POWER';
      NO_LOAD_CHECK='Both';
      NO_IO_CHECK='Both';
      NO_ASSERT_CHECK='TRUE';
      NO_DIR_CHECK='TRUE';
      ALLOW_CONNECT='TRUE';
    'VSS228':
      PIN_NUMBER='(0,0,0,0,0,0,0,0,0,0,0,0,0,0,0,0,0,0,0,0,0,0,0,0,0,0,0,0,0,0,0,0,0,0,0,0,0,AM16,0,0,0,0)';
      PINUSE='POWER';
      NO_LOAD_CHECK='Both';
      NO_IO_CHECK='Both';
      NO_ASSERT_CHECK='TRUE';
      NO_DIR_CHECK='TRUE';
      ALLOW_CONNECT='TRUE';
    'VSS227':
      PIN_NUMBER='(0,0,0,0,0,0,0,0,0,0,0,0,0,0,0,0,0,0,0,0,0,0,0,0,0,0,0,0,0,0,0,0,0,0,0,0,0,AM12,0,0,0,0)';
      PINUSE='POWER';
      NO_LOAD_CHECK='Both';
      NO_IO_CHECK='Both';
      NO_ASSERT_CHECK='TRUE';
      NO_DIR_CHECK='TRUE';
      ALLOW_CONNECT='TRUE';
    'VSS226':
      PIN_NUMBER='(0,0,0,0,0,0,0,0,0,0,0,0,0,0,0,0,0,0,0,0,0,0,0,0,0,0,0,0,0,0,0,0,0,0,0,0,0,AL9,0,0,0,0)';
      PINUSE='POWER';
      NO_LOAD_CHECK='Both';
      NO_IO_CHECK='Both';
      NO_ASSERT_CHECK='TRUE';
      NO_DIR_CHECK='TRUE';
      ALLOW_CONNECT='TRUE';
    'VSS225':
      PIN_NUMBER='(0,0,0,0,0,0,0,0,0,0,0,0,0,0,0,0,0,0,0,0,0,0,0,0,0,0,0,0,0,0,0,0,0,0,0,0,0,AL88,0,0,0,0)';
      PINUSE='POWER';
      NO_LOAD_CHECK='Both';
      NO_IO_CHECK='Both';
      NO_ASSERT_CHECK='TRUE';
      NO_DIR_CHECK='TRUE';
      ALLOW_CONNECT='TRUE';
    'VSS224':
      PIN_NUMBER='(0,0,0,0,0,0,0,0,0,0,0,0,0,0,0,0,0,0,0,0,0,0,0,0,0,0,0,0,0,0,0,0,0,0,0,0,0,AL84,0,0,0,0)';
      PINUSE='POWER';
      NO_LOAD_CHECK='Both';
      NO_IO_CHECK='Both';
      NO_ASSERT_CHECK='TRUE';
      NO_DIR_CHECK='TRUE';
      ALLOW_CONNECT='TRUE';
    'VSS223':
      PIN_NUMBER='(0,0,0,0,0,0,0,0,0,0,0,0,0,0,0,0,0,0,0,0,0,0,0,0,0,0,0,0,0,0,0,0,0,0,0,0,0,AL82,0,0,0,0)';
      PINUSE='POWER';
      NO_LOAD_CHECK='Both';
      NO_IO_CHECK='Both';
      NO_ASSERT_CHECK='TRUE';
      NO_DIR_CHECK='TRUE';
      ALLOW_CONNECT='TRUE';
    'VSS222':
      PIN_NUMBER='(0,0,0,0,0,0,0,0,0,0,0,0,0,0,0,0,0,0,0,0,0,0,0,0,0,0,0,0,0,0,0,0,0,0,0,0,0,AL80,0,0,0,0)';
      PINUSE='POWER';
      NO_LOAD_CHECK='Both';
      NO_IO_CHECK='Both';
      NO_ASSERT_CHECK='TRUE';
      NO_DIR_CHECK='TRUE';
      ALLOW_CONNECT='TRUE';
    'VSS221':
      PIN_NUMBER='(0,0,0,0,0,0,0,0,0,0,0,0,0,0,0,0,0,0,0,0,0,0,0,0,0,0,0,0,0,0,0,0,0,0,0,0,0,AL52,0,0,0,0)';
      PINUSE='POWER';
      NO_LOAD_CHECK='Both';
      NO_IO_CHECK='Both';
      NO_ASSERT_CHECK='TRUE';
      NO_DIR_CHECK='TRUE';
      ALLOW_CONNECT='TRUE';
    'VSS220':
      PIN_NUMBER='(0,0,0,0,0,0,0,0,0,0,0,0,0,0,0,0,0,0,0,0,0,0,0,0,0,0,0,0,0,0,0,0,0,0,0,0,0,AL5,0,0,0,0)';
      PINUSE='POWER';
      NO_LOAD_CHECK='Both';
      NO_IO_CHECK='Both';
      NO_ASSERT_CHECK='TRUE';
      NO_DIR_CHECK='TRUE';
      ALLOW_CONNECT='TRUE';
    'VSS219':
      PIN_NUMBER='(0,0,0,0,0,0,0,0,0,0,0,0,0,0,0,0,0,0,0,0,0,0,0,0,0,0,0,0,0,0,0,0,0,0,0,0,0,AL17,0,0,0,0)';
      PINUSE='POWER';
      NO_LOAD_CHECK='Both';
      NO_IO_CHECK='Both';
      NO_ASSERT_CHECK='TRUE';
      NO_DIR_CHECK='TRUE';
      ALLOW_CONNECT='TRUE';
    'VSS218':
      PIN_NUMBER='(0,0,0,0,0,0,0,0,0,0,0,0,0,0,0,0,0,0,0,0,0,0,0,0,0,0,0,0,0,0,0,0,0,0,0,0,0,AL13,0,0,0,0)';
      PINUSE='POWER';
      NO_LOAD_CHECK='Both';
      NO_IO_CHECK='Both';
      NO_ASSERT_CHECK='TRUE';
      NO_DIR_CHECK='TRUE';
      ALLOW_CONNECT='TRUE';
    'VSS217':
      PIN_NUMBER='(0,0,0,0,0,0,0,0,0,0,0,0,0,0,0,0,0,0,0,0,0,0,0,0,0,0,0,0,0,0,0,0,0,0,0,0,0,AL1,0,0,0,0)';
      PINUSE='POWER';
      NO_LOAD_CHECK='Both';
      NO_IO_CHECK='Both';
      NO_ASSERT_CHECK='TRUE';
      NO_DIR_CHECK='TRUE';
      ALLOW_CONNECT='TRUE';
    'VSS216':
      PIN_NUMBER='(0,0,0,0,0,0,0,0,0,0,0,0,0,0,0,0,0,0,0,0,0,0,0,0,0,0,0,0,0,0,0,0,0,0,0,0,0,AK91,0,0,0,0)';
      PINUSE='POWER';
      NO_LOAD_CHECK='Both';
      NO_IO_CHECK='Both';
      NO_ASSERT_CHECK='TRUE';
      NO_DIR_CHECK='TRUE';
      ALLOW_CONNECT='TRUE';
    'VSS215':
      PIN_NUMBER='(0,0,0,0,0,0,0,0,0,0,0,0,0,0,0,0,0,0,0,0,0,0,0,0,0,0,0,0,0,0,0,0,0,0,0,0,0,AK87,0,0,0,0)';
      PINUSE='POWER';
      NO_LOAD_CHECK='Both';
      NO_IO_CHECK='Both';
      NO_ASSERT_CHECK='TRUE';
      NO_DIR_CHECK='TRUE';
      ALLOW_CONNECT='TRUE';
    'VSS214':
      PIN_NUMBER='(0,0,0,0,0,0,0,0,0,0,0,0,0,0,0,0,0,0,0,0,0,0,0,0,0,0,0,0,0,0,0,0,0,0,0,0,0,AK83,0,0,0,0)';
      PINUSE='POWER';
      NO_LOAD_CHECK='Both';
      NO_IO_CHECK='Both';
      NO_ASSERT_CHECK='TRUE';
      NO_DIR_CHECK='TRUE';
      ALLOW_CONNECT='TRUE';
    'VSS213':
      PIN_NUMBER='(0,0,0,0,0,0,0,0,0,0,0,0,0,0,0,0,0,0,0,0,0,0,0,0,0,0,0,0,0,0,0,0,0,0,0,0,0,AK81,0,0,0,0)';
      PINUSE='POWER';
      NO_LOAD_CHECK='Both';
      NO_IO_CHECK='Both';
      NO_ASSERT_CHECK='TRUE';
      NO_DIR_CHECK='TRUE';
      ALLOW_CONNECT='TRUE';
    'VSS212':
      PIN_NUMBER='(0,0,0,0,0,0,0,0,0,0,0,0,0,0,0,0,0,0,0,0,0,0,0,0,0,0,0,0,0,0,0,0,0,0,0,0,0,AK8,0,0,0,0)';
      PINUSE='POWER';
      NO_LOAD_CHECK='Both';
      NO_IO_CHECK='Both';
      NO_ASSERT_CHECK='TRUE';
      NO_DIR_CHECK='TRUE';
      ALLOW_CONNECT='TRUE';
    'VSS211':
      PIN_NUMBER='(0,0,0,0,0,0,0,0,0,0,0,0,0,0,0,0,0,0,0,0,0,0,0,0,0,0,0,0,0,0,0,0,0,0,0,0,0,AK79,0,0,0,0)';
      PINUSE='POWER';
      NO_LOAD_CHECK='Both';
      NO_IO_CHECK='Both';
      NO_ASSERT_CHECK='TRUE';
      NO_DIR_CHECK='TRUE';
      ALLOW_CONNECT='TRUE';
    'VSS210':
      PIN_NUMBER='(0,0,0,0,0,0,0,0,0,0,0,0,0,0,0,0,0,0,0,0,0,0,0,0,0,0,0,0,0,0,0,0,0,0,0,0,0,AK73,0,0,0,0)';
      PINUSE='POWER';
      NO_LOAD_CHECK='Both';
      NO_IO_CHECK='Both';
      NO_ASSERT_CHECK='TRUE';
      NO_DIR_CHECK='TRUE';
      ALLOW_CONNECT='TRUE';
    'VSS209':
      PIN_NUMBER='(0,0,0,0,0,0,0,0,0,0,0,0,0,0,0,0,0,0,0,0,0,0,0,0,0,0,0,0,0,0,0,0,0,0,0,0,0,AK67,0,0,0,0)';
      PINUSE='POWER';
      NO_LOAD_CHECK='Both';
      NO_IO_CHECK='Both';
      NO_ASSERT_CHECK='TRUE';
      NO_DIR_CHECK='TRUE';
      ALLOW_CONNECT='TRUE';
    'VSS208':
      PIN_NUMBER='(0,0,0,0,0,0,0,0,0,0,0,0,0,0,0,0,0,0,0,0,0,0,0,0,0,0,0,0,0,0,0,0,0,0,0,0,0,AK61,0,0,0,0)';
      PINUSE='POWER';
      NO_LOAD_CHECK='Both';
      NO_IO_CHECK='Both';
      NO_ASSERT_CHECK='TRUE';
      NO_DIR_CHECK='TRUE';
      ALLOW_CONNECT='TRUE';
    'VSS207':
      PIN_NUMBER='(0,0,0,0,0,0,0,0,0,0,0,0,0,0,0,0,0,0,0,0,0,0,0,0,0,0,0,0,0,0,0,0,0,0,0,0,0,AK55,0,0,0,0)';
      PINUSE='POWER';
      NO_LOAD_CHECK='Both';
      NO_IO_CHECK='Both';
      NO_ASSERT_CHECK='TRUE';
      NO_DIR_CHECK='TRUE';
      ALLOW_CONNECT='TRUE';
    'VSS206':
      PIN_NUMBER='(0,0,0,0,0,0,0,0,0,0,0,0,0,0,0,0,0,0,0,0,0,0,0,0,0,0,0,0,0,0,0,0,0,0,0,0,0,AK49,0,0,0,0)';
      PINUSE='POWER';
      NO_LOAD_CHECK='Both';
      NO_IO_CHECK='Both';
      NO_ASSERT_CHECK='TRUE';
      NO_DIR_CHECK='TRUE';
      ALLOW_CONNECT='TRUE';
    'VSS205':
      PIN_NUMBER='(0,0,0,0,0,0,0,0,0,0,0,0,0,0,0,0,0,0,0,0,0,0,0,0,0,0,0,0,0,0,0,0,0,0,0,0,0,AK42,0,0,0,0)';
      PINUSE='POWER';
      NO_LOAD_CHECK='Both';
      NO_IO_CHECK='Both';
      NO_ASSERT_CHECK='TRUE';
      NO_DIR_CHECK='TRUE';
      ALLOW_CONNECT='TRUE';
    'VSS204':
      PIN_NUMBER='(0,0,0,0,0,0,0,0,0,0,0,0,0,0,0,0,0,0,0,0,0,0,0,0,0,0,0,0,0,0,0,0,0,0,0,0,0,AK4,0,0,0,0)';
      PINUSE='POWER';
      NO_LOAD_CHECK='Both';
      NO_IO_CHECK='Both';
      NO_ASSERT_CHECK='TRUE';
      NO_DIR_CHECK='TRUE';
      ALLOW_CONNECT='TRUE';
    'VSS203':
      PIN_NUMBER='(0,0,0,0,0,0,0,0,0,0,0,0,0,0,0,0,0,0,0,0,0,0,0,0,0,0,0,0,0,0,0,0,0,0,0,0,0,AK36,0,0,0,0)';
      PINUSE='POWER';
      NO_LOAD_CHECK='Both';
      NO_IO_CHECK='Both';
      NO_ASSERT_CHECK='TRUE';
      NO_DIR_CHECK='TRUE';
      ALLOW_CONNECT='TRUE';
    'VSS202':
      PIN_NUMBER='(0,0,0,0,0,0,0,0,0,0,0,0,0,0,0,0,0,0,0,0,0,0,0,0,0,0,0,0,0,0,0,0,0,0,0,0,0,AK30,0,0,0,0)';
      PINUSE='POWER';
      NO_LOAD_CHECK='Both';
      NO_IO_CHECK='Both';
      NO_ASSERT_CHECK='TRUE';
      NO_DIR_CHECK='TRUE';
      ALLOW_CONNECT='TRUE';
    'VSS201':
      PIN_NUMBER='(0,0,0,0,0,0,0,0,0,0,0,0,0,0,0,0,0,0,0,0,0,0,0,0,0,0,0,0,0,0,0,0,0,0,0,0,0,AK24,0,0,0,0)';
      PINUSE='POWER';
      NO_LOAD_CHECK='Both';
      NO_IO_CHECK='Both';
      NO_ASSERT_CHECK='TRUE';
      NO_DIR_CHECK='TRUE';
      ALLOW_CONNECT='TRUE';
    'VSS200':
      PIN_NUMBER='(0,0,0,0,0,0,0,0,0,0,0,0,0,0,0,0,0,0,0,0,0,0,0,0,0,0,0,0,0,0,0,0,0,0,0,0,0,AK18,0,0,0,0)';
      PINUSE='POWER';
      NO_LOAD_CHECK='Both';
      NO_IO_CHECK='Both';
      NO_ASSERT_CHECK='TRUE';
      NO_DIR_CHECK='TRUE';
      ALLOW_CONNECT='TRUE';
    'VSS199':
      PIN_NUMBER='(0,0,0,0,0,0,0,0,0,0,0,0,0,0,0,0,0,0,0,0,0,0,0,0,0,0,0,0,0,0,0,0,0,0,0,0,0,AK16,0,0,0,0)';
      PINUSE='POWER';
      NO_LOAD_CHECK='Both';
      NO_IO_CHECK='Both';
      NO_ASSERT_CHECK='TRUE';
      NO_DIR_CHECK='TRUE';
      ALLOW_CONNECT='TRUE';
    'VSS198':
      PIN_NUMBER='(0,0,0,0,0,0,0,0,0,0,0,0,0,0,0,0,0,0,0,0,0,0,0,0,0,0,0,0,0,0,0,0,0,0,0,0,0,AK12,0,0,0,0)';
      PINUSE='POWER';
      NO_LOAD_CHECK='Both';
      NO_IO_CHECK='Both';
      NO_ASSERT_CHECK='TRUE';
      NO_DIR_CHECK='TRUE';
      ALLOW_CONNECT='TRUE';
    'VSS197':
      PIN_NUMBER='(0,0,0,0,0,0,0,0,0,0,0,0,0,0,0,0,0,0,0,0,0,0,0,0,0,0,0,0,0,0,0,0,0,0,0,0,0,0,AJ88,0,0,0)';
      PINUSE='POWER';
      NO_LOAD_CHECK='Both';
      NO_IO_CHECK='Both';
      NO_ASSERT_CHECK='TRUE';
      NO_DIR_CHECK='TRUE';
      ALLOW_CONNECT='TRUE';
    'VSS196':
      PIN_NUMBER='(0,0,0,0,0,0,0,0,0,0,0,0,0,0,0,0,0,0,0,0,0,0,0,0,0,0,0,0,0,0,0,0,0,0,0,0,0,0,AJ84,0,0,0)';
      PINUSE='POWER';
      NO_LOAD_CHECK='Both';
      NO_IO_CHECK='Both';
      NO_ASSERT_CHECK='TRUE';
      NO_DIR_CHECK='TRUE';
      ALLOW_CONNECT='TRUE';
    'VSS195':
      PIN_NUMBER='(0,0,0,0,0,0,0,0,0,0,0,0,0,0,0,0,0,0,0,0,0,0,0,0,0,0,0,0,0,0,0,0,0,0,0,0,0,0,AJ78,0,0,0)';
      PINUSE='POWER';
      NO_LOAD_CHECK='Both';
      NO_IO_CHECK='Both';
      NO_ASSERT_CHECK='TRUE';
      NO_DIR_CHECK='TRUE';
      ALLOW_CONNECT='TRUE';
    'VSS194':
      PIN_NUMBER='(0,0,0,0,0,0,0,0,0,0,0,0,0,0,0,0,0,0,0,0,0,0,0,0,0,0,0,0,0,0,0,0,0,0,0,0,0,0,AJ74,0,0,0)';
      PINUSE='POWER';
      NO_LOAD_CHECK='Both';
      NO_IO_CHECK='Both';
      NO_ASSERT_CHECK='TRUE';
      NO_DIR_CHECK='TRUE';
      ALLOW_CONNECT='TRUE';
    'VSS193':
      PIN_NUMBER='(0,0,0,0,0,0,0,0,0,0,0,0,0,0,0,0,0,0,0,0,0,0,0,0,0,0,0,0,0,0,0,0,0,0,0,0,0,0,AJ72,0,0,0)';
      PINUSE='POWER';
      NO_LOAD_CHECK='Both';
      NO_IO_CHECK='Both';
      NO_ASSERT_CHECK='TRUE';
      NO_DIR_CHECK='TRUE';
      ALLOW_CONNECT='TRUE';
    'VSS192':
      PIN_NUMBER='(0,0,0,0,0,0,0,0,0,0,0,0,0,0,0,0,0,0,0,0,0,0,0,0,0,0,0,0,0,0,0,0,0,0,0,0,0,0,AJ68,0,0,0)';
      PINUSE='POWER';
      NO_LOAD_CHECK='Both';
      NO_IO_CHECK='Both';
      NO_ASSERT_CHECK='TRUE';
      NO_DIR_CHECK='TRUE';
      ALLOW_CONNECT='TRUE';
    'VSS191':
      PIN_NUMBER='(0,0,0,0,0,0,0,0,0,0,0,0,0,0,0,0,0,0,0,0,0,0,0,0,0,0,0,0,0,0,0,0,0,0,0,0,0,0,AJ66,0,0,0)';
      PINUSE='POWER';
      NO_LOAD_CHECK='Both';
      NO_IO_CHECK='Both';
      NO_ASSERT_CHECK='TRUE';
      NO_DIR_CHECK='TRUE';
      ALLOW_CONNECT='TRUE';
    'VSS190':
      PIN_NUMBER='(0,0,0,0,0,0,0,0,0,0,0,0,0,0,0,0,0,0,0,0,0,0,0,0,0,0,0,0,0,0,0,0,0,0,0,0,0,0,AJ62,0,0,0)';
      PINUSE='POWER';
      NO_LOAD_CHECK='Both';
      NO_IO_CHECK='Both';
      NO_ASSERT_CHECK='TRUE';
      NO_DIR_CHECK='TRUE';
      ALLOW_CONNECT='TRUE';
    'VSS189':
      PIN_NUMBER='(0,0,0,0,0,0,0,0,0,0,0,0,0,0,0,0,0,0,0,0,0,0,0,0,0,0,0,0,0,0,0,0,0,0,0,0,0,0,AJ60,0,0,0)';
      PINUSE='POWER';
      NO_LOAD_CHECK='Both';
      NO_IO_CHECK='Both';
      NO_ASSERT_CHECK='TRUE';
      NO_DIR_CHECK='TRUE';
      ALLOW_CONNECT='TRUE';
    'VSS188':
      PIN_NUMBER='(0,0,0,0,0,0,0,0,0,0,0,0,0,0,0,0,0,0,0,0,0,0,0,0,0,0,0,0,0,0,0,0,0,0,0,0,0,0,AJ56,0,0,0)';
      PINUSE='POWER';
      NO_LOAD_CHECK='Both';
      NO_IO_CHECK='Both';
      NO_ASSERT_CHECK='TRUE';
      NO_DIR_CHECK='TRUE';
      ALLOW_CONNECT='TRUE';
    'VSS187':
      PIN_NUMBER='(0,0,0,0,0,0,0,0,0,0,0,0,0,0,0,0,0,0,0,0,0,0,0,0,0,0,0,0,0,0,0,0,0,0,0,0,0,0,AJ54,0,0,0)';
      PINUSE='POWER';
      NO_LOAD_CHECK='Both';
      NO_IO_CHECK='Both';
      NO_ASSERT_CHECK='TRUE';
      NO_DIR_CHECK='TRUE';
      ALLOW_CONNECT='TRUE';
    'VSS186':
      PIN_NUMBER='(0,0,0,0,0,0,0,0,0,0,0,0,0,0,0,0,0,0,0,0,0,0,0,0,0,0,0,0,0,0,0,0,0,0,0,0,0,0,AJ50,0,0,0)';
      PINUSE='POWER';
      NO_LOAD_CHECK='Both';
      NO_IO_CHECK='Both';
      NO_ASSERT_CHECK='TRUE';
      NO_DIR_CHECK='TRUE';
      ALLOW_CONNECT='TRUE';
    'VSS185':
      PIN_NUMBER='(0,0,0,0,0,0,0,0,0,0,0,0,0,0,0,0,0,0,0,0,0,0,0,0,0,0,0,0,0,0,0,0,0,0,0,0,0,0,AJ48,0,0,0)';
      PINUSE='POWER';
      NO_LOAD_CHECK='Both';
      NO_IO_CHECK='Both';
      NO_ASSERT_CHECK='TRUE';
      NO_DIR_CHECK='TRUE';
      ALLOW_CONNECT='TRUE';
    'VSS184':
      PIN_NUMBER='(0,0,0,0,0,0,0,0,0,0,0,0,0,0,0,0,0,0,0,0,0,0,0,0,0,0,0,0,0,0,0,0,0,0,0,0,0,0,AJ43,0,0,0)';
      PINUSE='POWER';
      NO_LOAD_CHECK='Both';
      NO_IO_CHECK='Both';
      NO_ASSERT_CHECK='TRUE';
      NO_DIR_CHECK='TRUE';
      ALLOW_CONNECT='TRUE';
    'VSS183':
      PIN_NUMBER='(0,0,0,0,0,0,0,0,0,0,0,0,0,0,0,0,0,0,0,0,0,0,0,0,0,0,0,0,0,0,0,0,0,0,0,0,0,0,AJ41,0,0,0)';
      PINUSE='POWER';
      NO_LOAD_CHECK='Both';
      NO_IO_CHECK='Both';
      NO_ASSERT_CHECK='TRUE';
      NO_DIR_CHECK='TRUE';
      ALLOW_CONNECT='TRUE';
    'VSS182':
      PIN_NUMBER='(0,0,0,0,0,0,0,0,0,0,0,0,0,0,0,0,0,0,0,0,0,0,0,0,0,0,0,0,0,0,0,0,0,0,0,0,0,0,AJ37,0,0,0)';
      PINUSE='POWER';
      NO_LOAD_CHECK='Both';
      NO_IO_CHECK='Both';
      NO_ASSERT_CHECK='TRUE';
      NO_DIR_CHECK='TRUE';
      ALLOW_CONNECT='TRUE';
    'VSS181':
      PIN_NUMBER='(0,0,0,0,0,0,0,0,0,0,0,0,0,0,0,0,0,0,0,0,0,0,0,0,0,0,0,0,0,0,0,0,0,0,0,0,0,0,AJ35,0,0,0)';
      PINUSE='POWER';
      NO_LOAD_CHECK='Both';
      NO_IO_CHECK='Both';
      NO_ASSERT_CHECK='TRUE';
      NO_DIR_CHECK='TRUE';
      ALLOW_CONNECT='TRUE';
    'VSS180':
      PIN_NUMBER='(0,0,0,0,0,0,0,0,0,0,0,0,0,0,0,0,0,0,0,0,0,0,0,0,0,0,0,0,0,0,0,0,0,0,0,0,0,0,AJ31,0,0,0)';
      PINUSE='POWER';
      NO_LOAD_CHECK='Both';
      NO_IO_CHECK='Both';
      NO_ASSERT_CHECK='TRUE';
      NO_DIR_CHECK='TRUE';
      ALLOW_CONNECT='TRUE';
    'VSS179':
      PIN_NUMBER='(0,0,0,0,0,0,0,0,0,0,0,0,0,0,0,0,0,0,0,0,0,0,0,0,0,0,0,0,0,0,0,0,0,0,0,0,0,0,AJ29,0,0,0)';
      PINUSE='POWER';
      NO_LOAD_CHECK='Both';
      NO_IO_CHECK='Both';
      NO_ASSERT_CHECK='TRUE';
      NO_DIR_CHECK='TRUE';
      ALLOW_CONNECT='TRUE';
    'VSS178':
      PIN_NUMBER='(0,0,0,0,0,0,0,0,0,0,0,0,0,0,0,0,0,0,0,0,0,0,0,0,0,0,0,0,0,0,0,0,0,0,0,0,0,0,AJ25,0,0,0)';
      PINUSE='POWER';
      NO_LOAD_CHECK='Both';
      NO_IO_CHECK='Both';
      NO_ASSERT_CHECK='TRUE';
      NO_DIR_CHECK='TRUE';
      ALLOW_CONNECT='TRUE';
    'VSS177':
      PIN_NUMBER='(0,0,0,0,0,0,0,0,0,0,0,0,0,0,0,0,0,0,0,0,0,0,0,0,0,0,0,0,0,0,0,0,0,0,0,0,0,0,AJ23,0,0,0)';
      PINUSE='POWER';
      NO_LOAD_CHECK='Both';
      NO_IO_CHECK='Both';
      NO_ASSERT_CHECK='TRUE';
      NO_DIR_CHECK='TRUE';
      ALLOW_CONNECT='TRUE';
    'VSS176':
      PIN_NUMBER='(0,0,0,0,0,0,0,0,0,0,0,0,0,0,0,0,0,0,0,0,0,0,0,0,0,0,0,0,0,0,0,0,0,0,0,0,0,0,AJ19,0,0,0)';
      PINUSE='POWER';
      NO_LOAD_CHECK='Both';
      NO_IO_CHECK='Both';
      NO_ASSERT_CHECK='TRUE';
      NO_DIR_CHECK='TRUE';
      ALLOW_CONNECT='TRUE';
    'VSS175':
      PIN_NUMBER='(0,0,0,0,0,0,0,0,0,0,0,0,0,0,0,0,0,0,0,0,0,0,0,0,0,0,0,0,0,0,0,0,0,0,0,0,0,0,AH83,0,0,0)';
      PINUSE='POWER';
      NO_LOAD_CHECK='Both';
      NO_IO_CHECK='Both';
      NO_ASSERT_CHECK='TRUE';
      NO_DIR_CHECK='TRUE';
      ALLOW_CONNECT='TRUE';
    'VSS174':
      PIN_NUMBER='(0,0,0,0,0,0,0,0,0,0,0,0,0,0,0,0,0,0,0,0,0,0,0,0,0,0,0,0,0,0,0,0,0,0,0,0,0,0,AH8,0,0,0)';
      PINUSE='POWER';
      NO_LOAD_CHECK='Both';
      NO_IO_CHECK='Both';
      NO_ASSERT_CHECK='TRUE';
      NO_DIR_CHECK='TRUE';
      ALLOW_CONNECT='TRUE';
    'VSS173':
      PIN_NUMBER='(0,0,0,0,0,0,0,0,0,0,0,0,0,0,0,0,0,0,0,0,0,0,0,0,0,0,0,0,0,0,0,0,0,0,0,0,0,0,AH79,0,0,0)';
      PINUSE='POWER';
      NO_LOAD_CHECK='Both';
      NO_IO_CHECK='Both';
      NO_ASSERT_CHECK='TRUE';
      NO_DIR_CHECK='TRUE';
      ALLOW_CONNECT='TRUE';
    'VSS172':
      PIN_NUMBER='(0,0,0,0,0,0,0,0,0,0,0,0,0,0,0,0,0,0,0,0,0,0,0,0,0,0,0,0,0,0,0,0,0,0,0,0,0,0,AH77,0,0,0)';
      PINUSE='POWER';
      NO_LOAD_CHECK='Both';
      NO_IO_CHECK='Both';
      NO_ASSERT_CHECK='TRUE';
      NO_DIR_CHECK='TRUE';
      ALLOW_CONNECT='TRUE';
    'VSS171':
      PIN_NUMBER='(0,0,0,0,0,0,0,0,0,0,0,0,0,0,0,0,0,0,0,0,0,0,0,0,0,0,0,0,0,0,0,0,0,0,0,0,0,0,AH75,0,0,0)';
      PINUSE='POWER';
      NO_LOAD_CHECK='Both';
      NO_IO_CHECK='Both';
      NO_ASSERT_CHECK='TRUE';
      NO_DIR_CHECK='TRUE';
      ALLOW_CONNECT='TRUE';
    'VSS170':
      PIN_NUMBER='(0,0,0,0,0,0,0,0,0,0,0,0,0,0,0,0,0,0,0,0,0,0,0,0,0,0,0,0,0,0,0,0,0,0,0,0,0,0,AH71,0,0,0)';
      PINUSE='POWER';
      NO_LOAD_CHECK='Both';
      NO_IO_CHECK='Both';
      NO_ASSERT_CHECK='TRUE';
      NO_DIR_CHECK='TRUE';
      ALLOW_CONNECT='TRUE';
    'VSS169':
      PIN_NUMBER='(0,0,0,0,0,0,0,0,0,0,0,0,0,0,0,0,0,0,0,0,0,0,0,0,0,0,0,0,0,0,0,0,0,0,0,0,0,0,AH69,0,0,0)';
      PINUSE='POWER';
      NO_LOAD_CHECK='Both';
      NO_IO_CHECK='Both';
      NO_ASSERT_CHECK='TRUE';
      NO_DIR_CHECK='TRUE';
      ALLOW_CONNECT='TRUE';
    'VSS168':
      PIN_NUMBER='(0,0,0,0,0,0,0,0,0,0,0,0,0,0,0,0,0,0,0,0,0,0,0,0,0,0,0,0,0,0,0,0,0,0,0,0,0,0,AH65,0,0,0)';
      PINUSE='POWER';
      NO_LOAD_CHECK='Both';
      NO_IO_CHECK='Both';
      NO_ASSERT_CHECK='TRUE';
      NO_DIR_CHECK='TRUE';
      ALLOW_CONNECT='TRUE';
    'VSS167':
      PIN_NUMBER='(0,0,0,0,0,0,0,0,0,0,0,0,0,0,0,0,0,0,0,0,0,0,0,0,0,0,0,0,0,0,0,0,0,0,0,0,0,0,AH63,0,0,0)';
      PINUSE='POWER';
      NO_LOAD_CHECK='Both';
      NO_IO_CHECK='Both';
      NO_ASSERT_CHECK='TRUE';
      NO_DIR_CHECK='TRUE';
      ALLOW_CONNECT='TRUE';
    'VSS166':
      PIN_NUMBER='(0,0,0,0,0,0,0,0,0,0,0,0,0,0,0,0,0,0,0,0,0,0,0,0,0,0,0,0,0,0,0,0,0,0,0,0,0,0,AH59,0,0,0)';
      PINUSE='POWER';
      NO_LOAD_CHECK='Both';
      NO_IO_CHECK='Both';
      NO_ASSERT_CHECK='TRUE';
      NO_DIR_CHECK='TRUE';
      ALLOW_CONNECT='TRUE';
    'VSS165':
      PIN_NUMBER='(0,0,0,0,0,0,0,0,0,0,0,0,0,0,0,0,0,0,0,0,0,0,0,0,0,0,0,0,0,0,0,0,0,0,0,0,0,0,AH57,0,0,0)';
      PINUSE='POWER';
      NO_LOAD_CHECK='Both';
      NO_IO_CHECK='Both';
      NO_ASSERT_CHECK='TRUE';
      NO_DIR_CHECK='TRUE';
      ALLOW_CONNECT='TRUE';
    'VSS164':
      PIN_NUMBER='(0,0,0,0,0,0,0,0,0,0,0,0,0,0,0,0,0,0,0,0,0,0,0,0,0,0,0,0,0,0,0,0,0,0,0,0,0,0,AH53,0,0,0)';
      PINUSE='POWER';
      NO_LOAD_CHECK='Both';
      NO_IO_CHECK='Both';
      NO_ASSERT_CHECK='TRUE';
      NO_DIR_CHECK='TRUE';
      ALLOW_CONNECT='TRUE';
    'VSS163':
      PIN_NUMBER='(0,0,0,0,0,0,0,0,0,0,0,0,0,0,0,0,0,0,0,0,0,0,0,0,0,0,0,0,0,0,0,0,0,0,0,0,0,0,AH51,0,0,0)';
      PINUSE='POWER';
      NO_LOAD_CHECK='Both';
      NO_IO_CHECK='Both';
      NO_ASSERT_CHECK='TRUE';
      NO_DIR_CHECK='TRUE';
      ALLOW_CONNECT='TRUE';
    'VSS162':
      PIN_NUMBER='(0,0,0,0,0,0,0,0,0,0,0,0,0,0,0,0,0,0,0,0,0,0,0,0,0,0,0,0,0,0,0,0,0,0,0,0,0,0,AH47,0,0,0)';
      PINUSE='POWER';
      NO_LOAD_CHECK='Both';
      NO_IO_CHECK='Both';
      NO_ASSERT_CHECK='TRUE';
      NO_DIR_CHECK='TRUE';
      ALLOW_CONNECT='TRUE';
    'VSS161':
      PIN_NUMBER='(0,0,0,0,0,0,0,0,0,0,0,0,0,0,0,0,0,0,0,0,0,0,0,0,0,0,0,0,0,0,0,0,0,0,0,0,0,0,AH44,0,0,0)';
      PINUSE='POWER';
      NO_LOAD_CHECK='Both';
      NO_IO_CHECK='Both';
      NO_ASSERT_CHECK='TRUE';
      NO_DIR_CHECK='TRUE';
      ALLOW_CONNECT='TRUE';
    'VSS160':
      PIN_NUMBER='(0,0,0,0,0,0,0,0,0,0,0,0,0,0,0,0,0,0,0,0,0,0,0,0,0,0,0,0,0,0,0,0,0,0,0,0,0,0,AH40,0,0,0)';
      PINUSE='POWER';
      NO_LOAD_CHECK='Both';
      NO_IO_CHECK='Both';
      NO_ASSERT_CHECK='TRUE';
      NO_DIR_CHECK='TRUE';
      ALLOW_CONNECT='TRUE';
    'VSS159':
      PIN_NUMBER='(0,0,0,0,0,0,0,0,0,0,0,0,0,0,0,0,0,0,0,0,0,0,0,0,0,0,0,0,0,0,0,0,0,0,0,0,0,0,AH4,0,0,0)';
      PINUSE='POWER';
      NO_LOAD_CHECK='Both';
      NO_IO_CHECK='Both';
      NO_ASSERT_CHECK='TRUE';
      NO_DIR_CHECK='TRUE';
      ALLOW_CONNECT='TRUE';
    'VSS158':
      PIN_NUMBER='(0,0,0,0,0,0,0,0,0,0,0,0,0,0,0,0,0,0,0,0,0,0,0,0,0,0,0,0,0,0,0,0,0,0,0,0,0,0,AH38,0,0,0)';
      PINUSE='POWER';
      NO_LOAD_CHECK='Both';
      NO_IO_CHECK='Both';
      NO_ASSERT_CHECK='TRUE';
      NO_DIR_CHECK='TRUE';
      ALLOW_CONNECT='TRUE';
    'VSS157':
      PIN_NUMBER='(0,0,0,0,0,0,0,0,0,0,0,0,0,0,0,0,0,0,0,0,0,0,0,0,0,0,0,0,0,0,0,0,0,0,0,0,0,0,AH34,0,0,0)';
      PINUSE='POWER';
      NO_LOAD_CHECK='Both';
      NO_IO_CHECK='Both';
      NO_ASSERT_CHECK='TRUE';
      NO_DIR_CHECK='TRUE';
      ALLOW_CONNECT='TRUE';
    'VSS156':
      PIN_NUMBER='(0,0,0,0,0,0,0,0,0,0,0,0,0,0,0,0,0,0,0,0,0,0,0,0,0,0,0,0,0,0,0,0,0,0,0,0,0,0,AH32,0,0,0)';
      PINUSE='POWER';
      NO_LOAD_CHECK='Both';
      NO_IO_CHECK='Both';
      NO_ASSERT_CHECK='TRUE';
      NO_DIR_CHECK='TRUE';
      ALLOW_CONNECT='TRUE';
    'VSS155':
      PIN_NUMBER='(0,0,0,0,0,0,0,0,0,0,0,0,0,0,0,0,0,0,0,0,0,0,0,0,0,0,0,0,0,0,0,0,0,0,0,0,0,0,AH28,0,0,0)';
      PINUSE='POWER';
      NO_LOAD_CHECK='Both';
      NO_IO_CHECK='Both';
      NO_ASSERT_CHECK='TRUE';
      NO_DIR_CHECK='TRUE';
      ALLOW_CONNECT='TRUE';
    'VSS154':
      PIN_NUMBER='(0,0,0,0,0,0,0,0,0,0,0,0,0,0,0,0,0,0,0,0,0,0,0,0,0,0,0,0,0,0,0,0,0,0,0,0,0,0,AH26,0,0,0)';
      PINUSE='POWER';
      NO_LOAD_CHECK='Both';
      NO_IO_CHECK='Both';
      NO_ASSERT_CHECK='TRUE';
      NO_DIR_CHECK='TRUE';
      ALLOW_CONNECT='TRUE';
    'VSS153':
      PIN_NUMBER='(0,0,0,0,0,0,0,0,0,0,0,0,0,0,0,0,0,0,0,0,0,0,0,0,0,0,0,0,0,0,0,0,0,0,0,0,0,0,AH22,0,0,0)';
      PINUSE='POWER';
      NO_LOAD_CHECK='Both';
      NO_IO_CHECK='Both';
      NO_ASSERT_CHECK='TRUE';
      NO_DIR_CHECK='TRUE';
      ALLOW_CONNECT='TRUE';
    'VSS152':
      PIN_NUMBER='(0,0,0,0,0,0,0,0,0,0,0,0,0,0,0,0,0,0,0,0,0,0,0,0,0,0,0,0,0,0,0,0,0,0,0,0,0,0,AH20,0,0,0)';
      PINUSE='POWER';
      NO_LOAD_CHECK='Both';
      NO_IO_CHECK='Both';
      NO_ASSERT_CHECK='TRUE';
      NO_DIR_CHECK='TRUE';
      ALLOW_CONNECT='TRUE';
    'VSS151':
      PIN_NUMBER='(0,0,0,0,0,0,0,0,0,0,0,0,0,0,0,0,0,0,0,0,0,0,0,0,0,0,0,0,0,0,0,0,0,0,0,0,0,0,AH16,0,0,0)';
      PINUSE='POWER';
      NO_LOAD_CHECK='Both';
      NO_IO_CHECK='Both';
      NO_ASSERT_CHECK='TRUE';
      NO_DIR_CHECK='TRUE';
      ALLOW_CONNECT='TRUE';
    'VSS150':
      PIN_NUMBER='(0,0,0,0,0,0,0,0,0,0,0,0,0,0,0,0,0,0,0,0,0,0,0,0,0,0,0,0,0,0,0,0,0,0,0,0,0,0,AH12,0,0,0)';
      PINUSE='POWER';
      NO_LOAD_CHECK='Both';
      NO_IO_CHECK='Both';
      NO_ASSERT_CHECK='TRUE';
      NO_DIR_CHECK='TRUE';
      ALLOW_CONNECT='TRUE';
    'VSS149':
      PIN_NUMBER='(0,0,0,0,0,0,0,0,0,0,0,0,0,0,0,0,0,0,0,0,0,0,0,0,0,0,0,0,0,0,0,0,0,0,0,0,0,0,AG9,0,0,0)';
      PINUSE='POWER';
      NO_LOAD_CHECK='Both';
      NO_IO_CHECK='Both';
      NO_ASSERT_CHECK='TRUE';
      NO_DIR_CHECK='TRUE';
      ALLOW_CONNECT='TRUE';
    'VSS148':
      PIN_NUMBER='(0,0,0,0,0,0,0,0,0,0,0,0,0,0,0,0,0,0,0,0,0,0,0,0,0,0,0,0,0,0,0,0,0,0,0,0,0,0,AG88,0,0,0)';
      PINUSE='POWER';
      NO_LOAD_CHECK='Both';
      NO_IO_CHECK='Both';
      NO_ASSERT_CHECK='TRUE';
      NO_DIR_CHECK='TRUE';
      ALLOW_CONNECT='TRUE';
    'VSS147':
      PIN_NUMBER='(0,0,0,0,0,0,0,0,0,0,0,0,0,0,0,0,0,0,0,0,0,0,0,0,0,0,0,0,0,0,0,0,0,0,0,0,0,0,AG84,0,0,0)';
      PINUSE='POWER';
      NO_LOAD_CHECK='Both';
      NO_IO_CHECK='Both';
      NO_ASSERT_CHECK='TRUE';
      NO_DIR_CHECK='TRUE';
      ALLOW_CONNECT='TRUE';
    'VSS146':
      PIN_NUMBER='(0,0,0,0,0,0,0,0,0,0,0,0,0,0,0,0,0,0,0,0,0,0,0,0,0,0,0,0,0,0,0,0,0,0,0,0,0,0,AG76,0,0,0)';
      PINUSE='POWER';
      NO_LOAD_CHECK='Both';
      NO_IO_CHECK='Both';
      NO_ASSERT_CHECK='TRUE';
      NO_DIR_CHECK='TRUE';
      ALLOW_CONNECT='TRUE';
    'VSS145':
      PIN_NUMBER='(0,0,0,0,0,0,0,0,0,0,0,0,0,0,0,0,0,0,0,0,0,0,0,0,0,0,0,0,0,0,0,0,0,0,0,0,0,0,AG70,0,0,0)';
      PINUSE='POWER';
      NO_LOAD_CHECK='Both';
      NO_IO_CHECK='Both';
      NO_ASSERT_CHECK='TRUE';
      NO_DIR_CHECK='TRUE';
      ALLOW_CONNECT='TRUE';
    'VSS144':
      PIN_NUMBER='(0,0,0,0,0,0,0,0,0,0,0,0,0,0,0,0,0,0,0,0,0,0,0,0,0,0,0,0,0,0,0,0,0,0,0,0,0,0,AG64,0,0,0)';
      PINUSE='POWER';
      NO_LOAD_CHECK='Both';
      NO_IO_CHECK='Both';
      NO_ASSERT_CHECK='TRUE';
      NO_DIR_CHECK='TRUE';
      ALLOW_CONNECT='TRUE';
    'VSS143':
      PIN_NUMBER='(0,0,0,0,0,0,0,0,0,0,0,0,0,0,0,0,0,0,0,0,0,0,0,0,0,0,0,0,0,0,0,0,0,0,0,0,0,0,AG58,0,0,0)';
      PINUSE='POWER';
      NO_LOAD_CHECK='Both';
      NO_IO_CHECK='Both';
      NO_ASSERT_CHECK='TRUE';
      NO_DIR_CHECK='TRUE';
      ALLOW_CONNECT='TRUE';
    'VSS142':
      PIN_NUMBER='(0,0,0,0,0,0,0,0,0,0,0,0,0,0,0,0,0,0,0,0,0,0,0,0,0,0,0,0,0,0,0,0,0,0,0,0,0,0,AG52,0,0,0)';
      PINUSE='POWER';
      NO_LOAD_CHECK='Both';
      NO_IO_CHECK='Both';
      NO_ASSERT_CHECK='TRUE';
      NO_DIR_CHECK='TRUE';
      ALLOW_CONNECT='TRUE';
    'VSS141':
      PIN_NUMBER='(0,0,0,0,0,0,0,0,0,0,0,0,0,0,0,0,0,0,0,0,0,0,0,0,0,0,0,0,0,0,0,0,0,0,0,0,0,0,AG5,0,0,0)';
      PINUSE='POWER';
      NO_LOAD_CHECK='Both';
      NO_IO_CHECK='Both';
      NO_ASSERT_CHECK='TRUE';
      NO_DIR_CHECK='TRUE';
      ALLOW_CONNECT='TRUE';
    'VSS140':
      PIN_NUMBER='(0,0,0,0,0,0,0,0,0,0,0,0,0,0,0,0,0,0,0,0,0,0,0,0,0,0,0,0,0,0,0,0,0,0,0,0,0,0,AG45,0,0,0)';
      PINUSE='POWER';
      NO_LOAD_CHECK='Both';
      NO_IO_CHECK='Both';
      NO_ASSERT_CHECK='TRUE';
      NO_DIR_CHECK='TRUE';
      ALLOW_CONNECT='TRUE';
    'VSS139':
      PIN_NUMBER='(0,0,0,0,0,0,0,0,0,0,0,0,0,0,0,0,0,0,0,0,0,0,0,0,0,0,0,0,0,0,0,0,0,0,0,0,0,0,AG39,0,0,0)';
      PINUSE='POWER';
      NO_LOAD_CHECK='Both';
      NO_IO_CHECK='Both';
      NO_ASSERT_CHECK='TRUE';
      NO_DIR_CHECK='TRUE';
      ALLOW_CONNECT='TRUE';
    'VSS138':
      PIN_NUMBER='(0,0,0,0,0,0,0,0,0,0,0,0,0,0,0,0,0,0,0,0,0,0,0,0,0,0,0,0,0,0,0,0,0,0,0,0,0,0,AG33,0,0,0)';
      PINUSE='POWER';
      NO_LOAD_CHECK='Both';
      NO_IO_CHECK='Both';
      NO_ASSERT_CHECK='TRUE';
      NO_DIR_CHECK='TRUE';
      ALLOW_CONNECT='TRUE';
    'VSS137':
      PIN_NUMBER='(0,0,0,0,0,0,0,0,0,0,0,0,0,0,0,0,0,0,0,0,0,0,0,0,0,0,0,0,0,0,0,0,0,0,0,0,0,0,AG27,0,0,0)';
      PINUSE='POWER';
      NO_LOAD_CHECK='Both';
      NO_IO_CHECK='Both';
      NO_ASSERT_CHECK='TRUE';
      NO_DIR_CHECK='TRUE';
      ALLOW_CONNECT='TRUE';
    'VSS136':
      PIN_NUMBER='(0,0,0,0,0,0,0,0,0,0,0,0,0,0,0,0,0,0,0,0,0,0,0,0,0,0,0,0,0,0,0,0,0,0,0,0,0,0,AG21,0,0,0)';
      PINUSE='POWER';
      NO_LOAD_CHECK='Both';
      NO_IO_CHECK='Both';
      NO_ASSERT_CHECK='TRUE';
      NO_DIR_CHECK='TRUE';
      ALLOW_CONNECT='TRUE';
    'VSS135':
      PIN_NUMBER='(0,0,0,0,0,0,0,0,0,0,0,0,0,0,0,0,0,0,0,0,0,0,0,0,0,0,0,0,0,0,0,0,0,0,0,0,0,0,AG13,0,0,0)';
      PINUSE='POWER';
      NO_LOAD_CHECK='Both';
      NO_IO_CHECK='Both';
      NO_ASSERT_CHECK='TRUE';
      NO_DIR_CHECK='TRUE';
      ALLOW_CONNECT='TRUE';
    'VSS134':
      PIN_NUMBER='(0,0,0,0,0,0,0,0,0,0,0,0,0,0,0,0,0,0,0,0,0,0,0,0,0,0,0,0,0,0,0,0,0,0,0,0,0,0,AG1,0,0,0)';
      PINUSE='POWER';
      NO_LOAD_CHECK='Both';
      NO_IO_CHECK='Both';
      NO_ASSERT_CHECK='TRUE';
      NO_DIR_CHECK='TRUE';
      ALLOW_CONNECT='TRUE';
    'VSS133':
      PIN_NUMBER='(0,0,0,0,0,0,0,0,0,0,0,0,0,0,0,0,0,0,0,0,0,0,0,0,0,0,0,0,0,0,0,0,0,0,0,0,0,0,AF91,0,0,0)';
      PINUSE='POWER';
      NO_LOAD_CHECK='Both';
      NO_IO_CHECK='Both';
      NO_ASSERT_CHECK='TRUE';
      NO_DIR_CHECK='TRUE';
      ALLOW_CONNECT='TRUE';
    'VSS132':
      PIN_NUMBER='(0,0,0,0,0,0,0,0,0,0,0,0,0,0,0,0,0,0,0,0,0,0,0,0,0,0,0,0,0,0,0,0,0,0,0,0,0,0,AF87,0,0,0)';
      PINUSE='POWER';
      NO_LOAD_CHECK='Both';
      NO_IO_CHECK='Both';
      NO_ASSERT_CHECK='TRUE';
      NO_DIR_CHECK='TRUE';
      ALLOW_CONNECT='TRUE';
    'VSS131':
      PIN_NUMBER='(0,0,0,0,0,0,0,0,0,0,0,0,0,0,0,0,0,0,0,0,0,0,0,0,0,0,0,0,0,0,0,0,0,0,0,0,0,0,AF81,0,0,0)';
      PINUSE='POWER';
      NO_LOAD_CHECK='Both';
      NO_IO_CHECK='Both';
      NO_ASSERT_CHECK='TRUE';
      NO_DIR_CHECK='TRUE';
      ALLOW_CONNECT='TRUE';
    'VSS130':
      PIN_NUMBER='(0,0,0,0,0,0,0,0,0,0,0,0,0,0,0,0,0,0,0,0,0,0,0,0,0,0,0,0,0,0,0,0,0,0,0,0,0,0,AF8,0,0,0)';
      PINUSE='POWER';
      NO_LOAD_CHECK='Both';
      NO_IO_CHECK='Both';
      NO_ASSERT_CHECK='TRUE';
      NO_DIR_CHECK='TRUE';
      ALLOW_CONNECT='TRUE';
    'VSS129':
      PIN_NUMBER='(0,0,0,0,0,0,0,0,0,0,0,0,0,0,0,0,0,0,0,0,0,0,0,0,0,0,0,0,0,0,0,0,0,0,0,0,0,0,AF42,0,0,0)';
      PINUSE='POWER';
      NO_LOAD_CHECK='Both';
      NO_IO_CHECK='Both';
      NO_ASSERT_CHECK='TRUE';
      NO_DIR_CHECK='TRUE';
      ALLOW_CONNECT='TRUE';
    'VSS128':
      PIN_NUMBER='(0,0,0,0,0,0,0,0,0,0,0,0,0,0,0,0,0,0,0,0,0,0,0,0,0,0,0,0,0,0,0,0,0,0,0,0,0,0,AF4,0,0,0)';
      PINUSE='POWER';
      NO_LOAD_CHECK='Both';
      NO_IO_CHECK='Both';
      NO_ASSERT_CHECK='TRUE';
      NO_DIR_CHECK='TRUE';
      ALLOW_CONNECT='TRUE';
    'VSS127':
      PIN_NUMBER='(0,0,0,0,0,0,0,0,0,0,0,0,0,0,0,0,0,0,0,0,0,0,0,0,0,0,0,0,0,0,0,0,0,0,0,0,0,0,AF16,0,0,0)';
      PINUSE='POWER';
      NO_LOAD_CHECK='Both';
      NO_IO_CHECK='Both';
      NO_ASSERT_CHECK='TRUE';
      NO_DIR_CHECK='TRUE';
      ALLOW_CONNECT='TRUE';
    'VSS126':
      PIN_NUMBER='(0,0,0,0,0,0,0,0,0,0,0,0,0,0,0,0,0,0,0,0,0,0,0,0,0,0,0,0,0,0,0,0,0,0,0,0,0,0,AF12,0,0,0)';
      PINUSE='POWER';
      NO_LOAD_CHECK='Both';
      NO_IO_CHECK='Both';
      NO_ASSERT_CHECK='TRUE';
      NO_DIR_CHECK='TRUE';
      ALLOW_CONNECT='TRUE';
    'VSS125':
      PIN_NUMBER='(0,0,0,0,0,0,0,0,0,0,0,0,0,0,0,0,0,0,0,0,0,0,0,0,0,0,0,0,0,0,0,0,0,0,0,0,0,0,AE88,0,0,0)';
      PINUSE='POWER';
      NO_LOAD_CHECK='Both';
      NO_IO_CHECK='Both';
      NO_ASSERT_CHECK='TRUE';
      NO_DIR_CHECK='TRUE';
      ALLOW_CONNECT='TRUE';
    'VSS124':
      PIN_NUMBER='(0,0,0,0,0,0,0,0,0,0,0,0,0,0,0,0,0,0,0,0,0,0,0,0,0,0,0,0,0,0,0,0,0,0,0,0,0,0,AE84,0,0,0)';
      PINUSE='POWER';
      NO_LOAD_CHECK='Both';
      NO_IO_CHECK='Both';
      NO_ASSERT_CHECK='TRUE';
      NO_DIR_CHECK='TRUE';
      ALLOW_CONNECT='TRUE';
    'VSS123':
      PIN_NUMBER='(0,0,0,0,0,0,0,0,0,0,0,0,0,0,0,0,0,0,0,0,0,0,0,0,0,0,0,0,0,0,0,0,0,0,0,0,0,0,AE78,0,0,0)';
      PINUSE='POWER';
      NO_LOAD_CHECK='Both';
      NO_IO_CHECK='Both';
      NO_ASSERT_CHECK='TRUE';
      NO_DIR_CHECK='TRUE';
      ALLOW_CONNECT='TRUE';
    'VSS122':
      PIN_NUMBER='(0,0,0,0,0,0,0,0,0,0,0,0,0,0,0,0,0,0,0,0,0,0,0,0,0,0,0,0,0,0,0,0,0,0,0,0,0,0,AE76,0,0,0)';
      PINUSE='POWER';
      NO_LOAD_CHECK='Both';
      NO_IO_CHECK='Both';
      NO_ASSERT_CHECK='TRUE';
      NO_DIR_CHECK='TRUE';
      ALLOW_CONNECT='TRUE';
    'VSS121':
      PIN_NUMBER='(0,0,0,0,0,0,0,0,0,0,0,0,0,0,0,0,0,0,0,0,0,0,0,0,0,0,0,0,0,0,0,0,0,0,0,0,0,0,AE74,0,0,0)';
      PINUSE='POWER';
      NO_LOAD_CHECK='Both';
      NO_IO_CHECK='Both';
      NO_ASSERT_CHECK='TRUE';
      NO_DIR_CHECK='TRUE';
      ALLOW_CONNECT='TRUE';
    'VSS120':
      PIN_NUMBER='(0,0,0,0,0,0,0,0,0,0,0,0,0,0,0,0,0,0,0,0,0,0,0,0,0,0,0,0,0,0,0,0,0,0,0,0,0,0,AE72,0,0,0)';
      PINUSE='POWER';
      NO_LOAD_CHECK='Both';
      NO_IO_CHECK='Both';
      NO_ASSERT_CHECK='TRUE';
      NO_DIR_CHECK='TRUE';
      ALLOW_CONNECT='TRUE';
    'VSS119':
      PIN_NUMBER='(0,0,0,0,0,0,0,0,0,0,0,0,0,0,0,0,0,0,0,0,0,0,0,0,0,0,0,0,0,0,0,0,0,0,0,0,0,0,AE70,0,0,0)';
      PINUSE='POWER';
      NO_LOAD_CHECK='Both';
      NO_IO_CHECK='Both';
      NO_ASSERT_CHECK='TRUE';
      NO_DIR_CHECK='TRUE';
      ALLOW_CONNECT='TRUE';
    'VSS118':
      PIN_NUMBER='(0,0,0,0,0,0,0,0,0,0,0,0,0,0,0,0,0,0,0,0,0,0,0,0,0,0,0,0,0,0,0,0,0,0,0,0,0,0,AE68,0,0,0)';
      PINUSE='POWER';
      NO_LOAD_CHECK='Both';
      NO_IO_CHECK='Both';
      NO_ASSERT_CHECK='TRUE';
      NO_DIR_CHECK='TRUE';
      ALLOW_CONNECT='TRUE';
    'VSS117':
      PIN_NUMBER='(0,0,0,0,0,0,0,0,0,0,0,0,0,0,0,0,0,0,0,0,0,0,0,0,0,0,0,0,0,0,0,0,0,0,0,0,0,0,AE66,0,0,0)';
      PINUSE='POWER';
      NO_LOAD_CHECK='Both';
      NO_IO_CHECK='Both';
      NO_ASSERT_CHECK='TRUE';
      NO_DIR_CHECK='TRUE';
      ALLOW_CONNECT='TRUE';
    'VSS116':
      PIN_NUMBER='(0,0,0,0,0,0,0,0,0,0,0,0,0,0,0,0,0,0,0,0,0,0,0,0,0,0,0,0,0,0,0,0,0,0,0,0,0,0,AE64,0,0,0)';
      PINUSE='POWER';
      NO_LOAD_CHECK='Both';
      NO_IO_CHECK='Both';
      NO_ASSERT_CHECK='TRUE';
      NO_DIR_CHECK='TRUE';
      ALLOW_CONNECT='TRUE';
    'VSS115':
      PIN_NUMBER='(0,0,0,0,0,0,0,0,0,0,0,0,0,0,0,0,0,0,0,0,0,0,0,0,0,0,0,0,0,0,0,0,0,0,0,0,0,0,AE62,0,0,0)';
      PINUSE='POWER';
      NO_LOAD_CHECK='Both';
      NO_IO_CHECK='Both';
      NO_ASSERT_CHECK='TRUE';
      NO_DIR_CHECK='TRUE';
      ALLOW_CONNECT='TRUE';
    'VSS114':
      PIN_NUMBER='(0,0,0,0,0,0,0,0,0,0,0,0,0,0,0,0,0,0,0,0,0,0,0,0,0,0,0,0,0,0,0,0,0,0,0,0,0,0,AE60,0,0,0)';
      PINUSE='POWER';
      NO_LOAD_CHECK='Both';
      NO_IO_CHECK='Both';
      NO_ASSERT_CHECK='TRUE';
      NO_DIR_CHECK='TRUE';
      ALLOW_CONNECT='TRUE';
    'VSS113':
      PIN_NUMBER='(0,0,0,0,0,0,0,0,0,0,0,0,0,0,0,0,0,0,0,0,0,0,0,0,0,0,0,0,0,0,0,0,0,0,0,0,0,0,AE58,0,0,0)';
      PINUSE='POWER';
      NO_LOAD_CHECK='Both';
      NO_IO_CHECK='Both';
      NO_ASSERT_CHECK='TRUE';
      NO_DIR_CHECK='TRUE';
      ALLOW_CONNECT='TRUE';
    'VSS112':
      PIN_NUMBER='(0,0,0,0,0,0,0,0,0,0,0,0,0,0,0,0,0,0,0,0,0,0,0,0,0,0,0,0,0,0,0,0,0,0,0,0,0,0,AE56,0,0,0)';
      PINUSE='POWER';
      NO_LOAD_CHECK='Both';
      NO_IO_CHECK='Both';
      NO_ASSERT_CHECK='TRUE';
      NO_DIR_CHECK='TRUE';
      ALLOW_CONNECT='TRUE';
    'VSS111':
      PIN_NUMBER='(0,0,0,0,0,0,0,0,0,0,0,0,0,0,0,0,0,0,0,0,0,0,0,0,0,0,0,0,0,0,0,0,0,0,0,0,0,0,AE54,0,0,0)';
      PINUSE='POWER';
      NO_LOAD_CHECK='Both';
      NO_IO_CHECK='Both';
      NO_ASSERT_CHECK='TRUE';
      NO_DIR_CHECK='TRUE';
      ALLOW_CONNECT='TRUE';
    'VSS110':
      PIN_NUMBER='(0,0,0,0,0,0,0,0,0,0,0,0,0,0,0,0,0,0,0,0,0,0,0,0,0,0,0,0,0,0,0,0,0,0,0,0,0,0,AE52,0,0,0)';
      PINUSE='POWER';
      NO_LOAD_CHECK='Both';
      NO_IO_CHECK='Both';
      NO_ASSERT_CHECK='TRUE';
      NO_DIR_CHECK='TRUE';
      ALLOW_CONNECT='TRUE';
    'VSS109':
      PIN_NUMBER='(0,0,0,0,0,0,0,0,0,0,0,0,0,0,0,0,0,0,0,0,0,0,0,0,0,0,0,0,0,0,0,0,0,0,0,0,0,0,AE50,0,0,0)';
      PINUSE='POWER';
      NO_LOAD_CHECK='Both';
      NO_IO_CHECK='Both';
      NO_ASSERT_CHECK='TRUE';
      NO_DIR_CHECK='TRUE';
      ALLOW_CONNECT='TRUE';
    'VSS108':
      PIN_NUMBER='(0,0,0,0,0,0,0,0,0,0,0,0,0,0,0,0,0,0,0,0,0,0,0,0,0,0,0,0,0,0,0,0,0,0,0,0,0,0,AE48,0,0,0)';
      PINUSE='POWER';
      NO_LOAD_CHECK='Both';
      NO_IO_CHECK='Both';
      NO_ASSERT_CHECK='TRUE';
      NO_DIR_CHECK='TRUE';
      ALLOW_CONNECT='TRUE';
    'VSS107':
      PIN_NUMBER='(0,0,0,0,0,0,0,0,0,0,0,0,0,0,0,0,0,0,0,0,0,0,0,0,0,0,0,0,0,0,0,0,0,0,0,0,0,0,AE45,0,0,0)';
      PINUSE='POWER';
      NO_LOAD_CHECK='Both';
      NO_IO_CHECK='Both';
      NO_ASSERT_CHECK='TRUE';
      NO_DIR_CHECK='TRUE';
      ALLOW_CONNECT='TRUE';
    'VSS106':
      PIN_NUMBER='(0,0,0,0,0,0,0,0,0,0,0,0,0,0,0,0,0,0,0,0,0,0,0,0,0,0,0,0,0,0,0,0,0,0,0,0,0,0,AE43,0,0,0)';
      PINUSE='POWER';
      NO_LOAD_CHECK='Both';
      NO_IO_CHECK='Both';
      NO_ASSERT_CHECK='TRUE';
      NO_DIR_CHECK='TRUE';
      ALLOW_CONNECT='TRUE';
    'VSS105':
      PIN_NUMBER='(0,0,0,0,0,0,0,0,0,0,0,0,0,0,0,0,0,0,0,0,0,0,0,0,0,0,0,0,0,0,0,0,0,0,0,0,0,0,AE41,0,0,0)';
      PINUSE='POWER';
      NO_LOAD_CHECK='Both';
      NO_IO_CHECK='Both';
      NO_ASSERT_CHECK='TRUE';
      NO_DIR_CHECK='TRUE';
      ALLOW_CONNECT='TRUE';
    'VSS104':
      PIN_NUMBER='(0,0,0,0,0,0,0,0,0,0,0,0,0,0,0,0,0,0,0,0,0,0,0,0,0,0,0,0,0,0,0,0,0,0,0,0,0,0,AE39,0,0,0)';
      PINUSE='POWER';
      NO_LOAD_CHECK='Both';
      NO_IO_CHECK='Both';
      NO_ASSERT_CHECK='TRUE';
      NO_DIR_CHECK='TRUE';
      ALLOW_CONNECT='TRUE';
    'VSS103':
      PIN_NUMBER='(0,0,0,0,0,0,0,0,0,0,0,0,0,0,0,0,0,0,0,0,0,0,0,0,0,0,0,0,0,0,0,0,0,0,0,0,0,0,AE37,0,0,0)';
      PINUSE='POWER';
      NO_LOAD_CHECK='Both';
      NO_IO_CHECK='Both';
      NO_ASSERT_CHECK='TRUE';
      NO_DIR_CHECK='TRUE';
      ALLOW_CONNECT='TRUE';
    'VSS102':
      PIN_NUMBER='(0,0,0,0,0,0,0,0,0,0,0,0,0,0,0,0,0,0,0,0,0,0,0,0,0,0,0,0,0,0,0,0,0,0,0,0,0,0,AE35,0,0,0)';
      PINUSE='POWER';
      NO_LOAD_CHECK='Both';
      NO_IO_CHECK='Both';
      NO_ASSERT_CHECK='TRUE';
      NO_DIR_CHECK='TRUE';
      ALLOW_CONNECT='TRUE';
    'VSS101':
      PIN_NUMBER='(0,0,0,0,0,0,0,0,0,0,0,0,0,0,0,0,0,0,0,0,0,0,0,0,0,0,0,0,0,0,0,0,0,0,0,0,0,0,AE33,0,0,0)';
      PINUSE='POWER';
      NO_LOAD_CHECK='Both';
      NO_IO_CHECK='Both';
      NO_ASSERT_CHECK='TRUE';
      NO_DIR_CHECK='TRUE';
      ALLOW_CONNECT='TRUE';
    'VSS100':
      PIN_NUMBER='(0,0,0,0,0,0,0,0,0,0,0,0,0,0,0,0,0,0,0,0,0,0,0,0,0,0,0,0,0,0,0,0,0,0,0,0,0,0,AE31,0,0,0)';
      PINUSE='POWER';
      NO_LOAD_CHECK='Both';
      NO_IO_CHECK='Both';
      NO_ASSERT_CHECK='TRUE';
      NO_DIR_CHECK='TRUE';
      ALLOW_CONNECT='TRUE';
    'VSS99':
      PIN_NUMBER='(0,0,0,0,0,0,0,0,0,0,0,0,0,0,0,0,0,0,0,0,0,0,0,0,0,0,0,0,0,0,0,0,0,0,0,0,0,0,AE29,0,0,0)';
      PINUSE='POWER';
      NO_LOAD_CHECK='Both';
      NO_IO_CHECK='Both';
      NO_ASSERT_CHECK='TRUE';
      NO_DIR_CHECK='TRUE';
      ALLOW_CONNECT='TRUE';
    'VSS98':
      PIN_NUMBER='(0,0,0,0,0,0,0,0,0,0,0,0,0,0,0,0,0,0,0,0,0,0,0,0,0,0,0,0,0,0,0,0,0,0,0,0,0,0,AE27,0,0,0)';
      PINUSE='POWER';
      NO_LOAD_CHECK='Both';
      NO_IO_CHECK='Both';
      NO_ASSERT_CHECK='TRUE';
      NO_DIR_CHECK='TRUE';
      ALLOW_CONNECT='TRUE';
    'VSS97':
      PIN_NUMBER='(0,0,0,0,0,0,0,0,0,0,0,0,0,0,0,0,0,0,0,0,0,0,0,0,0,0,0,0,0,0,0,0,0,0,0,0,0,0,AE25,0,0,0)';
      PINUSE='POWER';
      NO_LOAD_CHECK='Both';
      NO_IO_CHECK='Both';
      NO_ASSERT_CHECK='TRUE';
      NO_DIR_CHECK='TRUE';
      ALLOW_CONNECT='TRUE';
    'VSS96':
      PIN_NUMBER='(0,0,0,0,0,0,0,0,0,0,0,0,0,0,0,0,0,0,0,0,0,0,0,0,0,0,0,0,0,0,0,0,0,0,0,0,0,0,AE23,0,0,0)';
      PINUSE='POWER';
      NO_LOAD_CHECK='Both';
      NO_IO_CHECK='Both';
      NO_ASSERT_CHECK='TRUE';
      NO_DIR_CHECK='TRUE';
      ALLOW_CONNECT='TRUE';
    'VSS95':
      PIN_NUMBER='(0,0,0,0,0,0,0,0,0,0,0,0,0,0,0,0,0,0,0,0,0,0,0,0,0,0,0,0,0,0,0,0,0,0,0,0,0,0,AE21,0,0,0)';
      PINUSE='POWER';
      NO_LOAD_CHECK='Both';
      NO_IO_CHECK='Both';
      NO_ASSERT_CHECK='TRUE';
      NO_DIR_CHECK='TRUE';
      ALLOW_CONNECT='TRUE';
    'VSS94':
      PIN_NUMBER='(0,0,0,0,0,0,0,0,0,0,0,0,0,0,0,0,0,0,0,0,0,0,0,0,0,0,0,0,0,0,0,0,0,0,0,0,0,0,AE19,0,0,0)';
      PINUSE='POWER';
      NO_LOAD_CHECK='Both';
      NO_IO_CHECK='Both';
      NO_ASSERT_CHECK='TRUE';
      NO_DIR_CHECK='TRUE';
      ALLOW_CONNECT='TRUE';
    'VSS93':
      PIN_NUMBER='(0,0,0,0,0,0,0,0,0,0,0,0,0,0,0,0,0,0,0,0,0,0,0,0,0,0,0,0,0,0,0,0,0,0,0,0,0,0,AE17,0,0,0)';
      PINUSE='POWER';
      NO_LOAD_CHECK='Both';
      NO_IO_CHECK='Both';
      NO_ASSERT_CHECK='TRUE';
      NO_DIR_CHECK='TRUE';
      ALLOW_CONNECT='TRUE';
    'VSS92':
      PIN_NUMBER='(0,0,0,0,0,0,0,0,0,0,0,0,0,0,0,0,0,0,0,0,0,0,0,0,0,0,0,0,0,0,0,0,0,0,0,0,0,0,AD83,0,0,0)';
      PINUSE='POWER';
      NO_LOAD_CHECK='Both';
      NO_IO_CHECK='Both';
      NO_ASSERT_CHECK='TRUE';
      NO_DIR_CHECK='TRUE';
      ALLOW_CONNECT='TRUE';
    'VSS91':
      PIN_NUMBER='(0,0,0,0,0,0,0,0,0,0,0,0,0,0,0,0,0,0,0,0,0,0,0,0,0,0,0,0,0,0,0,0,0,0,0,0,0,0,AD8,0,0,0)';
      PINUSE='POWER';
      NO_LOAD_CHECK='Both';
      NO_IO_CHECK='Both';
      NO_ASSERT_CHECK='TRUE';
      NO_DIR_CHECK='TRUE';
      ALLOW_CONNECT='TRUE';
    'VSS90':
      PIN_NUMBER='(0,0,0,0,0,0,0,0,0,0,0,0,0,0,0,0,0,0,0,0,0,0,0,0,0,0,0,0,0,0,0,0,0,0,0,0,0,0,AD79,0,0,0)';
      PINUSE='POWER';
      NO_LOAD_CHECK='Both';
      NO_IO_CHECK='Both';
      NO_ASSERT_CHECK='TRUE';
      NO_DIR_CHECK='TRUE';
      ALLOW_CONNECT='TRUE';
    'VSS89':
      PIN_NUMBER='(0,0,0,0,0,0,0,0,0,0,0,0,0,0,0,0,0,0,0,0,0,0,0,0,0,0,0,0,0,0,0,0,0,0,0,0,0,0,AD42,0,0,0)';
      PINUSE='POWER';
      NO_LOAD_CHECK='Both';
      NO_IO_CHECK='Both';
      NO_ASSERT_CHECK='TRUE';
      NO_DIR_CHECK='TRUE';
      ALLOW_CONNECT='TRUE';
    'VSS88':
      PIN_NUMBER='(0,0,0,0,0,0,0,0,0,0,0,0,0,0,0,0,0,0,0,0,0,0,0,0,0,0,0,0,0,0,0,0,0,0,0,0,0,0,AD4,0,0,0)';
      PINUSE='POWER';
      NO_LOAD_CHECK='Both';
      NO_IO_CHECK='Both';
      NO_ASSERT_CHECK='TRUE';
      NO_DIR_CHECK='TRUE';
      ALLOW_CONNECT='TRUE';
    'VSS87':
      PIN_NUMBER='(0,0,0,0,0,0,0,0,0,0,0,0,0,0,0,0,0,0,0,0,0,0,0,0,0,0,0,0,0,0,0,0,0,0,0,0,0,0,AD16,0,0,0)';
      PINUSE='POWER';
      NO_LOAD_CHECK='Both';
      NO_IO_CHECK='Both';
      NO_ASSERT_CHECK='TRUE';
      NO_DIR_CHECK='TRUE';
      ALLOW_CONNECT='TRUE';
    'VSS86':
      PIN_NUMBER='(0,0,0,0,0,0,0,0,0,0,0,0,0,0,0,0,0,0,0,0,0,0,0,0,0,0,0,0,0,0,0,0,0,0,0,0,0,0,AD12,0,0,0)';
      PINUSE='POWER';
      NO_LOAD_CHECK='Both';
      NO_IO_CHECK='Both';
      NO_ASSERT_CHECK='TRUE';
      NO_DIR_CHECK='TRUE';
      ALLOW_CONNECT='TRUE';
    'VSS85':
      PIN_NUMBER='(0,0,0,0,0,0,0,0,0,0,0,0,0,0,0,0,0,0,0,0,0,0,0,0,0,0,0,0,0,0,0,0,0,0,0,0,0,0,AC9,0,0,0)';
      PINUSE='POWER';
      NO_LOAD_CHECK='Both';
      NO_IO_CHECK='Both';
      NO_ASSERT_CHECK='TRUE';
      NO_DIR_CHECK='TRUE';
      ALLOW_CONNECT='TRUE';
    'VSS84':
      PIN_NUMBER='(0,0,0,0,0,0,0,0,0,0,0,0,0,0,0,0,0,0,0,0,0,0,0,0,0,0,0,0,0,0,0,0,0,0,0,0,0,0,AC88,0,0,0)';
      PINUSE='POWER';
      NO_LOAD_CHECK='Both';
      NO_IO_CHECK='Both';
      NO_ASSERT_CHECK='TRUE';
      NO_DIR_CHECK='TRUE';
      ALLOW_CONNECT='TRUE';
    'VSS83':
      PIN_NUMBER='(0,0,0,0,0,0,0,0,0,0,0,0,0,0,0,0,0,0,0,0,0,0,0,0,0,0,0,0,0,0,0,0,0,0,0,0,0,0,AC84,0,0,0)';
      PINUSE='POWER';
      NO_LOAD_CHECK='Both';
      NO_IO_CHECK='Both';
      NO_ASSERT_CHECK='TRUE';
      NO_DIR_CHECK='TRUE';
      ALLOW_CONNECT='TRUE';
    'VSS82':
      PIN_NUMBER='(0,0,0,0,0,0,0,0,0,0,0,0,0,0,0,0,0,0,0,0,0,0,0,0,0,0,0,0,0,0,0,0,0,0,0,0,0,0,AC76,0,0,0)';
      PINUSE='POWER';
      NO_LOAD_CHECK='Both';
      NO_IO_CHECK='Both';
      NO_ASSERT_CHECK='TRUE';
      NO_DIR_CHECK='TRUE';
      ALLOW_CONNECT='TRUE';
    'VSS81':
      PIN_NUMBER='(0,0,0,0,0,0,0,0,0,0,0,0,0,0,0,0,0,0,0,0,0,0,0,0,0,0,0,0,0,0,0,0,0,0,0,0,0,0,AC70,0,0,0)';
      PINUSE='POWER';
      NO_LOAD_CHECK='Both';
      NO_IO_CHECK='Both';
      NO_ASSERT_CHECK='TRUE';
      NO_DIR_CHECK='TRUE';
      ALLOW_CONNECT='TRUE';
    'VSS80':
      PIN_NUMBER='(0,0,0,0,0,0,0,0,0,0,0,0,0,0,0,0,0,0,0,0,0,0,0,0,0,0,0,0,0,0,0,0,0,0,0,0,0,0,AC64,0,0,0)';
      PINUSE='POWER';
      NO_LOAD_CHECK='Both';
      NO_IO_CHECK='Both';
      NO_ASSERT_CHECK='TRUE';
      NO_DIR_CHECK='TRUE';
      ALLOW_CONNECT='TRUE';
    'VSS79':
      PIN_NUMBER='(0,0,0,0,0,0,0,0,0,0,0,0,0,0,0,0,0,0,0,0,0,0,0,0,0,0,0,0,0,0,0,0,0,0,0,0,0,0,AC58,0,0,0)';
      PINUSE='POWER';
      NO_LOAD_CHECK='Both';
      NO_IO_CHECK='Both';
      NO_ASSERT_CHECK='TRUE';
      NO_DIR_CHECK='TRUE';
      ALLOW_CONNECT='TRUE';
    'VSS78':
      PIN_NUMBER='(0,0,0,0,0,0,0,0,0,0,0,0,0,0,0,0,0,0,0,0,0,0,0,0,0,0,0,0,0,0,0,0,0,0,0,0,0,0,AC52,0,0,0)';
      PINUSE='POWER';
      NO_LOAD_CHECK='Both';
      NO_IO_CHECK='Both';
      NO_ASSERT_CHECK='TRUE';
      NO_DIR_CHECK='TRUE';
      ALLOW_CONNECT='TRUE';
    'VSS77':
      PIN_NUMBER='(0,0,0,0,0,0,0,0,0,0,0,0,0,0,0,0,0,0,0,0,0,0,0,0,0,0,0,0,0,0,0,0,0,0,0,0,0,0,AC5,0,0,0)';
      PINUSE='POWER';
      NO_LOAD_CHECK='Both';
      NO_IO_CHECK='Both';
      NO_ASSERT_CHECK='TRUE';
      NO_DIR_CHECK='TRUE';
      ALLOW_CONNECT='TRUE';
    'VSS76':
      PIN_NUMBER='(0,0,0,0,0,0,0,0,0,0,0,0,0,0,0,0,0,0,0,0,0,0,0,0,0,0,0,0,0,0,0,0,0,0,0,0,0,0,AC45,0,0,0)';
      PINUSE='POWER';
      NO_LOAD_CHECK='Both';
      NO_IO_CHECK='Both';
      NO_ASSERT_CHECK='TRUE';
      NO_DIR_CHECK='TRUE';
      ALLOW_CONNECT='TRUE';
    'VSS75':
      PIN_NUMBER='(0,0,0,0,0,0,0,0,0,0,0,0,0,0,0,0,0,0,0,0,0,0,0,0,0,0,0,0,0,0,0,0,0,0,0,0,0,0,AC39,0,0,0)';
      PINUSE='POWER';
      NO_LOAD_CHECK='Both';
      NO_IO_CHECK='Both';
      NO_ASSERT_CHECK='TRUE';
      NO_DIR_CHECK='TRUE';
      ALLOW_CONNECT='TRUE';
    'VSS74':
      PIN_NUMBER='(0,0,0,0,0,0,0,0,0,0,0,0,0,0,0,0,0,0,0,0,0,0,0,0,0,0,0,0,0,0,0,0,0,0,0,0,0,0,AC33,0,0,0)';
      PINUSE='POWER';
      NO_LOAD_CHECK='Both';
      NO_IO_CHECK='Both';
      NO_ASSERT_CHECK='TRUE';
      NO_DIR_CHECK='TRUE';
      ALLOW_CONNECT='TRUE';
    'VSS73':
      PIN_NUMBER='(0,0,0,0,0,0,0,0,0,0,0,0,0,0,0,0,0,0,0,0,0,0,0,0,0,0,0,0,0,0,0,0,0,0,0,0,0,0,AC27,0,0,0)';
      PINUSE='POWER';
      NO_LOAD_CHECK='Both';
      NO_IO_CHECK='Both';
      NO_ASSERT_CHECK='TRUE';
      NO_DIR_CHECK='TRUE';
      ALLOW_CONNECT='TRUE';
    'VSS72':
      PIN_NUMBER='(0,0,0,0,0,0,0,0,0,0,0,0,0,0,0,0,0,0,0,0,0,0,0,0,0,0,0,0,0,0,0,0,0,0,0,0,0,0,AC21,0,0,0)';
      PINUSE='POWER';
      NO_LOAD_CHECK='Both';
      NO_IO_CHECK='Both';
      NO_ASSERT_CHECK='TRUE';
      NO_DIR_CHECK='TRUE';
      ALLOW_CONNECT='TRUE';
    'VSS71':
      PIN_NUMBER='(0,0,0,0,0,0,0,0,0,0,0,0,0,0,0,0,0,0,0,0,0,0,0,0,0,0,0,0,0,0,0,0,0,0,0,0,0,0,AC13,0,0,0)';
      PINUSE='POWER';
      NO_LOAD_CHECK='Both';
      NO_IO_CHECK='Both';
      NO_ASSERT_CHECK='TRUE';
      NO_DIR_CHECK='TRUE';
      ALLOW_CONNECT='TRUE';
    'VSS70':
      PIN_NUMBER='(0,0,0,0,0,0,0,0,0,0,0,0,0,0,0,0,0,0,0,0,0,0,0,0,0,0,0,0,0,0,0,0,0,0,0,0,0,0,AC1,0,0,0)';
      PINUSE='POWER';
      NO_LOAD_CHECK='Both';
      NO_IO_CHECK='Both';
      NO_ASSERT_CHECK='TRUE';
      NO_DIR_CHECK='TRUE';
      ALLOW_CONNECT='TRUE';
    'VSS69':
      PIN_NUMBER='(0,0,0,0,0,0,0,0,0,0,0,0,0,0,0,0,0,0,0,0,0,0,0,0,0,0,0,0,0,0,0,0,0,0,0,0,0,0,AB91,0,0,0)';
      PINUSE='POWER';
      NO_LOAD_CHECK='Both';
      NO_IO_CHECK='Both';
      NO_ASSERT_CHECK='TRUE';
      NO_DIR_CHECK='TRUE';
      ALLOW_CONNECT='TRUE';
    'VSS68':
      PIN_NUMBER='(0,0,0,0,0,0,0,0,0,0,0,0,0,0,0,0,0,0,0,0,0,0,0,0,0,0,0,0,0,0,0,0,0,0,0,0,0,0,AB87,0,0,0)';
      PINUSE='POWER';
      NO_LOAD_CHECK='Both';
      NO_IO_CHECK='Both';
      NO_ASSERT_CHECK='TRUE';
      NO_DIR_CHECK='TRUE';
      ALLOW_CONNECT='TRUE';
    'VSS67':
      PIN_NUMBER='(0,0,0,0,0,0,0,0,0,0,0,0,0,0,0,0,0,0,0,0,0,0,0,0,0,0,0,0,0,0,0,0,0,0,0,0,0,0,AB83,0,0,0)';
      PINUSE='POWER';
      NO_LOAD_CHECK='Both';
      NO_IO_CHECK='Both';
      NO_ASSERT_CHECK='TRUE';
      NO_DIR_CHECK='TRUE';
      ALLOW_CONNECT='TRUE';
    'VSS66':
      PIN_NUMBER='(0,0,0,0,0,0,0,0,0,0,0,0,0,0,0,0,0,0,0,0,0,0,0,0,0,0,0,0,0,0,0,0,0,0,0,0,0,0,AB81,0,0,0)';
      PINUSE='POWER';
      NO_LOAD_CHECK='Both';
      NO_IO_CHECK='Both';
      NO_ASSERT_CHECK='TRUE';
      NO_DIR_CHECK='TRUE';
      ALLOW_CONNECT='TRUE';
    'VSS65':
      PIN_NUMBER='(0,0,0,0,0,0,0,0,0,0,0,0,0,0,0,0,0,0,0,0,0,0,0,0,0,0,0,0,0,0,0,0,0,0,0,0,0,0,AB8,0,0,0)';
      PINUSE='POWER';
      NO_LOAD_CHECK='Both';
      NO_IO_CHECK='Both';
      NO_ASSERT_CHECK='TRUE';
      NO_DIR_CHECK='TRUE';
      ALLOW_CONNECT='TRUE';
    'VSS64':
      PIN_NUMBER='(0,0,0,0,0,0,0,0,0,0,0,0,0,0,0,0,0,0,0,0,0,0,0,0,0,0,0,0,0,0,0,0,0,0,0,0,0,0,AB79,0,0,0)';
      PINUSE='POWER';
      NO_LOAD_CHECK='Both';
      NO_IO_CHECK='Both';
      NO_ASSERT_CHECK='TRUE';
      NO_DIR_CHECK='TRUE';
      ALLOW_CONNECT='TRUE';
    'VSS63':
      PIN_NUMBER='(0,0,0,0,0,0,0,0,0,0,0,0,0,0,0,0,0,0,0,0,0,0,0,0,0,0,0,0,0,0,0,0,0,0,0,0,0,0,AB77,0,0,0)';
      PINUSE='POWER';
      NO_LOAD_CHECK='Both';
      NO_IO_CHECK='Both';
      NO_ASSERT_CHECK='TRUE';
      NO_DIR_CHECK='TRUE';
      ALLOW_CONNECT='TRUE';
    'VSS62':
      PIN_NUMBER='(0,0,0,0,0,0,0,0,0,0,0,0,0,0,0,0,0,0,0,0,0,0,0,0,0,0,0,0,0,0,0,0,0,0,0,0,0,0,AB75,0,0,0)';
      PINUSE='POWER';
      NO_LOAD_CHECK='Both';
      NO_IO_CHECK='Both';
      NO_ASSERT_CHECK='TRUE';
      NO_DIR_CHECK='TRUE';
      ALLOW_CONNECT='TRUE';
    'VSS61':
      PIN_NUMBER='(0,0,0,0,0,0,0,0,0,0,0,0,0,0,0,0,0,0,0,0,0,0,0,0,0,0,0,0,0,0,0,0,0,0,0,0,0,0,AB71,0,0,0)';
      PINUSE='POWER';
      NO_LOAD_CHECK='Both';
      NO_IO_CHECK='Both';
      NO_ASSERT_CHECK='TRUE';
      NO_DIR_CHECK='TRUE';
      ALLOW_CONNECT='TRUE';
    'VSS60':
      PIN_NUMBER='(0,0,0,0,0,0,0,0,0,0,0,0,0,0,0,0,0,0,0,0,0,0,0,0,0,0,0,0,0,0,0,0,0,0,0,0,0,0,AB69,0,0,0)';
      PINUSE='POWER';
      NO_LOAD_CHECK='Both';
      NO_IO_CHECK='Both';
      NO_ASSERT_CHECK='TRUE';
      NO_DIR_CHECK='TRUE';
      ALLOW_CONNECT='TRUE';
    'VSS59':
      PIN_NUMBER='(0,0,0,0,0,0,0,0,0,0,0,0,0,0,0,0,0,0,0,0,0,0,0,0,0,0,0,0,0,0,0,0,0,0,0,0,0,0,AB65,0,0,0)';
      PINUSE='POWER';
      NO_LOAD_CHECK='Both';
      NO_IO_CHECK='Both';
      NO_ASSERT_CHECK='TRUE';
      NO_DIR_CHECK='TRUE';
      ALLOW_CONNECT='TRUE';
    'VSS58':
      PIN_NUMBER='(0,0,0,0,0,0,0,0,0,0,0,0,0,0,0,0,0,0,0,0,0,0,0,0,0,0,0,0,0,0,0,0,0,0,0,0,0,0,AB63,0,0,0)';
      PINUSE='POWER';
      NO_LOAD_CHECK='Both';
      NO_IO_CHECK='Both';
      NO_ASSERT_CHECK='TRUE';
      NO_DIR_CHECK='TRUE';
      ALLOW_CONNECT='TRUE';
    'VSS57':
      PIN_NUMBER='(0,0,0,0,0,0,0,0,0,0,0,0,0,0,0,0,0,0,0,0,0,0,0,0,0,0,0,0,0,0,0,0,0,0,0,0,0,0,AB59,0,0,0)';
      PINUSE='POWER';
      NO_LOAD_CHECK='Both';
      NO_IO_CHECK='Both';
      NO_ASSERT_CHECK='TRUE';
      NO_DIR_CHECK='TRUE';
      ALLOW_CONNECT='TRUE';
    'VSS56':
      PIN_NUMBER='(0,0,0,0,0,0,0,0,0,0,0,0,0,0,0,0,0,0,0,0,0,0,0,0,0,0,0,0,0,0,0,0,0,0,0,0,0,0,AB57,0,0,0)';
      PINUSE='POWER';
      NO_LOAD_CHECK='Both';
      NO_IO_CHECK='Both';
      NO_ASSERT_CHECK='TRUE';
      NO_DIR_CHECK='TRUE';
      ALLOW_CONNECT='TRUE';
    'VSS55':
      PIN_NUMBER='(0,0,0,0,0,0,0,0,0,0,0,0,0,0,0,0,0,0,0,0,0,0,0,0,0,0,0,0,0,0,0,0,0,0,0,0,0,0,AB53,0,0,0)';
      PINUSE='POWER';
      NO_LOAD_CHECK='Both';
      NO_IO_CHECK='Both';
      NO_ASSERT_CHECK='TRUE';
      NO_DIR_CHECK='TRUE';
      ALLOW_CONNECT='TRUE';
    'VSS54':
      PIN_NUMBER='(0,0,0,0,0,0,0,0,0,0,0,0,0,0,0,0,0,0,0,0,0,0,0,0,0,0,0,0,0,0,0,0,0,0,0,0,0,0,AB51,0,0,0)';
      PINUSE='POWER';
      NO_LOAD_CHECK='Both';
      NO_IO_CHECK='Both';
      NO_ASSERT_CHECK='TRUE';
      NO_DIR_CHECK='TRUE';
      ALLOW_CONNECT='TRUE';
    'VSS53':
      PIN_NUMBER='(0,0,0,0,0,0,0,0,0,0,0,0,0,0,0,0,0,0,0,0,0,0,0,0,0,0,0,0,0,0,0,0,0,0,0,0,0,0,AB47,0,0,0)';
      PINUSE='POWER';
      NO_LOAD_CHECK='Both';
      NO_IO_CHECK='Both';
      NO_ASSERT_CHECK='TRUE';
      NO_DIR_CHECK='TRUE';
      ALLOW_CONNECT='TRUE';
    'VSS52':
      PIN_NUMBER='(0,0,0,0,0,0,0,0,0,0,0,0,0,0,0,0,0,0,0,0,0,0,0,0,0,0,0,0,0,0,0,0,0,0,0,0,0,0,AB44,0,0,0)';
      PINUSE='POWER';
      NO_LOAD_CHECK='Both';
      NO_IO_CHECK='Both';
      NO_ASSERT_CHECK='TRUE';
      NO_DIR_CHECK='TRUE';
      ALLOW_CONNECT='TRUE';
    'VSS51':
      PIN_NUMBER='(0,0,0,0,0,0,0,0,0,0,0,0,0,0,0,0,0,0,0,0,0,0,0,0,0,0,0,0,0,0,0,0,0,0,0,0,0,0,AB40,0,0,0)';
      PINUSE='POWER';
      NO_LOAD_CHECK='Both';
      NO_IO_CHECK='Both';
      NO_ASSERT_CHECK='TRUE';
      NO_DIR_CHECK='TRUE';
      ALLOW_CONNECT='TRUE';
    'VSS50':
      PIN_NUMBER='(0,0,0,0,0,0,0,0,0,0,0,0,0,0,0,0,0,0,0,0,0,0,0,0,0,0,0,0,0,0,0,0,0,0,0,0,0,0,AB4,0,0,0)';
      PINUSE='POWER';
      NO_LOAD_CHECK='Both';
      NO_IO_CHECK='Both';
      NO_ASSERT_CHECK='TRUE';
      NO_DIR_CHECK='TRUE';
      ALLOW_CONNECT='TRUE';
    'VSS49':
      PIN_NUMBER='(0,0,0,0,0,0,0,0,0,0,0,0,0,0,0,0,0,0,0,0,0,0,0,0,0,0,0,0,0,0,0,0,0,0,0,0,0,0,AB38,0,0,0)';
      PINUSE='POWER';
      NO_LOAD_CHECK='Both';
      NO_IO_CHECK='Both';
      NO_ASSERT_CHECK='TRUE';
      NO_DIR_CHECK='TRUE';
      ALLOW_CONNECT='TRUE';
    'VSS48':
      PIN_NUMBER='(0,0,0,0,0,0,0,0,0,0,0,0,0,0,0,0,0,0,0,0,0,0,0,0,0,0,0,0,0,0,0,0,0,0,0,0,0,0,AB34,0,0,0)';
      PINUSE='POWER';
      NO_LOAD_CHECK='Both';
      NO_IO_CHECK='Both';
      NO_ASSERT_CHECK='TRUE';
      NO_DIR_CHECK='TRUE';
      ALLOW_CONNECT='TRUE';
    'VSS47':
      PIN_NUMBER='(0,0,0,0,0,0,0,0,0,0,0,0,0,0,0,0,0,0,0,0,0,0,0,0,0,0,0,0,0,0,0,0,0,0,0,0,0,0,AB32,0,0,0)';
      PINUSE='POWER';
      NO_LOAD_CHECK='Both';
      NO_IO_CHECK='Both';
      NO_ASSERT_CHECK='TRUE';
      NO_DIR_CHECK='TRUE';
      ALLOW_CONNECT='TRUE';
    'VSS46':
      PIN_NUMBER='(0,0,0,0,0,0,0,0,0,0,0,0,0,0,0,0,0,0,0,0,0,0,0,0,0,0,0,0,0,0,0,0,0,0,0,0,0,0,AB28,0,0,0)';
      PINUSE='POWER';
      NO_LOAD_CHECK='Both';
      NO_IO_CHECK='Both';
      NO_ASSERT_CHECK='TRUE';
      NO_DIR_CHECK='TRUE';
      ALLOW_CONNECT='TRUE';
    'VSS45':
      PIN_NUMBER='(0,0,0,0,0,0,0,0,0,0,0,0,0,0,0,0,0,0,0,0,0,0,0,0,0,0,0,0,0,0,0,0,0,0,0,0,0,0,AB26,0,0,0)';
      PINUSE='POWER';
      NO_LOAD_CHECK='Both';
      NO_IO_CHECK='Both';
      NO_ASSERT_CHECK='TRUE';
      NO_DIR_CHECK='TRUE';
      ALLOW_CONNECT='TRUE';
    'VSS44':
      PIN_NUMBER='(0,0,0,0,0,0,0,0,0,0,0,0,0,0,0,0,0,0,0,0,0,0,0,0,0,0,0,0,0,0,0,0,0,0,0,0,0,0,AB22,0,0,0)';
      PINUSE='POWER';
      NO_LOAD_CHECK='Both';
      NO_IO_CHECK='Both';
      NO_ASSERT_CHECK='TRUE';
      NO_DIR_CHECK='TRUE';
      ALLOW_CONNECT='TRUE';
    'VSS43':
      PIN_NUMBER='(0,0,0,0,0,0,0,0,0,0,0,0,0,0,0,0,0,0,0,0,0,0,0,0,0,0,0,0,0,0,0,0,0,0,0,0,0,0,AB20,0,0,0)';
      PINUSE='POWER';
      NO_LOAD_CHECK='Both';
      NO_IO_CHECK='Both';
      NO_ASSERT_CHECK='TRUE';
      NO_DIR_CHECK='TRUE';
      ALLOW_CONNECT='TRUE';
    'VSS42':
      PIN_NUMBER='(0,0,0,0,0,0,0,0,0,0,0,0,0,0,0,0,0,0,0,0,0,0,0,0,0,0,0,0,0,0,0,0,0,0,0,0,0,0,AB16,0,0,0)';
      PINUSE='POWER';
      NO_LOAD_CHECK='Both';
      NO_IO_CHECK='Both';
      NO_ASSERT_CHECK='TRUE';
      NO_DIR_CHECK='TRUE';
      ALLOW_CONNECT='TRUE';
    'VSS41':
      PIN_NUMBER='(0,0,0,0,0,0,0,0,0,0,0,0,0,0,0,0,0,0,0,0,0,0,0,0,0,0,0,0,0,0,0,0,0,0,0,0,0,0,AB12,0,0,0)';
      PINUSE='POWER';
      NO_LOAD_CHECK='Both';
      NO_IO_CHECK='Both';
      NO_ASSERT_CHECK='TRUE';
      NO_DIR_CHECK='TRUE';
      ALLOW_CONNECT='TRUE';
    'VSS40':
      PIN_NUMBER='(0,0,0,0,0,0,0,0,0,0,0,0,0,0,0,0,0,0,0,0,0,0,0,0,0,0,0,0,0,0,0,0,0,0,0,0,0,0,AA88,0,0,0)';
      PINUSE='POWER';
      NO_LOAD_CHECK='Both';
      NO_IO_CHECK='Both';
      NO_ASSERT_CHECK='TRUE';
      NO_DIR_CHECK='TRUE';
      ALLOW_CONNECT='TRUE';
    'VSS39':
      PIN_NUMBER='(0,0,0,0,0,0,0,0,0,0,0,0,0,0,0,0,0,0,0,0,0,0,0,0,0,0,0,0,0,0,0,0,0,0,0,0,0,0,AA84,0,0,0)';
      PINUSE='POWER';
      NO_LOAD_CHECK='Both';
      NO_IO_CHECK='Both';
      NO_ASSERT_CHECK='TRUE';
      NO_DIR_CHECK='TRUE';
      ALLOW_CONNECT='TRUE';
    'VSS38':
      PIN_NUMBER='(0,0,0,0,0,0,0,0,0,0,0,0,0,0,0,0,0,0,0,0,0,0,0,0,0,0,0,0,0,0,0,0,0,0,0,0,0,0,AA82,0,0,0)';
      PINUSE='POWER';
      NO_LOAD_CHECK='Both';
      NO_IO_CHECK='Both';
      NO_ASSERT_CHECK='TRUE';
      NO_DIR_CHECK='TRUE';
      ALLOW_CONNECT='TRUE';
    'VSS1833':
      PIN_NUMBER='(0,0,0,0,0,0,0,0,0,0,0,0,0,0,0,0,0,0,0,0,0,0,0,0,0,0,0,0,0,0,0,0,0,0,0,0,0,0,0,Y73,0,0)';
      PINUSE='POWER';
      NO_LOAD_CHECK='Both';
      NO_IO_CHECK='Both';
      NO_ASSERT_CHECK='TRUE';
      NO_DIR_CHECK='TRUE';
      ALLOW_CONNECT='TRUE';
    'VSS1832':
      PIN_NUMBER='(0,0,0,0,0,0,0,0,0,0,0,0,0,0,0,0,0,0,0,0,0,0,0,0,0,0,0,0,0,0,0,0,0,0,0,0,0,0,0,Y8,0,0)';
      PINUSE='POWER';
      NO_LOAD_CHECK='Both';
      NO_IO_CHECK='Both';
      NO_ASSERT_CHECK='TRUE';
      NO_DIR_CHECK='TRUE';
      ALLOW_CONNECT='TRUE';
    'VSS1831':
      PIN_NUMBER='(0,0,0,0,0,0,0,0,0,0,0,0,0,0,0,0,0,0,0,0,0,0,0,0,0,0,0,0,0,0,0,0,0,0,0,0,0,0,0,Y55,0,0)';
      PINUSE='POWER';
      NO_LOAD_CHECK='Both';
      NO_IO_CHECK='Both';
      NO_ASSERT_CHECK='TRUE';
      NO_DIR_CHECK='TRUE';
      ALLOW_CONNECT='TRUE';
    'VSS1830':
      PIN_NUMBER='(0,0,0,0,0,0,0,0,0,0,0,0,0,0,0,0,0,0,0,0,0,0,0,0,0,0,0,0,0,0,0,0,0,0,0,0,0,0,0,Y49,0,0)';
      PINUSE='POWER';
      NO_LOAD_CHECK='Both';
      NO_IO_CHECK='Both';
      NO_ASSERT_CHECK='TRUE';
      NO_DIR_CHECK='TRUE';
      ALLOW_CONNECT='TRUE';
    'VSS1829':
      PIN_NUMBER='(0,0,0,0,0,0,0,0,0,0,0,0,0,0,0,0,0,0,0,0,0,0,0,0,0,0,0,0,0,0,0,0,0,0,0,0,0,0,0,Y67,0,0)';
      PINUSE='POWER';
      NO_LOAD_CHECK='Both';
      NO_IO_CHECK='Both';
      NO_ASSERT_CHECK='TRUE';
      NO_DIR_CHECK='TRUE';
      ALLOW_CONNECT='TRUE';
    'VSS1828':
      PIN_NUMBER='(0,0,0,0,0,0,0,0,0,0,0,0,0,0,0,0,0,0,0,0,0,0,0,0,0,0,0,0,0,0,0,0,0,0,0,0,0,0,0,Y61,0,0)';
      PINUSE='POWER';
      NO_LOAD_CHECK='Both';
      NO_IO_CHECK='Both';
      NO_ASSERT_CHECK='TRUE';
      NO_DIR_CHECK='TRUE';
      ALLOW_CONNECT='TRUE';
    'VSS1827':
      PIN_NUMBER='(0,0,0,0,0,0,0,0,0,0,0,0,0,0,0,0,0,0,0,0,0,0,0,0,0,0,0,0,0,0,0,0,0,0,0,0,0,0,0,Y42,0,0)';
      PINUSE='POWER';
      NO_LOAD_CHECK='Both';
      NO_IO_CHECK='Both';
      NO_ASSERT_CHECK='TRUE';
      NO_DIR_CHECK='TRUE';
      ALLOW_CONNECT='TRUE';
    'VSS1826':
      PIN_NUMBER='(0,0,0,0,0,0,0,0,0,0,0,0,0,0,0,0,0,0,0,0,0,0,0,0,0,0,0,0,0,0,0,0,0,0,0,0,0,0,0,Y4,0,0)';
      PINUSE='POWER';
      NO_LOAD_CHECK='Both';
      NO_IO_CHECK='Both';
      NO_ASSERT_CHECK='TRUE';
      NO_DIR_CHECK='TRUE';
      ALLOW_CONNECT='TRUE';
    'VSS1825':
      PIN_NUMBER='(0,0,0,0,0,0,0,0,0,0,0,0,0,0,0,0,0,0,0,0,0,0,0,0,0,0,0,0,0,0,0,0,0,0,0,0,0,0,0,Y36,0,0)';
      PINUSE='POWER';
      NO_LOAD_CHECK='Both';
      NO_IO_CHECK='Both';
      NO_ASSERT_CHECK='TRUE';
      NO_DIR_CHECK='TRUE';
      ALLOW_CONNECT='TRUE';
    'VSS1824':
      PIN_NUMBER='(0,0,0,0,0,0,0,0,0,0,0,0,0,0,0,0,0,0,0,0,0,0,0,0,0,0,0,0,0,0,0,0,0,0,0,0,0,0,0,Y30,0,0)';
      PINUSE='POWER';
      NO_LOAD_CHECK='Both';
      NO_IO_CHECK='Both';
      NO_ASSERT_CHECK='TRUE';
      NO_DIR_CHECK='TRUE';
      ALLOW_CONNECT='TRUE';
    'VSS1823':
      PIN_NUMBER='(0,0,0,0,0,0,0,0,0,0,0,0,0,0,0,0,0,0,0,0,0,0,0,0,0,0,0,0,0,0,0,0,0,0,0,0,0,0,0,Y24,0,0)';
      PINUSE='POWER';
      NO_LOAD_CHECK='Both';
      NO_IO_CHECK='Both';
      NO_ASSERT_CHECK='TRUE';
      NO_DIR_CHECK='TRUE';
      ALLOW_CONNECT='TRUE';
    'VSS1822':
      PIN_NUMBER='(0,0,0,0,0,0,0,0,0,0,0,0,0,0,0,0,0,0,0,0,0,0,0,0,0,0,0,0,0,0,0,0,0,0,0,0,0,0,0,Y18,0,0)';
      PINUSE='POWER';
      NO_LOAD_CHECK='Both';
      NO_IO_CHECK='Both';
      NO_ASSERT_CHECK='TRUE';
      NO_DIR_CHECK='TRUE';
      ALLOW_CONNECT='TRUE';
    'VSS1821':
      PIN_NUMBER='(0,0,0,0,0,0,0,0,0,0,0,0,0,0,0,0,0,0,0,0,0,0,0,0,0,0,0,0,0,0,0,0,0,0,0,0,0,0,0,Y16,0,0)';
      PINUSE='POWER';
      NO_LOAD_CHECK='Both';
      NO_IO_CHECK='Both';
      NO_ASSERT_CHECK='TRUE';
      NO_DIR_CHECK='TRUE';
      ALLOW_CONNECT='TRUE';
    'VSS1820':
      PIN_NUMBER='(0,0,0,0,0,0,0,0,0,0,0,0,0,0,0,0,0,0,0,0,0,0,0,0,0,0,0,0,0,0,0,0,0,0,0,0,0,0,0,Y12,0,0)';
      PINUSE='POWER';
      NO_LOAD_CHECK='Both';
      NO_IO_CHECK='Both';
      NO_ASSERT_CHECK='TRUE';
      NO_DIR_CHECK='TRUE';
      ALLOW_CONNECT='TRUE';
    'VSS1819':
      PIN_NUMBER='(0,0,0,0,0,0,0,0,0,0,0,0,0,0,0,0,0,0,0,0,0,0,0,0,0,0,0,0,0,0,0,0,0,0,0,0,0,0,0,W9,0,0)';
      PINUSE='POWER';
      NO_LOAD_CHECK='Both';
      NO_IO_CHECK='Both';
      NO_ASSERT_CHECK='TRUE';
      NO_DIR_CHECK='TRUE';
      ALLOW_CONNECT='TRUE';
    'VSS1818':
      PIN_NUMBER='(0,0,0,0,0,0,0,0,0,0,0,0,0,0,0,0,0,0,0,0,0,0,0,0,0,0,0,0,0,0,0,0,0,0,0,0,0,0,0,W88,0,0)';
      PINUSE='POWER';
      NO_LOAD_CHECK='Both';
      NO_IO_CHECK='Both';
      NO_ASSERT_CHECK='TRUE';
      NO_DIR_CHECK='TRUE';
      ALLOW_CONNECT='TRUE';
    'VSS1817':
      PIN_NUMBER='(0,0,0,0,0,0,0,0,0,0,0,0,0,0,0,0,0,0,0,0,0,0,0,0,0,0,0,0,0,0,0,0,0,0,0,0,0,0,0,W84,0,0)';
      PINUSE='POWER';
      NO_LOAD_CHECK='Both';
      NO_IO_CHECK='Both';
      NO_ASSERT_CHECK='TRUE';
      NO_DIR_CHECK='TRUE';
      ALLOW_CONNECT='TRUE';
    'VSS1816':
      PIN_NUMBER='(0,0,0,0,0,0,0,0,0,0,0,0,0,0,0,0,0,0,0,0,0,0,0,0,0,0,0,0,0,0,0,0,0,0,0,0,0,0,0,W39,0,0)';
      PINUSE='POWER';
      NO_LOAD_CHECK='Both';
      NO_IO_CHECK='Both';
      NO_ASSERT_CHECK='TRUE';
      NO_DIR_CHECK='TRUE';
      ALLOW_CONNECT='TRUE';
    'VSS1815':
      PIN_NUMBER='(0,0,0,0,0,0,0,0,0,0,0,0,0,0,0,0,0,0,0,0,0,0,0,0,0,0,0,0,0,0,0,0,0,0,0,0,0,0,0,W52,0,0)';
      PINUSE='POWER';
      NO_LOAD_CHECK='Both';
      NO_IO_CHECK='Both';
      NO_ASSERT_CHECK='TRUE';
      NO_DIR_CHECK='TRUE';
      ALLOW_CONNECT='TRUE';
    'VSS1814':
      PIN_NUMBER='(0,0,0,0,0,0,0,0,0,0,0,0,0,0,0,0,0,0,0,0,0,0,0,0,0,0,0,0,0,0,0,0,0,0,0,0,0,0,0,W5,0,0)';
      PINUSE='POWER';
      NO_LOAD_CHECK='Both';
      NO_IO_CHECK='Both';
      NO_ASSERT_CHECK='TRUE';
      NO_DIR_CHECK='TRUE';
      ALLOW_CONNECT='TRUE';
    'VSS1813':
      PIN_NUMBER='(0,0,0,0,0,0,0,0,0,0,0,0,0,0,0,0,0,0,0,0,0,0,0,0,0,0,0,0,0,0,0,0,0,0,0,0,0,0,0,V87,0,0)';
      PINUSE='POWER';
      NO_LOAD_CHECK='Both';
      NO_IO_CHECK='Both';
      NO_ASSERT_CHECK='TRUE';
      NO_DIR_CHECK='TRUE';
      ALLOW_CONNECT='TRUE';
    'VSS1812':
      PIN_NUMBER='(0,0,0,0,0,0,0,0,0,0,0,0,0,0,0,0,0,0,0,0,0,0,0,0,0,0,0,0,0,0,0,0,0,0,0,0,0,0,0,V8,0,0)';
      PINUSE='POWER';
      NO_LOAD_CHECK='Both';
      NO_IO_CHECK='Both';
      NO_ASSERT_CHECK='TRUE';
      NO_DIR_CHECK='TRUE';
      ALLOW_CONNECT='TRUE';
    'VSS1811':
      PIN_NUMBER='(0,0,0,0,0,0,0,0,0,0,0,0,0,0,0,0,0,0,0,0,0,0,0,0,0,0,0,0,0,0,0,0,0,0,0,0,0,0,0,V79,0,0)';
      PINUSE='POWER';
      NO_LOAD_CHECK='Both';
      NO_IO_CHECK='Both';
      NO_ASSERT_CHECK='TRUE';
      NO_DIR_CHECK='TRUE';
      ALLOW_CONNECT='TRUE';
    'VSS1810':
      PIN_NUMBER='(0,0,0,0,0,0,0,0,0,0,0,0,0,0,0,0,0,0,0,0,0,0,0,0,0,0,0,0,0,0,0,0,0,0,0,0,0,0,0,V77,0,0)';
      PINUSE='POWER';
      NO_LOAD_CHECK='Both';
      NO_IO_CHECK='Both';
      NO_ASSERT_CHECK='TRUE';
      NO_DIR_CHECK='TRUE';
      ALLOW_CONNECT='TRUE';
    'VSS1809':
      PIN_NUMBER='(0,0,0,0,0,0,0,0,0,0,0,0,0,0,0,0,0,0,0,0,0,0,0,0,0,0,0,0,0,0,0,0,0,0,0,0,0,0,0,W13,0,0)';
      PINUSE='POWER';
      NO_LOAD_CHECK='Both';
      NO_IO_CHECK='Both';
      NO_ASSERT_CHECK='TRUE';
      NO_DIR_CHECK='TRUE';
      ALLOW_CONNECT='TRUE';
    'VSS1808':
      PIN_NUMBER='(0,0,0,0,0,0,0,0,0,0,0,0,0,0,0,0,0,0,0,0,0,0,0,0,0,0,0,0,0,0,0,0,0,0,0,0,0,0,0,W1,0,0)';
      PINUSE='POWER';
      NO_LOAD_CHECK='Both';
      NO_IO_CHECK='Both';
      NO_ASSERT_CHECK='TRUE';
      NO_DIR_CHECK='TRUE';
      ALLOW_CONNECT='TRUE';
    'VSS1807':
      PIN_NUMBER='(0,0,0,0,0,0,0,0,0,0,0,0,0,0,0,0,0,0,0,0,0,0,0,0,0,0,0,0,0,0,0,0,0,0,0,0,0,0,0,V91,0,0)';
      PINUSE='POWER';
      NO_LOAD_CHECK='Both';
      NO_IO_CHECK='Both';
      NO_ASSERT_CHECK='TRUE';
      NO_DIR_CHECK='TRUE';
      ALLOW_CONNECT='TRUE';
    'VSS1806':
      PIN_NUMBER='(0,0,0,0,0,0,0,0,0,0,0,0,0,0,0,0,0,0,0,0,0,0,0,0,0,0,0,0,0,0,0,0,0,0,0,0,0,0,0,V75,0,0)';
      PINUSE='POWER';
      NO_LOAD_CHECK='Both';
      NO_IO_CHECK='Both';
      NO_ASSERT_CHECK='TRUE';
      NO_DIR_CHECK='TRUE';
      ALLOW_CONNECT='TRUE';
    'VSS1805':
      PIN_NUMBER='(0,0,0,0,0,0,0,0,0,0,0,0,0,0,0,0,0,0,0,0,0,0,0,0,0,0,0,0,0,0,0,0,0,0,0,0,0,0,0,V69,0,0)';
      PINUSE='POWER';
      NO_LOAD_CHECK='Both';
      NO_IO_CHECK='Both';
      NO_ASSERT_CHECK='TRUE';
      NO_DIR_CHECK='TRUE';
      ALLOW_CONNECT='TRUE';
    'VSS1804':
      PIN_NUMBER='(0,0,0,0,0,0,0,0,0,0,0,0,0,0,0,0,0,0,0,0,0,0,0,0,0,0,0,0,0,0,0,0,0,0,0,0,0,0,0,V67,0,0)';
      PINUSE='POWER';
      NO_LOAD_CHECK='Both';
      NO_IO_CHECK='Both';
      NO_ASSERT_CHECK='TRUE';
      NO_DIR_CHECK='TRUE';
      ALLOW_CONNECT='TRUE';
    'VSS1803':
      PIN_NUMBER='(0,0,0,0,0,0,0,0,0,0,0,0,0,0,0,0,0,0,0,0,0,0,0,0,0,0,0,0,0,0,0,0,0,0,0,0,0,0,0,V65,0,0)';
      PINUSE='POWER';
      NO_LOAD_CHECK='Both';
      NO_IO_CHECK='Both';
      NO_ASSERT_CHECK='TRUE';
      NO_DIR_CHECK='TRUE';
      ALLOW_CONNECT='TRUE';
    'VSS1802':
      PIN_NUMBER='(0,0,0,0,0,0,0,0,0,0,0,0,0,0,0,0,0,0,0,0,0,0,0,0,0,0,0,0,0,0,0,0,0,0,0,0,0,0,0,V63,0,0)';
      PINUSE='POWER';
      NO_LOAD_CHECK='Both';
      NO_IO_CHECK='Both';
      NO_ASSERT_CHECK='TRUE';
      NO_DIR_CHECK='TRUE';
      ALLOW_CONNECT='TRUE';
    'VSS1801':
      PIN_NUMBER='(0,0,0,0,0,0,0,0,0,0,0,0,0,0,0,0,0,0,0,0,0,0,0,0,0,0,0,0,0,0,0,0,0,0,0,0,0,0,0,V73,0,0)';
      PINUSE='POWER';
      NO_LOAD_CHECK='Both';
      NO_IO_CHECK='Both';
      NO_ASSERT_CHECK='TRUE';
      NO_DIR_CHECK='TRUE';
      ALLOW_CONNECT='TRUE';
    'VSS1800':
      PIN_NUMBER='(0,0,0,0,0,0,0,0,0,0,0,0,0,0,0,0,0,0,0,0,0,0,0,0,0,0,0,0,0,0,0,0,0,0,0,0,0,0,0,V71,0,0)';
      PINUSE='POWER';
      NO_LOAD_CHECK='Both';
      NO_IO_CHECK='Both';
      NO_ASSERT_CHECK='TRUE';
      NO_DIR_CHECK='TRUE';
      ALLOW_CONNECT='TRUE';
    'VSS1799':
      PIN_NUMBER='(0,0,0,0,0,0,0,0,0,0,0,0,0,0,0,0,0,0,0,0,0,0,0,0,0,0,0,0,0,0,0,0,0,0,0,0,0,0,0,V61,0,0)';
      PINUSE='POWER';
      NO_LOAD_CHECK='Both';
      NO_IO_CHECK='Both';
      NO_ASSERT_CHECK='TRUE';
      NO_DIR_CHECK='TRUE';
      ALLOW_CONNECT='TRUE';
    'VSS1798':
      PIN_NUMBER='(0,0,0,0,0,0,0,0,0,0,0,0,0,0,0,0,0,0,0,0,0,0,0,0,0,0,0,0,0,0,0,0,0,0,0,0,0,0,0,V59,0,0)';
      PINUSE='POWER';
      NO_LOAD_CHECK='Both';
      NO_IO_CHECK='Both';
      NO_ASSERT_CHECK='TRUE';
      NO_DIR_CHECK='TRUE';
      ALLOW_CONNECT='TRUE';
    'VSS1797':
      PIN_NUMBER='(0,0,0,0,0,0,0,0,0,0,0,0,0,0,0,0,0,0,0,0,0,0,0,0,0,0,0,0,0,0,0,0,0,0,0,0,0,0,0,V57,0,0)';
      PINUSE='POWER';
      NO_LOAD_CHECK='Both';
      NO_IO_CHECK='Both';
      NO_ASSERT_CHECK='TRUE';
      NO_DIR_CHECK='TRUE';
      ALLOW_CONNECT='TRUE';
    'VSS1796':
      PIN_NUMBER='(0,0,0,0,0,0,0,0,0,0,0,0,0,0,0,0,0,0,0,0,0,0,0,0,0,0,0,0,0,0,0,0,0,0,0,0,0,0,0,V55,0,0)';
      PINUSE='POWER';
      NO_LOAD_CHECK='Both';
      NO_IO_CHECK='Both';
      NO_ASSERT_CHECK='TRUE';
      NO_DIR_CHECK='TRUE';
      ALLOW_CONNECT='TRUE';
    'VSS1795':
      PIN_NUMBER='(0,0,0,0,0,0,0,0,0,0,0,0,0,0,0,0,0,0,0,0,0,0,0,0,0,0,0,0,0,0,0,0,0,0,0,0,0,0,0,V53,0,0)';
      PINUSE='POWER';
      NO_LOAD_CHECK='Both';
      NO_IO_CHECK='Both';
      NO_ASSERT_CHECK='TRUE';
      NO_DIR_CHECK='TRUE';
      ALLOW_CONNECT='TRUE';
    'VSS1794':
      PIN_NUMBER='(0,0,0,0,0,0,0,0,0,0,0,0,0,0,0,0,0,0,0,0,0,0,0,0,0,0,0,0,0,0,0,0,0,0,0,0,0,0,0,V51,0,0)';
      PINUSE='POWER';
      NO_LOAD_CHECK='Both';
      NO_IO_CHECK='Both';
      NO_ASSERT_CHECK='TRUE';
      NO_DIR_CHECK='TRUE';
      ALLOW_CONNECT='TRUE';
    'VSS1793':
      PIN_NUMBER='(0,0,0,0,0,0,0,0,0,0,0,0,0,0,0,0,0,0,0,0,0,0,0,0,0,0,0,0,0,0,0,0,0,0,0,0,0,0,0,V47,0,0)';
      PINUSE='POWER';
      NO_LOAD_CHECK='Both';
      NO_IO_CHECK='Both';
      NO_ASSERT_CHECK='TRUE';
      NO_DIR_CHECK='TRUE';
      ALLOW_CONNECT='TRUE';
    'VSS1792':
      PIN_NUMBER='(0,0,0,0,0,0,0,0,0,0,0,0,0,0,0,0,0,0,0,0,0,0,0,0,0,0,0,0,0,0,0,0,0,0,0,0,0,0,0,V44,0,0)';
      PINUSE='POWER';
      NO_LOAD_CHECK='Both';
      NO_IO_CHECK='Both';
      NO_ASSERT_CHECK='TRUE';
      NO_DIR_CHECK='TRUE';
      ALLOW_CONNECT='TRUE';
    'VSS1791':
      PIN_NUMBER='(0,0,0,0,0,0,0,0,0,0,0,0,0,0,0,0,0,0,0,0,0,0,0,0,0,0,0,0,0,0,0,0,0,0,0,0,0,0,0,V42,0,0)';
      PINUSE='POWER';
      NO_LOAD_CHECK='Both';
      NO_IO_CHECK='Both';
      NO_ASSERT_CHECK='TRUE';
      NO_DIR_CHECK='TRUE';
      ALLOW_CONNECT='TRUE';
    'VSS1790':
      PIN_NUMBER='(0,0,0,0,0,0,0,0,0,0,0,0,0,0,0,0,0,0,0,0,0,0,0,0,0,0,0,0,0,0,0,0,0,0,0,0,0,0,0,V40,0,0)';
      PINUSE='POWER';
      NO_LOAD_CHECK='Both';
      NO_IO_CHECK='Both';
      NO_ASSERT_CHECK='TRUE';
      NO_DIR_CHECK='TRUE';
      ALLOW_CONNECT='TRUE';
    'VSS1789':
      PIN_NUMBER='(0,0,0,0,0,0,0,0,0,0,0,0,0,0,0,0,0,0,0,0,0,0,0,0,0,0,0,0,0,0,0,0,0,0,0,0,0,0,0,V49,0,0)';
      PINUSE='POWER';
      NO_LOAD_CHECK='Both';
      NO_IO_CHECK='Both';
      NO_ASSERT_CHECK='TRUE';
      NO_DIR_CHECK='TRUE';
      ALLOW_CONNECT='TRUE';
    'VSS1788':
      PIN_NUMBER='(0,0,0,0,0,0,0,0,0,0,0,0,0,0,0,0,0,0,0,0,0,0,0,0,0,0,0,0,0,0,0,0,0,0,0,0,0,0,0,V4,0,0)';
      PINUSE='POWER';
      NO_LOAD_CHECK='Both';
      NO_IO_CHECK='Both';
      NO_ASSERT_CHECK='TRUE';
      NO_DIR_CHECK='TRUE';
      ALLOW_CONNECT='TRUE';
    'VSS1787':
      PIN_NUMBER='(0,0,0,0,0,0,0,0,0,0,0,0,0,0,0,0,0,0,0,0,0,0,0,0,0,0,0,0,0,0,0,0,0,0,0,0,0,0,0,V38,0,0)';
      PINUSE='POWER';
      NO_LOAD_CHECK='Both';
      NO_IO_CHECK='Both';
      NO_ASSERT_CHECK='TRUE';
      NO_DIR_CHECK='TRUE';
      ALLOW_CONNECT='TRUE';
    'VSS1786':
      PIN_NUMBER='(0,0,0,0,0,0,0,0,0,0,0,0,0,0,0,0,0,0,0,0,0,0,0,0,0,0,0,0,0,0,0,0,0,0,0,0,0,0,0,V36,0,0)';
      PINUSE='POWER';
      NO_LOAD_CHECK='Both';
      NO_IO_CHECK='Both';
      NO_ASSERT_CHECK='TRUE';
      NO_DIR_CHECK='TRUE';
      ALLOW_CONNECT='TRUE';
    'VSS1785':
      PIN_NUMBER='(0,0,0,0,0,0,0,0,0,0,0,0,0,0,0,0,0,0,0,0,0,0,0,0,0,0,0,0,0,0,0,0,0,0,0,0,0,0,0,V34,0,0)';
      PINUSE='POWER';
      NO_LOAD_CHECK='Both';
      NO_IO_CHECK='Both';
      NO_ASSERT_CHECK='TRUE';
      NO_DIR_CHECK='TRUE';
      ALLOW_CONNECT='TRUE';
    'VSS1784':
      PIN_NUMBER='(0,0,0,0,0,0,0,0,0,0,0,0,0,0,0,0,0,0,0,0,0,0,0,0,0,0,0,0,0,0,0,0,0,0,0,0,0,0,0,V32,0,0)';
      PINUSE='POWER';
      NO_LOAD_CHECK='Both';
      NO_IO_CHECK='Both';
      NO_ASSERT_CHECK='TRUE';
      NO_DIR_CHECK='TRUE';
      ALLOW_CONNECT='TRUE';
    'VSS1783':
      PIN_NUMBER='(0,0,0,0,0,0,0,0,0,0,0,0,0,0,0,0,0,0,0,0,0,0,0,0,0,0,0,0,0,0,0,0,0,0,0,0,0,0,0,V30,0,0)';
      PINUSE='POWER';
      NO_LOAD_CHECK='Both';
      NO_IO_CHECK='Both';
      NO_ASSERT_CHECK='TRUE';
      NO_DIR_CHECK='TRUE';
      ALLOW_CONNECT='TRUE';
    'VSS1782':
      PIN_NUMBER='(0,0,0,0,0,0,0,0,0,0,0,0,0,0,0,0,0,0,0,0,0,0,0,0,0,0,0,0,0,0,0,0,0,0,0,0,0,0,0,V28,0,0)';
      PINUSE='POWER';
      NO_LOAD_CHECK='Both';
      NO_IO_CHECK='Both';
      NO_ASSERT_CHECK='TRUE';
      NO_DIR_CHECK='TRUE';
      ALLOW_CONNECT='TRUE';
    'VSS1781':
      PIN_NUMBER='(0,0,0,0,0,0,0,0,0,0,0,0,0,0,0,0,0,0,0,0,0,0,0,0,0,0,0,0,0,0,0,0,0,0,0,0,0,0,0,V26,0,0)';
      PINUSE='POWER';
      NO_LOAD_CHECK='Both';
      NO_IO_CHECK='Both';
      NO_ASSERT_CHECK='TRUE';
      NO_DIR_CHECK='TRUE';
      ALLOW_CONNECT='TRUE';
    'VSS1780':
      PIN_NUMBER='(0,0,0,0,0,0,0,0,0,0,0,0,0,0,0,0,0,0,0,0,0,0,0,0,0,0,0,0,0,0,0,0,0,0,0,0,0,0,0,V24,0,0)';
      PINUSE='POWER';
      NO_LOAD_CHECK='Both';
      NO_IO_CHECK='Both';
      NO_ASSERT_CHECK='TRUE';
      NO_DIR_CHECK='TRUE';
      ALLOW_CONNECT='TRUE';
    'VSS1779':
      PIN_NUMBER='(0,0,0,0,0,0,0,0,0,0,0,0,0,0,0,0,0,0,0,0,0,0,0,0,0,0,0,0,0,0,0,0,0,0,0,0,0,0,0,V22,0,0)';
      PINUSE='POWER';
      NO_LOAD_CHECK='Both';
      NO_IO_CHECK='Both';
      NO_ASSERT_CHECK='TRUE';
      NO_DIR_CHECK='TRUE';
      ALLOW_CONNECT='TRUE';
    'VSS1778':
      PIN_NUMBER='(0,0,0,0,0,0,0,0,0,0,0,0,0,0,0,0,0,0,0,0,0,0,0,0,0,0,0,0,0,0,0,0,0,0,0,0,0,0,0,V20,0,0)';
      PINUSE='POWER';
      NO_LOAD_CHECK='Both';
      NO_IO_CHECK='Both';
      NO_ASSERT_CHECK='TRUE';
      NO_DIR_CHECK='TRUE';
      ALLOW_CONNECT='TRUE';
    'VSS1777':
      PIN_NUMBER='(0,0,0,0,0,0,0,0,0,0,0,0,0,0,0,0,0,0,0,0,0,0,0,0,0,0,0,0,0,0,0,0,0,0,0,0,0,0,0,V18,0,0)';
      PINUSE='POWER';
      NO_LOAD_CHECK='Both';
      NO_IO_CHECK='Both';
      NO_ASSERT_CHECK='TRUE';
      NO_DIR_CHECK='TRUE';
      ALLOW_CONNECT='TRUE';
    'VSS1776':
      PIN_NUMBER='(0,0,0,0,0,0,0,0,0,0,0,0,0,0,0,0,0,0,0,0,0,0,0,0,0,0,0,0,0,0,0,0,0,0,0,0,0,0,0,V16,0,0)';
      PINUSE='POWER';
      NO_LOAD_CHECK='Both';
      NO_IO_CHECK='Both';
      NO_ASSERT_CHECK='TRUE';
      NO_DIR_CHECK='TRUE';
      ALLOW_CONNECT='TRUE';
    'VSS1775':
      PIN_NUMBER='(0,0,0,0,0,0,0,0,0,0,0,0,0,0,0,0,0,0,0,0,0,0,0,0,0,0,0,0,0,0,0,0,0,0,0,0,0,0,0,V12,0,0)';
      PINUSE='POWER';
      NO_LOAD_CHECK='Both';
      NO_IO_CHECK='Both';
      NO_ASSERT_CHECK='TRUE';
      NO_DIR_CHECK='TRUE';
      ALLOW_CONNECT='TRUE';
    'VSS1774':
      PIN_NUMBER='(0,0,0,0,0,0,0,0,0,0,0,0,0,0,0,0,0,0,0,0,0,0,0,0,0,0,0,0,0,0,0,0,0,0,0,0,0,0,0,U88,0,0)';
      PINUSE='POWER';
      NO_LOAD_CHECK='Both';
      NO_IO_CHECK='Both';
      NO_ASSERT_CHECK='TRUE';
      NO_DIR_CHECK='TRUE';
      ALLOW_CONNECT='TRUE';
    'VSS1773':
      PIN_NUMBER='(0,0,0,0,0,0,0,0,0,0,0,0,0,0,0,0,0,0,0,0,0,0,0,0,0,0,0,0,0,0,0,0,0,0,0,0,0,0,0,U84,0,0)';
      PINUSE='POWER';
      NO_LOAD_CHECK='Both';
      NO_IO_CHECK='Both';
      NO_ASSERT_CHECK='TRUE';
      NO_DIR_CHECK='TRUE';
      ALLOW_CONNECT='TRUE';
    'VSS1772':
      PIN_NUMBER='(0,0,0,0,0,0,0,0,0,0,0,0,0,0,0,0,0,0,0,0,0,0,0,0,0,0,0,0,0,0,0,0,0,0,0,0,0,0,0,U82,0,0)';
      PINUSE='POWER';
      NO_LOAD_CHECK='Both';
      NO_IO_CHECK='Both';
      NO_ASSERT_CHECK='TRUE';
      NO_DIR_CHECK='TRUE';
      ALLOW_CONNECT='TRUE';
    'VSS1771':
      PIN_NUMBER='(0,0,0,0,0,0,0,0,0,0,0,0,0,0,0,0,0,0,0,0,0,0,0,0,0,0,0,0,0,0,0,0,0,0,0,0,0,0,0,U39,0,0)';
      PINUSE='POWER';
      NO_LOAD_CHECK='Both';
      NO_IO_CHECK='Both';
      NO_ASSERT_CHECK='TRUE';
      NO_DIR_CHECK='TRUE';
      ALLOW_CONNECT='TRUE';
    'VSS1770':
      PIN_NUMBER='(0,0,0,0,0,0,0,0,0,0,0,0,0,0,0,0,0,0,0,0,0,0,0,0,0,0,0,0,0,0,0,0,0,0,0,0,0,0,0,T83,0,0)';
      PINUSE='POWER';
      NO_LOAD_CHECK='Both';
      NO_IO_CHECK='Both';
      NO_ASSERT_CHECK='TRUE';
      NO_DIR_CHECK='TRUE';
      ALLOW_CONNECT='TRUE';
    'VSS1769':
      PIN_NUMBER='(0,0,0,0,0,0,0,0,0,0,0,0,0,0,0,0,0,0,0,0,0,0,0,0,0,0,0,0,0,0,0,0,0,0,0,0,0,0,0,T8,0,0)';
      PINUSE='POWER';
      NO_LOAD_CHECK='Both';
      NO_IO_CHECK='Both';
      NO_ASSERT_CHECK='TRUE';
      NO_DIR_CHECK='TRUE';
      ALLOW_CONNECT='TRUE';
    'VSS1768':
      PIN_NUMBER='(0,0,0,0,0,0,0,0,0,0,0,0,0,0,0,0,0,0,0,0,0,0,0,0,0,0,0,0,0,0,0,0,0,0,0,0,0,0,0,T79,0,0)';
      PINUSE='POWER';
      NO_LOAD_CHECK='Both';
      NO_IO_CHECK='Both';
      NO_ASSERT_CHECK='TRUE';
      NO_DIR_CHECK='TRUE';
      ALLOW_CONNECT='TRUE';
    'VSS1767':
      PIN_NUMBER='(0,0,0,0,0,0,0,0,0,0,0,0,0,0,0,0,0,0,0,0,0,0,0,0,0,0,0,0,0,0,0,0,0,0,0,0,0,0,0,T73,0,0)';
      PINUSE='POWER';
      NO_LOAD_CHECK='Both';
      NO_IO_CHECK='Both';
      NO_ASSERT_CHECK='TRUE';
      NO_DIR_CHECK='TRUE';
      ALLOW_CONNECT='TRUE';
    'VSS1766':
      PIN_NUMBER='(0,0,0,0,0,0,0,0,0,0,0,0,0,0,0,0,0,0,0,0,0,0,0,0,0,0,0,0,0,0,0,0,0,0,0,0,0,0,0,U52,0,0)';
      PINUSE='POWER';
      NO_LOAD_CHECK='Both';
      NO_IO_CHECK='Both';
      NO_ASSERT_CHECK='TRUE';
      NO_DIR_CHECK='TRUE';
      ALLOW_CONNECT='TRUE';
    'VSS1765':
      PIN_NUMBER='(0,0,0,0,0,0,0,0,0,0,0,0,0,0,0,0,0,0,0,0,0,0,0,0,0,0,0,0,0,0,0,0,0,0,0,0,0,0,0,T67,0,0)';
      PINUSE='POWER';
      NO_LOAD_CHECK='Both';
      NO_IO_CHECK='Both';
      NO_ASSERT_CHECK='TRUE';
      NO_DIR_CHECK='TRUE';
      ALLOW_CONNECT='TRUE';
    'VSS1764':
      PIN_NUMBER='(0,0,0,0,0,0,0,0,0,0,0,0,0,0,0,0,0,0,0,0,0,0,0,0,0,0,0,0,0,0,0,0,0,0,0,0,0,0,0,T61,0,0)';
      PINUSE='POWER';
      NO_LOAD_CHECK='Both';
      NO_IO_CHECK='Both';
      NO_ASSERT_CHECK='TRUE';
      NO_DIR_CHECK='TRUE';
      ALLOW_CONNECT='TRUE';
    'VSS1763':
      PIN_NUMBER='(0,0,0,0,0,0,0,0,0,0,0,0,0,0,0,0,0,0,0,0,0,0,0,0,0,0,0,0,0,0,0,0,0,0,0,0,0,0,0,T42,0,0)';
      PINUSE='POWER';
      NO_LOAD_CHECK='Both';
      NO_IO_CHECK='Both';
      NO_ASSERT_CHECK='TRUE';
      NO_DIR_CHECK='TRUE';
      ALLOW_CONNECT='TRUE';
    'VSS1762':
      PIN_NUMBER='(0,0,0,0,0,0,0,0,0,0,0,0,0,0,0,0,0,0,0,0,0,0,0,0,0,0,0,0,0,0,0,0,0,0,0,0,0,0,0,T4,0,0)';
      PINUSE='POWER';
      NO_LOAD_CHECK='Both';
      NO_IO_CHECK='Both';
      NO_ASSERT_CHECK='TRUE';
      NO_DIR_CHECK='TRUE';
      ALLOW_CONNECT='TRUE';
    'VSS1761':
      PIN_NUMBER='(0,0,0,0,0,0,0,0,0,0,0,0,0,0,0,0,0,0,0,0,0,0,0,0,0,0,0,0,0,0,0,0,0,0,0,0,0,0,0,T30,0,0)';
      PINUSE='POWER';
      NO_LOAD_CHECK='Both';
      NO_IO_CHECK='Both';
      NO_ASSERT_CHECK='TRUE';
      NO_DIR_CHECK='TRUE';
      ALLOW_CONNECT='TRUE';
    'VSS1760':
      PIN_NUMBER='(0,0,0,0,0,0,0,0,0,0,0,0,0,0,0,0,0,0,0,0,0,0,0,0,0,0,0,0,0,0,0,0,0,0,0,0,0,0,0,T24,0,0)';
      PINUSE='POWER';
      NO_LOAD_CHECK='Both';
      NO_IO_CHECK='Both';
      NO_ASSERT_CHECK='TRUE';
      NO_DIR_CHECK='TRUE';
      ALLOW_CONNECT='TRUE';
    'VSS1759':
      PIN_NUMBER='(0,0,0,0,0,0,0,0,0,0,0,0,0,0,0,0,0,0,0,0,0,0,0,0,0,0,0,0,0,0,0,0,0,0,0,0,0,0,0,R9,0,0)';
      PINUSE='POWER';
      NO_LOAD_CHECK='Both';
      NO_IO_CHECK='Both';
      NO_ASSERT_CHECK='TRUE';
      NO_DIR_CHECK='TRUE';
      ALLOW_CONNECT='TRUE';
    'VSS1758':
      PIN_NUMBER='(0,0,0,0,0,0,0,0,0,0,0,0,0,0,0,0,0,0,0,0,0,0,0,0,0,0,0,0,0,0,0,0,0,0,0,0,0,0,0,R88,0,0)';
      PINUSE='POWER';
      NO_LOAD_CHECK='Both';
      NO_IO_CHECK='Both';
      NO_ASSERT_CHECK='TRUE';
      NO_DIR_CHECK='TRUE';
      ALLOW_CONNECT='TRUE';
    'VSS1757':
      PIN_NUMBER='(0,0,0,0,0,0,0,0,0,0,0,0,0,0,0,0,0,0,0,0,0,0,0,0,0,0,0,0,0,0,0,0,0,0,0,0,0,0,0,R84,0,0)';
      PINUSE='POWER';
      NO_LOAD_CHECK='Both';
      NO_IO_CHECK='Both';
      NO_ASSERT_CHECK='TRUE';
      NO_DIR_CHECK='TRUE';
      ALLOW_CONNECT='TRUE';
    'VSS1756':
      PIN_NUMBER='(0,0,0,0,0,0,0,0,0,0,0,0,0,0,0,0,0,0,0,0,0,0,0,0,0,0,0,0,0,0,0,0,0,0,0,0,0,0,0,R78,0,0)';
      PINUSE='POWER';
      NO_LOAD_CHECK='Both';
      NO_IO_CHECK='Both';
      NO_ASSERT_CHECK='TRUE';
      NO_DIR_CHECK='TRUE';
      ALLOW_CONNECT='TRUE';
    'VSS1755':
      PIN_NUMBER='(0,0,0,0,0,0,0,0,0,0,0,0,0,0,0,0,0,0,0,0,0,0,0,0,0,0,0,0,0,0,0,0,0,0,0,0,0,0,0,R74,0,0)';
      PINUSE='POWER';
      NO_LOAD_CHECK='Both';
      NO_IO_CHECK='Both';
      NO_ASSERT_CHECK='TRUE';
      NO_DIR_CHECK='TRUE';
      ALLOW_CONNECT='TRUE';
    'VSS1754':
      PIN_NUMBER='(0,0,0,0,0,0,0,0,0,0,0,0,0,0,0,0,0,0,0,0,0,0,0,0,0,0,0,0,0,0,0,0,0,0,0,0,0,0,0,R72,0,0)';
      PINUSE='POWER';
      NO_LOAD_CHECK='Both';
      NO_IO_CHECK='Both';
      NO_ASSERT_CHECK='TRUE';
      NO_DIR_CHECK='TRUE';
      ALLOW_CONNECT='TRUE';
    'VSS1753':
      PIN_NUMBER='(0,0,0,0,0,0,0,0,0,0,0,0,0,0,0,0,0,0,0,0,0,0,0,0,0,0,0,0,0,0,0,0,0,0,0,0,0,0,0,R68,0,0)';
      PINUSE='POWER';
      NO_LOAD_CHECK='Both';
      NO_IO_CHECK='Both';
      NO_ASSERT_CHECK='TRUE';
      NO_DIR_CHECK='TRUE';
      ALLOW_CONNECT='TRUE';
    'VSS1752':
      PIN_NUMBER='(0,0,0,0,0,0,0,0,0,0,0,0,0,0,0,0,0,0,0,0,0,0,0,0,0,0,0,0,0,0,0,0,0,0,0,0,0,0,0,R62,0,0)';
      PINUSE='POWER';
      NO_LOAD_CHECK='Both';
      NO_IO_CHECK='Both';
      NO_ASSERT_CHECK='TRUE';
      NO_DIR_CHECK='TRUE';
      ALLOW_CONNECT='TRUE';
    'VSS1751':
      PIN_NUMBER='(0,0,0,0,0,0,0,0,0,0,0,0,0,0,0,0,0,0,0,0,0,0,0,0,0,0,0,0,0,0,0,0,0,0,0,0,0,0,0,R56,0,0)';
      PINUSE='POWER';
      NO_LOAD_CHECK='Both';
      NO_IO_CHECK='Both';
      NO_ASSERT_CHECK='TRUE';
      NO_DIR_CHECK='TRUE';
      ALLOW_CONNECT='TRUE';
    'VSS1750':
      PIN_NUMBER='(0,0,0,0,0,0,0,0,0,0,0,0,0,0,0,0,0,0,0,0,0,0,0,0,0,0,0,0,0,0,0,0,0,0,0,0,0,0,0,T55,0,0)';
      PINUSE='POWER';
      NO_LOAD_CHECK='Both';
      NO_IO_CHECK='Both';
      NO_ASSERT_CHECK='TRUE';
      NO_DIR_CHECK='TRUE';
      ALLOW_CONNECT='TRUE';
    'VSS1749':
      PIN_NUMBER='(0,0,0,0,0,0,0,0,0,0,0,0,0,0,0,0,0,0,0,0,0,0,0,0,0,0,0,0,0,0,0,0,0,0,0,0,0,0,0,T49,0,0)';
      PINUSE='POWER';
      NO_LOAD_CHECK='Both';
      NO_IO_CHECK='Both';
      NO_ASSERT_CHECK='TRUE';
      NO_DIR_CHECK='TRUE';
      ALLOW_CONNECT='TRUE';
    'VSS1748':
      PIN_NUMBER='(0,0,0,0,0,0,0,0,0,0,0,0,0,0,0,0,0,0,0,0,0,0,0,0,0,0,0,0,0,0,0,0,0,0,0,0,0,0,0,R54,0,0)';
      PINUSE='POWER';
      NO_LOAD_CHECK='Both';
      NO_IO_CHECK='Both';
      NO_ASSERT_CHECK='TRUE';
      NO_DIR_CHECK='TRUE';
      ALLOW_CONNECT='TRUE';
    'VSS1747':
      PIN_NUMBER='(0,0,0,0,0,0,0,0,0,0,0,0,0,0,0,0,0,0,0,0,0,0,0,0,0,0,0,0,0,0,0,0,0,0,0,0,0,0,0,R50,0,0)';
      PINUSE='POWER';
      NO_LOAD_CHECK='Both';
      NO_IO_CHECK='Both';
      NO_ASSERT_CHECK='TRUE';
      NO_DIR_CHECK='TRUE';
      ALLOW_CONNECT='TRUE';
    'VSS1746':
      PIN_NUMBER='(0,0,0,0,0,0,0,0,0,0,0,0,0,0,0,0,0,0,0,0,0,0,0,0,0,0,0,0,0,0,0,0,0,0,0,0,0,0,0,T36,0,0)';
      PINUSE='POWER';
      NO_LOAD_CHECK='Both';
      NO_IO_CHECK='Both';
      NO_ASSERT_CHECK='TRUE';
      NO_DIR_CHECK='TRUE';
      ALLOW_CONNECT='TRUE';
    'VSS1745':
      PIN_NUMBER='(0,0,0,0,0,0,0,0,0,0,0,0,0,0,0,0,0,0,0,0,0,0,0,0,0,0,0,0,0,0,0,0,0,0,0,0,0,0,0,R5,0,0)';
      PINUSE='POWER';
      NO_LOAD_CHECK='Both';
      NO_IO_CHECK='Both';
      NO_ASSERT_CHECK='TRUE';
      NO_DIR_CHECK='TRUE';
      ALLOW_CONNECT='TRUE';
    'VSS1744':
      PIN_NUMBER='(0,0,0,0,0,0,0,0,0,0,0,0,0,0,0,0,0,0,0,0,0,0,0,0,0,0,0,0,0,0,0,0,0,0,0,0,0,0,0,R43,0,0)';
      PINUSE='POWER';
      NO_LOAD_CHECK='Both';
      NO_IO_CHECK='Both';
      NO_ASSERT_CHECK='TRUE';
      NO_DIR_CHECK='TRUE';
      ALLOW_CONNECT='TRUE';
    'VSS1743':
      PIN_NUMBER='(0,0,0,0,0,0,0,0,0,0,0,0,0,0,0,0,0,0,0,0,0,0,0,0,0,0,0,0,0,0,0,0,0,0,0,0,0,0,0,R41,0,0)';
      PINUSE='POWER';
      NO_LOAD_CHECK='Both';
      NO_IO_CHECK='Both';
      NO_ASSERT_CHECK='TRUE';
      NO_DIR_CHECK='TRUE';
      ALLOW_CONNECT='TRUE';
    'VSS1742':
      PIN_NUMBER='(0,0,0,0,0,0,0,0,0,0,0,0,0,0,0,0,0,0,0,0,0,0,0,0,0,0,0,0,0,0,0,0,0,0,0,0,0,0,0,R37,0,0)';
      PINUSE='POWER';
      NO_LOAD_CHECK='Both';
      NO_IO_CHECK='Both';
      NO_ASSERT_CHECK='TRUE';
      NO_DIR_CHECK='TRUE';
      ALLOW_CONNECT='TRUE';
    'VSS1741':
      PIN_NUMBER='(0,0,0,0,0,0,0,0,0,0,0,0,0,0,0,0,0,0,0,0,0,0,0,0,0,0,0,0,0,0,0,0,0,0,0,0,0,0,0,T18,0,0)';
      PINUSE='POWER';
      NO_LOAD_CHECK='Both';
      NO_IO_CHECK='Both';
      NO_ASSERT_CHECK='TRUE';
      NO_DIR_CHECK='TRUE';
      ALLOW_CONNECT='TRUE';
    'VSS1740':
      PIN_NUMBER='(0,0,0,0,0,0,0,0,0,0,0,0,0,0,0,0,0,0,0,0,0,0,0,0,0,0,0,0,0,0,0,0,0,0,0,0,0,0,0,T16,0,0)';
      PINUSE='POWER';
      NO_LOAD_CHECK='Both';
      NO_IO_CHECK='Both';
      NO_ASSERT_CHECK='TRUE';
      NO_DIR_CHECK='TRUE';
      ALLOW_CONNECT='TRUE';
    'VSS1739':
      PIN_NUMBER='(0,0,0,0,0,0,0,0,0,0,0,0,0,0,0,0,0,0,0,0,0,0,0,0,0,0,0,0,0,0,0,0,0,0,0,0,0,0,0,T12,0,0)';
      PINUSE='POWER';
      NO_LOAD_CHECK='Both';
      NO_IO_CHECK='Both';
      NO_ASSERT_CHECK='TRUE';
      NO_DIR_CHECK='TRUE';
      ALLOW_CONNECT='TRUE';
    'VSS1738':
      PIN_NUMBER='(0,0,0,0,0,0,0,0,0,0,0,0,0,0,0,0,0,0,0,0,0,0,0,0,0,0,0,0,0,0,0,0,0,0,0,0,0,0,0,R35,0,0)';
      PINUSE='POWER';
      NO_LOAD_CHECK='Both';
      NO_IO_CHECK='Both';
      NO_ASSERT_CHECK='TRUE';
      NO_DIR_CHECK='TRUE';
      ALLOW_CONNECT='TRUE';
    'VSS1737':
      PIN_NUMBER='(0,0,0,0,0,0,0,0,0,0,0,0,0,0,0,0,0,0,0,0,0,0,0,0,0,0,0,0,0,0,0,0,0,0,0,0,0,0,0,R31,0,0)';
      PINUSE='POWER';
      NO_LOAD_CHECK='Both';
      NO_IO_CHECK='Both';
      NO_ASSERT_CHECK='TRUE';
      NO_DIR_CHECK='TRUE';
      ALLOW_CONNECT='TRUE';
    'VSS1736':
      PIN_NUMBER='(0,0,0,0,0,0,0,0,0,0,0,0,0,0,0,0,0,0,0,0,0,0,0,0,0,0,0,0,0,0,0,0,0,0,0,0,0,0,0,R29,0,0)';
      PINUSE='POWER';
      NO_LOAD_CHECK='Both';
      NO_IO_CHECK='Both';
      NO_ASSERT_CHECK='TRUE';
      NO_DIR_CHECK='TRUE';
      ALLOW_CONNECT='TRUE';
    'VSS1735':
      PIN_NUMBER='(0,0,0,0,0,0,0,0,0,0,0,0,0,0,0,0,0,0,0,0,0,0,0,0,0,0,0,0,0,0,0,0,0,0,0,0,0,0,0,R25,0,0)';
      PINUSE='POWER';
      NO_LOAD_CHECK='Both';
      NO_IO_CHECK='Both';
      NO_ASSERT_CHECK='TRUE';
      NO_DIR_CHECK='TRUE';
      ALLOW_CONNECT='TRUE';
    'VSS1734':
      PIN_NUMBER='(0,0,0,0,0,0,0,0,0,0,0,0,0,0,0,0,0,0,0,0,0,0,0,0,0,0,0,0,0,0,0,0,0,0,0,0,0,0,0,R17,0,0)';
      PINUSE='POWER';
      NO_LOAD_CHECK='Both';
      NO_IO_CHECK='Both';
      NO_ASSERT_CHECK='TRUE';
      NO_DIR_CHECK='TRUE';
      ALLOW_CONNECT='TRUE';
    'VSS1733':
      PIN_NUMBER='(0,0,0,0,0,0,0,0,0,0,0,0,0,0,0,0,0,0,0,0,0,0,0,0,0,0,0,0,0,0,0,0,0,0,0,0,0,0,0,R13,0,0)';
      PINUSE='POWER';
      NO_LOAD_CHECK='Both';
      NO_IO_CHECK='Both';
      NO_ASSERT_CHECK='TRUE';
      NO_DIR_CHECK='TRUE';
      ALLOW_CONNECT='TRUE';
    'VSS1732':
      PIN_NUMBER='(0,0,0,0,0,0,0,0,0,0,0,0,0,0,0,0,0,0,0,0,0,0,0,0,0,0,0,0,0,0,0,0,0,0,0,0,0,0,0,P91,0,0)';
      PINUSE='POWER';
      NO_LOAD_CHECK='Both';
      NO_IO_CHECK='Both';
      NO_ASSERT_CHECK='TRUE';
      NO_DIR_CHECK='TRUE';
      ALLOW_CONNECT='TRUE';
    'VSS1731':
      PIN_NUMBER='(0,0,0,0,0,0,0,0,0,0,0,0,0,0,0,0,0,0,0,0,0,0,0,0,0,0,0,0,0,0,0,0,0,0,0,0,0,0,0,P87,0,0)';
      PINUSE='POWER';
      NO_LOAD_CHECK='Both';
      NO_IO_CHECK='Both';
      NO_ASSERT_CHECK='TRUE';
      NO_DIR_CHECK='TRUE';
      ALLOW_CONNECT='TRUE';
    'VSS1730':
      PIN_NUMBER='(0,0,0,0,0,0,0,0,0,0,0,0,0,0,0,0,0,0,0,0,0,0,0,0,0,0,0,0,0,0,0,0,0,0,0,0,0,0,0,R66,0,0)';
      PINUSE='POWER';
      NO_LOAD_CHECK='Both';
      NO_IO_CHECK='Both';
      NO_ASSERT_CHECK='TRUE';
      NO_DIR_CHECK='TRUE';
      ALLOW_CONNECT='TRUE';
    'VSS1729':
      PIN_NUMBER='(0,0,0,0,0,0,0,0,0,0,0,0,0,0,0,0,0,0,0,0,0,0,0,0,0,0,0,0,0,0,0,0,0,0,0,0,0,0,0,P8,0,0)';
      PINUSE='POWER';
      NO_LOAD_CHECK='Both';
      NO_IO_CHECK='Both';
      NO_ASSERT_CHECK='TRUE';
      NO_DIR_CHECK='TRUE';
      ALLOW_CONNECT='TRUE';
    'VSS1728':
      PIN_NUMBER='(0,0,0,0,0,0,0,0,0,0,0,0,0,0,0,0,0,0,0,0,0,0,0,0,0,0,0,0,0,0,0,0,0,0,0,0,0,0,0,R60,0,0)';
      PINUSE='POWER';
      NO_LOAD_CHECK='Both';
      NO_IO_CHECK='Both';
      NO_ASSERT_CHECK='TRUE';
      NO_DIR_CHECK='TRUE';
      ALLOW_CONNECT='TRUE';
    'VSS1727':
      PIN_NUMBER='(0,0,0,0,0,0,0,0,0,0,0,0,0,0,0,0,0,0,0,0,0,0,0,0,0,0,0,0,0,0,0,0,0,0,0,0,0,0,0,P77,0,0)';
      PINUSE='POWER';
      NO_LOAD_CHECK='Both';
      NO_IO_CHECK='Both';
      NO_ASSERT_CHECK='TRUE';
      NO_DIR_CHECK='TRUE';
      ALLOW_CONNECT='TRUE';
    'VSS1726':
      PIN_NUMBER='(0,0,0,0,0,0,0,0,0,0,0,0,0,0,0,0,0,0,0,0,0,0,0,0,0,0,0,0,0,0,0,0,0,0,0,0,0,0,0,P75,0,0)';
      PINUSE='POWER';
      NO_LOAD_CHECK='Both';
      NO_IO_CHECK='Both';
      NO_ASSERT_CHECK='TRUE';
      NO_DIR_CHECK='TRUE';
      ALLOW_CONNECT='TRUE';
    'VSS1725':
      PIN_NUMBER='(0,0,0,0,0,0,0,0,0,0,0,0,0,0,0,0,0,0,0,0,0,0,0,0,0,0,0,0,0,0,0,0,0,0,0,0,0,0,0,P69,0,0)';
      PINUSE='POWER';
      NO_LOAD_CHECK='Both';
      NO_IO_CHECK='Both';
      NO_ASSERT_CHECK='TRUE';
      NO_DIR_CHECK='TRUE';
      ALLOW_CONNECT='TRUE';
    'VSS1724':
      PIN_NUMBER='(0,0,0,0,0,0,0,0,0,0,0,0,0,0,0,0,0,0,0,0,0,0,0,0,0,0,0,0,0,0,0,0,0,0,0,0,0,0,0,P65,0,0)';
      PINUSE='POWER';
      NO_LOAD_CHECK='Both';
      NO_IO_CHECK='Both';
      NO_ASSERT_CHECK='TRUE';
      NO_DIR_CHECK='TRUE';
      ALLOW_CONNECT='TRUE';
    'VSS1723':
      PIN_NUMBER='(0,0,0,0,0,0,0,0,0,0,0,0,0,0,0,0,0,0,0,0,0,0,0,0,0,0,0,0,0,0,0,0,0,0,0,0,0,0,0,R48,0,0)';
      PINUSE='POWER';
      NO_LOAD_CHECK='Both';
      NO_IO_CHECK='Both';
      NO_ASSERT_CHECK='TRUE';
      NO_DIR_CHECK='TRUE';
      ALLOW_CONNECT='TRUE';
    'VSS1722':
      PIN_NUMBER='(0,0,0,0,0,0,0,0,0,0,0,0,0,0,0,0,0,0,0,0,0,0,0,0,0,0,0,0,0,0,0,0,0,0,0,0,0,0,0,P63,0,0)';
      PINUSE='POWER';
      NO_LOAD_CHECK='Both';
      NO_IO_CHECK='Both';
      NO_ASSERT_CHECK='TRUE';
      NO_DIR_CHECK='TRUE';
      ALLOW_CONNECT='TRUE';
    'VSS1721':
      PIN_NUMBER='(0,0,0,0,0,0,0,0,0,0,0,0,0,0,0,0,0,0,0,0,0,0,0,0,0,0,0,0,0,0,0,0,0,0,0,0,0,0,0,P59,0,0)';
      PINUSE='POWER';
      NO_LOAD_CHECK='Both';
      NO_IO_CHECK='Both';
      NO_ASSERT_CHECK='TRUE';
      NO_DIR_CHECK='TRUE';
      ALLOW_CONNECT='TRUE';
    'VSS1720':
      PIN_NUMBER='(0,0,0,0,0,0,0,0,0,0,0,0,0,0,0,0,0,0,0,0,0,0,0,0,0,0,0,0,0,0,0,0,0,0,0,0,0,0,0,P53,0,0)';
      PINUSE='POWER';
      NO_LOAD_CHECK='Both';
      NO_IO_CHECK='Both';
      NO_ASSERT_CHECK='TRUE';
      NO_DIR_CHECK='TRUE';
      ALLOW_CONNECT='TRUE';
    'VSS1719':
      PIN_NUMBER='(0,0,0,0,0,0,0,0,0,0,0,0,0,0,0,0,0,0,0,0,0,0,0,0,0,0,0,0,0,0,0,0,0,0,0,0,0,0,0,P47,0,0)';
      PINUSE='POWER';
      NO_LOAD_CHECK='Both';
      NO_IO_CHECK='Both';
      NO_ASSERT_CHECK='TRUE';
      NO_DIR_CHECK='TRUE';
      ALLOW_CONNECT='TRUE';
    'VSS1718':
      PIN_NUMBER='(0,0,0,0,0,0,0,0,0,0,0,0,0,0,0,0,0,0,0,0,0,0,0,0,0,0,0,0,0,0,0,0,0,0,0,0,0,0,0,P44,0,0)';
      PINUSE='POWER';
      NO_LOAD_CHECK='Both';
      NO_IO_CHECK='Both';
      NO_ASSERT_CHECK='TRUE';
      NO_DIR_CHECK='TRUE';
      ALLOW_CONNECT='TRUE';
    'VSS1717':
      PIN_NUMBER='(0,0,0,0,0,0,0,0,0,0,0,0,0,0,0,0,0,0,0,0,0,0,0,0,0,0,0,0,0,0,0,0,0,0,0,0,0,0,0,P40,0,0)';
      PINUSE='POWER';
      NO_LOAD_CHECK='Both';
      NO_IO_CHECK='Both';
      NO_ASSERT_CHECK='TRUE';
      NO_DIR_CHECK='TRUE';
      ALLOW_CONNECT='TRUE';
    'VSS1716':
      PIN_NUMBER='(0,0,0,0,0,0,0,0,0,0,0,0,0,0,0,0,0,0,0,0,0,0,0,0,0,0,0,0,0,0,0,0,0,0,0,0,0,0,0,P4,0,0)';
      PINUSE='POWER';
      NO_LOAD_CHECK='Both';
      NO_IO_CHECK='Both';
      NO_ASSERT_CHECK='TRUE';
      NO_DIR_CHECK='TRUE';
      ALLOW_CONNECT='TRUE';
    'VSS1715':
      PIN_NUMBER='(0,0,0,0,0,0,0,0,0,0,0,0,0,0,0,0,0,0,0,0,0,0,0,0,0,0,0,0,0,0,0,0,0,0,0,0,0,0,0,R23,0,0)';
      PINUSE='POWER';
      NO_LOAD_CHECK='Both';
      NO_IO_CHECK='Both';
      NO_ASSERT_CHECK='TRUE';
      NO_DIR_CHECK='TRUE';
      ALLOW_CONNECT='TRUE';
    'VSS1714':
      PIN_NUMBER='(0,0,0,0,0,0,0,0,0,0,0,0,0,0,0,0,0,0,0,0,0,0,0,0,0,0,0,0,0,0,0,0,0,0,0,0,0,0,0,R19,0,0)';
      PINUSE='POWER';
      NO_LOAD_CHECK='Both';
      NO_IO_CHECK='Both';
      NO_ASSERT_CHECK='TRUE';
      NO_DIR_CHECK='TRUE';
      ALLOW_CONNECT='TRUE';
    'VSS1713':
      PIN_NUMBER='(0,0,0,0,0,0,0,0,0,0,0,0,0,0,0,0,0,0,0,0,0,0,0,0,0,0,0,0,0,0,0,0,0,0,0,0,0,0,0,P38,0,0)';
      PINUSE='POWER';
      NO_LOAD_CHECK='Both';
      NO_IO_CHECK='Both';
      NO_ASSERT_CHECK='TRUE';
      NO_DIR_CHECK='TRUE';
      ALLOW_CONNECT='TRUE';
    'VSS1712':
      PIN_NUMBER='(0,0,0,0,0,0,0,0,0,0,0,0,0,0,0,0,0,0,0,0,0,0,0,0,0,0,0,0,0,0,0,0,0,0,0,0,0,0,0,P34,0,0)';
      PINUSE='POWER';
      NO_LOAD_CHECK='Both';
      NO_IO_CHECK='Both';
      NO_ASSERT_CHECK='TRUE';
      NO_DIR_CHECK='TRUE';
      ALLOW_CONNECT='TRUE';
    'VSS1711':
      PIN_NUMBER='(0,0,0,0,0,0,0,0,0,0,0,0,0,0,0,0,0,0,0,0,0,0,0,0,0,0,0,0,0,0,0,0,0,0,0,0,0,0,0,R1,0,0)';
      PINUSE='POWER';
      NO_LOAD_CHECK='Both';
      NO_IO_CHECK='Both';
      NO_ASSERT_CHECK='TRUE';
      NO_DIR_CHECK='TRUE';
      ALLOW_CONNECT='TRUE';
    'VSS1710':
      PIN_NUMBER='(0,0,0,0,0,0,0,0,0,0,0,0,0,0,0,0,0,0,0,0,0,0,0,0,0,0,0,0,0,0,0,0,0,0,0,0,0,0,0,P28,0,0)';
      PINUSE='POWER';
      NO_LOAD_CHECK='Both';
      NO_IO_CHECK='Both';
      NO_ASSERT_CHECK='TRUE';
      NO_DIR_CHECK='TRUE';
      ALLOW_CONNECT='TRUE';
    'VSS1709':
      PIN_NUMBER='(0,0,0,0,0,0,0,0,0,0,0,0,0,0,0,0,0,0,0,0,0,0,0,0,0,0,0,0,0,0,0,0,0,0,0,0,0,0,0,P26,0,0)';
      PINUSE='POWER';
      NO_LOAD_CHECK='Both';
      NO_IO_CHECK='Both';
      NO_ASSERT_CHECK='TRUE';
      NO_DIR_CHECK='TRUE';
      ALLOW_CONNECT='TRUE';
    'VSS1708':
      PIN_NUMBER='(0,0,0,0,0,0,0,0,0,0,0,0,0,0,0,0,0,0,0,0,0,0,0,0,0,0,0,0,0,0,0,0,0,0,0,0,0,0,0,P22,0,0)';
      PINUSE='POWER';
      NO_LOAD_CHECK='Both';
      NO_IO_CHECK='Both';
      NO_ASSERT_CHECK='TRUE';
      NO_DIR_CHECK='TRUE';
      ALLOW_CONNECT='TRUE';
    'VSS1707':
      PIN_NUMBER='(0,0,0,0,0,0,0,0,0,0,0,0,0,0,0,0,0,0,0,0,0,0,0,0,0,0,0,0,0,0,0,0,0,0,0,0,0,0,0,P20,0,0)';
      PINUSE='POWER';
      NO_LOAD_CHECK='Both';
      NO_IO_CHECK='Both';
      NO_ASSERT_CHECK='TRUE';
      NO_DIR_CHECK='TRUE';
      ALLOW_CONNECT='TRUE';
    'VSS1706':
      PIN_NUMBER='(0,0,0,0,0,0,0,0,0,0,0,0,0,0,0,0,0,0,0,0,0,0,0,0,0,0,0,0,0,0,0,0,0,0,0,0,0,0,0,P16,0,0)';
      PINUSE='POWER';
      NO_LOAD_CHECK='Both';
      NO_IO_CHECK='Both';
      NO_ASSERT_CHECK='TRUE';
      NO_DIR_CHECK='TRUE';
      ALLOW_CONNECT='TRUE';
    'VSS1705':
      PIN_NUMBER='(0,0,0,0,0,0,0,0,0,0,0,0,0,0,0,0,0,0,0,0,0,0,0,0,0,0,0,0,0,0,0,0,0,0,0,0,0,0,0,P12,0,0)';
      PINUSE='POWER';
      NO_LOAD_CHECK='Both';
      NO_IO_CHECK='Both';
      NO_ASSERT_CHECK='TRUE';
      NO_DIR_CHECK='TRUE';
      ALLOW_CONNECT='TRUE';
    'VSS1704':
      PIN_NUMBER='(0,0,0,0,0,0,0,0,0,0,0,0,0,0,0,0,0,0,0,0,0,0,0,0,0,0,0,0,0,0,0,0,0,0,0,0,0,0,0,P71,0,0)';
      PINUSE='POWER';
      NO_LOAD_CHECK='Both';
      NO_IO_CHECK='Both';
      NO_ASSERT_CHECK='TRUE';
      NO_DIR_CHECK='TRUE';
      ALLOW_CONNECT='TRUE';
    'VSS1703':
      PIN_NUMBER='(0,0,0,0,0,0,0,0,0,0,0,0,0,0,0,0,0,0,0,0,0,0,0,0,0,0,0,0,0,0,0,0,0,0,0,0,0,0,0,N88,0,0)';
      PINUSE='POWER';
      NO_LOAD_CHECK='Both';
      NO_IO_CHECK='Both';
      NO_ASSERT_CHECK='TRUE';
      NO_DIR_CHECK='TRUE';
      ALLOW_CONNECT='TRUE';
    'VSS1702':
      PIN_NUMBER='(0,0,0,0,0,0,0,0,0,0,0,0,0,0,0,0,0,0,0,0,0,0,0,0,0,0,0,0,0,0,0,0,0,0,0,0,0,0,0,N84,0,0)';
      PINUSE='POWER';
      NO_LOAD_CHECK='Both';
      NO_IO_CHECK='Both';
      NO_ASSERT_CHECK='TRUE';
      NO_DIR_CHECK='TRUE';
      ALLOW_CONNECT='TRUE';
    'VSS1701':
      PIN_NUMBER='(0,0,0,0,0,0,0,0,0,0,0,0,0,0,0,0,0,0,0,0,0,0,0,0,0,0,0,0,0,0,0,0,0,0,0,0,0,0,0,N82,0,0)';
      PINUSE='POWER';
      NO_LOAD_CHECK='Both';
      NO_IO_CHECK='Both';
      NO_ASSERT_CHECK='TRUE';
      NO_DIR_CHECK='TRUE';
      ALLOW_CONNECT='TRUE';
    'VSS1700':
      PIN_NUMBER='(0,0,0,0,0,0,0,0,0,0,0,0,0,0,0,0,0,0,0,0,0,0,0,0,0,0,0,0,0,0,0,0,0,0,0,0,0,0,0,N80,0,0)';
      PINUSE='POWER';
      NO_LOAD_CHECK='Both';
      NO_IO_CHECK='Both';
      NO_ASSERT_CHECK='TRUE';
      NO_DIR_CHECK='TRUE';
      ALLOW_CONNECT='TRUE';
    'VSS1699':
      PIN_NUMBER='(0,0,0,0,0,0,0,0,0,0,0,0,0,0,0,0,0,0,0,0,0,0,0,0,0,0,0,0,0,0,0,0,0,0,0,0,0,0,0,P57,0,0)';
      PINUSE='POWER';
      NO_LOAD_CHECK='Both';
      NO_IO_CHECK='Both';
      NO_ASSERT_CHECK='TRUE';
      NO_DIR_CHECK='TRUE';
      ALLOW_CONNECT='TRUE';
    'VSS1698':
      PIN_NUMBER='(0,0,0,0,0,0,0,0,0,0,0,0,0,0,0,0,0,0,0,0,0,0,0,0,0,0,0,0,0,0,0,0,0,0,0,0,0,0,0,N78,0,0)';
      PINUSE='POWER';
      NO_LOAD_CHECK='Both';
      NO_IO_CHECK='Both';
      NO_ASSERT_CHECK='TRUE';
      NO_DIR_CHECK='TRUE';
      ALLOW_CONNECT='TRUE';
    'VSS1697':
      PIN_NUMBER='(0,0,0,0,0,0,0,0,0,0,0,0,0,0,0,0,0,0,0,0,0,0,0,0,0,0,0,0,0,0,0,0,0,0,0,0,0,0,0,P51,0,0)';
      PINUSE='POWER';
      NO_LOAD_CHECK='Both';
      NO_IO_CHECK='Both';
      NO_ASSERT_CHECK='TRUE';
      NO_DIR_CHECK='TRUE';
      ALLOW_CONNECT='TRUE';
    'VSS1696':
      PIN_NUMBER='(0,0,0,0,0,0,0,0,0,0,0,0,0,0,0,0,0,0,0,0,0,0,0,0,0,0,0,0,0,0,0,0,0,0,0,0,0,0,0,N76,0,0)';
      PINUSE='POWER';
      NO_LOAD_CHECK='Both';
      NO_IO_CHECK='Both';
      NO_ASSERT_CHECK='TRUE';
      NO_DIR_CHECK='TRUE';
      ALLOW_CONNECT='TRUE';
    'VSS1690':
      PIN_NUMBER='(0,0,0,0,0,0,0,0,0,0,0,0,0,0,0,0,0,0,0,0,0,0,0,0,0,0,0,0,0,0,0,0,0,0,0,0,0,0,0,P32,0,0)';
      PINUSE='POWER';
      NO_LOAD_CHECK='Both';
      NO_IO_CHECK='Both';
      NO_ASSERT_CHECK='TRUE';
      NO_DIR_CHECK='TRUE';
      ALLOW_CONNECT='TRUE';
    'VSS37':
      PIN_NUMBER='(0,0,0,0,0,0,0,0,0,0,0,0,0,0,0,0,0,0,0,0,0,0,0,0,0,0,0,0,0,0,0,0,0,0,0,0,0,0,0,AA80,0,0)';
      PINUSE='POWER';
      NO_LOAD_CHECK='Both';
      NO_IO_CHECK='Both';
      NO_ASSERT_CHECK='TRUE';
      NO_DIR_CHECK='TRUE';
      ALLOW_CONNECT='TRUE';
    'VSS36':
      PIN_NUMBER='(0,0,0,0,0,0,0,0,0,0,0,0,0,0,0,0,0,0,0,0,0,0,0,0,0,0,0,0,0,0,0,0,0,0,0,0,0,0,0,AA78,0,0)';
      PINUSE='POWER';
      NO_LOAD_CHECK='Both';
      NO_IO_CHECK='Both';
      NO_ASSERT_CHECK='TRUE';
      NO_DIR_CHECK='TRUE';
      ALLOW_CONNECT='TRUE';
    'VSS35':
      PIN_NUMBER='(0,0,0,0,0,0,0,0,0,0,0,0,0,0,0,0,0,0,0,0,0,0,0,0,0,0,0,0,0,0,0,0,0,0,0,0,0,0,0,AA74,0,0)';
      PINUSE='POWER';
      NO_LOAD_CHECK='Both';
      NO_IO_CHECK='Both';
      NO_ASSERT_CHECK='TRUE';
      NO_DIR_CHECK='TRUE';
      ALLOW_CONNECT='TRUE';
    'VSS34':
      PIN_NUMBER='(0,0,0,0,0,0,0,0,0,0,0,0,0,0,0,0,0,0,0,0,0,0,0,0,0,0,0,0,0,0,0,0,0,0,0,0,0,0,0,AA72,0,0)';
      PINUSE='POWER';
      NO_LOAD_CHECK='Both';
      NO_IO_CHECK='Both';
      NO_ASSERT_CHECK='TRUE';
      NO_DIR_CHECK='TRUE';
      ALLOW_CONNECT='TRUE';
    'VSS33':
      PIN_NUMBER='(0,0,0,0,0,0,0,0,0,0,0,0,0,0,0,0,0,0,0,0,0,0,0,0,0,0,0,0,0,0,0,0,0,0,0,0,0,0,0,AA68,0,0)';
      PINUSE='POWER';
      NO_LOAD_CHECK='Both';
      NO_IO_CHECK='Both';
      NO_ASSERT_CHECK='TRUE';
      NO_DIR_CHECK='TRUE';
      ALLOW_CONNECT='TRUE';
    'VSS32':
      PIN_NUMBER='(0,0,0,0,0,0,0,0,0,0,0,0,0,0,0,0,0,0,0,0,0,0,0,0,0,0,0,0,0,0,0,0,0,0,0,0,0,0,0,AA66,0,0)';
      PINUSE='POWER';
      NO_LOAD_CHECK='Both';
      NO_IO_CHECK='Both';
      NO_ASSERT_CHECK='TRUE';
      NO_DIR_CHECK='TRUE';
      ALLOW_CONNECT='TRUE';
    'VSS31':
      PIN_NUMBER='(0,0,0,0,0,0,0,0,0,0,0,0,0,0,0,0,0,0,0,0,0,0,0,0,0,0,0,0,0,0,0,0,0,0,0,0,0,0,0,AA62,0,0)';
      PINUSE='POWER';
      NO_LOAD_CHECK='Both';
      NO_IO_CHECK='Both';
      NO_ASSERT_CHECK='TRUE';
      NO_DIR_CHECK='TRUE';
      ALLOW_CONNECT='TRUE';
    'VSS30':
      PIN_NUMBER='(0,0,0,0,0,0,0,0,0,0,0,0,0,0,0,0,0,0,0,0,0,0,0,0,0,0,0,0,0,0,0,0,0,0,0,0,0,0,0,AA60,0,0)';
      PINUSE='POWER';
      NO_LOAD_CHECK='Both';
      NO_IO_CHECK='Both';
      NO_ASSERT_CHECK='TRUE';
      NO_DIR_CHECK='TRUE';
      ALLOW_CONNECT='TRUE';
    'VSS29':
      PIN_NUMBER='(0,0,0,0,0,0,0,0,0,0,0,0,0,0,0,0,0,0,0,0,0,0,0,0,0,0,0,0,0,0,0,0,0,0,0,0,0,0,0,AA56,0,0)';
      PINUSE='POWER';
      NO_LOAD_CHECK='Both';
      NO_IO_CHECK='Both';
      NO_ASSERT_CHECK='TRUE';
      NO_DIR_CHECK='TRUE';
      ALLOW_CONNECT='TRUE';
    'VSS28':
      PIN_NUMBER='(0,0,0,0,0,0,0,0,0,0,0,0,0,0,0,0,0,0,0,0,0,0,0,0,0,0,0,0,0,0,0,0,0,0,0,0,0,0,0,AA54,0,0)';
      PINUSE='POWER';
      NO_LOAD_CHECK='Both';
      NO_IO_CHECK='Both';
      NO_ASSERT_CHECK='TRUE';
      NO_DIR_CHECK='TRUE';
      ALLOW_CONNECT='TRUE';
    'VSS27':
      PIN_NUMBER='(0,0,0,0,0,0,0,0,0,0,0,0,0,0,0,0,0,0,0,0,0,0,0,0,0,0,0,0,0,0,0,0,0,0,0,0,0,0,0,AA50,0,0)';
      PINUSE='POWER';
      NO_LOAD_CHECK='Both';
      NO_IO_CHECK='Both';
      NO_ASSERT_CHECK='TRUE';
      NO_DIR_CHECK='TRUE';
      ALLOW_CONNECT='TRUE';
    'VSS26':
      PIN_NUMBER='(0,0,0,0,0,0,0,0,0,0,0,0,0,0,0,0,0,0,0,0,0,0,0,0,0,0,0,0,0,0,0,0,0,0,0,0,0,0,0,AA48,0,0)';
      PINUSE='POWER';
      NO_LOAD_CHECK='Both';
      NO_IO_CHECK='Both';
      NO_ASSERT_CHECK='TRUE';
      NO_DIR_CHECK='TRUE';
      ALLOW_CONNECT='TRUE';
    'VSS25':
      PIN_NUMBER='(0,0,0,0,0,0,0,0,0,0,0,0,0,0,0,0,0,0,0,0,0,0,0,0,0,0,0,0,0,0,0,0,0,0,0,0,0,0,0,AA43,0,0)';
      PINUSE='POWER';
      NO_LOAD_CHECK='Both';
      NO_IO_CHECK='Both';
      NO_ASSERT_CHECK='TRUE';
      NO_DIR_CHECK='TRUE';
      ALLOW_CONNECT='TRUE';
    'VSS24':
      PIN_NUMBER='(0,0,0,0,0,0,0,0,0,0,0,0,0,0,0,0,0,0,0,0,0,0,0,0,0,0,0,0,0,0,0,0,0,0,0,0,0,0,0,AA41,0,0)';
      PINUSE='POWER';
      NO_LOAD_CHECK='Both';
      NO_IO_CHECK='Both';
      NO_ASSERT_CHECK='TRUE';
      NO_DIR_CHECK='TRUE';
      ALLOW_CONNECT='TRUE';
    'VSS23':
      PIN_NUMBER='(0,0,0,0,0,0,0,0,0,0,0,0,0,0,0,0,0,0,0,0,0,0,0,0,0,0,0,0,0,0,0,0,0,0,0,0,0,0,0,AA37,0,0)';
      PINUSE='POWER';
      NO_LOAD_CHECK='Both';
      NO_IO_CHECK='Both';
      NO_ASSERT_CHECK='TRUE';
      NO_DIR_CHECK='TRUE';
      ALLOW_CONNECT='TRUE';
    'VSS22':
      PIN_NUMBER='(0,0,0,0,0,0,0,0,0,0,0,0,0,0,0,0,0,0,0,0,0,0,0,0,0,0,0,0,0,0,0,0,0,0,0,0,0,0,0,AA35,0,0)';
      PINUSE='POWER';
      NO_LOAD_CHECK='Both';
      NO_IO_CHECK='Both';
      NO_ASSERT_CHECK='TRUE';
      NO_DIR_CHECK='TRUE';
      ALLOW_CONNECT='TRUE';
    'VSS21':
      PIN_NUMBER='(0,0,0,0,0,0,0,0,0,0,0,0,0,0,0,0,0,0,0,0,0,0,0,0,0,0,0,0,0,0,0,0,0,0,0,0,0,0,0,AA31,0,0)';
      PINUSE='POWER';
      NO_LOAD_CHECK='Both';
      NO_IO_CHECK='Both';
      NO_ASSERT_CHECK='TRUE';
      NO_DIR_CHECK='TRUE';
      ALLOW_CONNECT='TRUE';
    'VSS20':
      PIN_NUMBER='(0,0,0,0,0,0,0,0,0,0,0,0,0,0,0,0,0,0,0,0,0,0,0,0,0,0,0,0,0,0,0,0,0,0,0,0,0,0,0,AA29,0,0)';
      PINUSE='POWER';
      NO_LOAD_CHECK='Both';
      NO_IO_CHECK='Both';
      NO_ASSERT_CHECK='TRUE';
      NO_DIR_CHECK='TRUE';
      ALLOW_CONNECT='TRUE';
    'VSS19':
      PIN_NUMBER='(0,0,0,0,0,0,0,0,0,0,0,0,0,0,0,0,0,0,0,0,0,0,0,0,0,0,0,0,0,0,0,0,0,0,0,0,0,0,0,AA25,0,0)';
      PINUSE='POWER';
      NO_LOAD_CHECK='Both';
      NO_IO_CHECK='Both';
      NO_ASSERT_CHECK='TRUE';
      NO_DIR_CHECK='TRUE';
      ALLOW_CONNECT='TRUE';
    'VSS18':
      PIN_NUMBER='(0,0,0,0,0,0,0,0,0,0,0,0,0,0,0,0,0,0,0,0,0,0,0,0,0,0,0,0,0,0,0,0,0,0,0,0,0,0,0,AA23,0,0)';
      PINUSE='POWER';
      NO_LOAD_CHECK='Both';
      NO_IO_CHECK='Both';
      NO_ASSERT_CHECK='TRUE';
      NO_DIR_CHECK='TRUE';
      ALLOW_CONNECT='TRUE';
    'VSS17':
      PIN_NUMBER='(0,0,0,0,0,0,0,0,0,0,0,0,0,0,0,0,0,0,0,0,0,0,0,0,0,0,0,0,0,0,0,0,0,0,0,0,0,0,0,AA19,0,0)';
      PINUSE='POWER';
      NO_LOAD_CHECK='Both';
      NO_IO_CHECK='Both';
      NO_ASSERT_CHECK='TRUE';
      NO_DIR_CHECK='TRUE';
      ALLOW_CONNECT='TRUE';
    'VSS1695':
      PIN_NUMBER='(0,0,0,0,0,0,0,0,0,0,0,0,0,0,0,0,0,0,0,0,0,0,0,0,0,0,0,0,0,0,0,0,0,0,0,0,0,0,0,0,N70,0)';
      PINUSE='POWER';
      NO_LOAD_CHECK='Both';
      NO_IO_CHECK='Both';
      NO_ASSERT_CHECK='TRUE';
      NO_DIR_CHECK='TRUE';
      ALLOW_CONNECT='TRUE';
    'VSS1694':
      PIN_NUMBER='(0,0,0,0,0,0,0,0,0,0,0,0,0,0,0,0,0,0,0,0,0,0,0,0,0,0,0,0,0,0,0,0,0,0,0,0,0,0,0,0,N58,0)';
      PINUSE='POWER';
      NO_LOAD_CHECK='Both';
      NO_IO_CHECK='Both';
      NO_ASSERT_CHECK='TRUE';
      NO_DIR_CHECK='TRUE';
      ALLOW_CONNECT='TRUE';
    'VSS1693':
      PIN_NUMBER='(0,0,0,0,0,0,0,0,0,0,0,0,0,0,0,0,0,0,0,0,0,0,0,0,0,0,0,0,0,0,0,0,0,0,0,0,0,0,0,0,N52,0)';
      PINUSE='POWER';
      NO_LOAD_CHECK='Both';
      NO_IO_CHECK='Both';
      NO_ASSERT_CHECK='TRUE';
      NO_DIR_CHECK='TRUE';
      ALLOW_CONNECT='TRUE';
    'VSS1692':
      PIN_NUMBER='(0,0,0,0,0,0,0,0,0,0,0,0,0,0,0,0,0,0,0,0,0,0,0,0,0,0,0,0,0,0,0,0,0,0,0,0,0,0,0,0,N45,0)';
      PINUSE='POWER';
      NO_LOAD_CHECK='Both';
      NO_IO_CHECK='Both';
      NO_ASSERT_CHECK='TRUE';
      NO_DIR_CHECK='TRUE';
      ALLOW_CONNECT='TRUE';
    'VSS1691':
      PIN_NUMBER='(0,0,0,0,0,0,0,0,0,0,0,0,0,0,0,0,0,0,0,0,0,0,0,0,0,0,0,0,0,0,0,0,0,0,0,0,0,0,0,0,N33,0)';
      PINUSE='POWER';
      NO_LOAD_CHECK='Both';
      NO_IO_CHECK='Both';
      NO_ASSERT_CHECK='TRUE';
      NO_DIR_CHECK='TRUE';
      ALLOW_CONNECT='TRUE';
    'VSS1689':
      PIN_NUMBER='(0,0,0,0,0,0,0,0,0,0,0,0,0,0,0,0,0,0,0,0,0,0,0,0,0,0,0,0,0,0,0,0,0,0,0,0,0,0,0,0,N27,0)';
      PINUSE='POWER';
      NO_LOAD_CHECK='Both';
      NO_IO_CHECK='Both';
      NO_ASSERT_CHECK='TRUE';
      NO_DIR_CHECK='TRUE';
      ALLOW_CONNECT='TRUE';
    'VSS1688':
      PIN_NUMBER='(0,0,0,0,0,0,0,0,0,0,0,0,0,0,0,0,0,0,0,0,0,0,0,0,0,0,0,0,0,0,0,0,0,0,0,0,0,0,0,0,N15,0)';
      PINUSE='POWER';
      NO_LOAD_CHECK='Both';
      NO_IO_CHECK='Both';
      NO_ASSERT_CHECK='TRUE';
      NO_DIR_CHECK='TRUE';
      ALLOW_CONNECT='TRUE';
    'VSS1687':
      PIN_NUMBER='(0,0,0,0,0,0,0,0,0,0,0,0,0,0,0,0,0,0,0,0,0,0,0,0,0,0,0,0,0,0,0,0,0,0,0,0,0,0,0,0,M83,0)';
      PINUSE='POWER';
      NO_LOAD_CHECK='Both';
      NO_IO_CHECK='Both';
      NO_ASSERT_CHECK='TRUE';
      NO_DIR_CHECK='TRUE';
      ALLOW_CONNECT='TRUE';
    'VSS1686':
      PIN_NUMBER='(0,0,0,0,0,0,0,0,0,0,0,0,0,0,0,0,0,0,0,0,0,0,0,0,0,0,0,0,0,0,0,0,0,0,0,0,0,0,0,0,M81,0)';
      PINUSE='POWER';
      NO_LOAD_CHECK='Both';
      NO_IO_CHECK='Both';
      NO_ASSERT_CHECK='TRUE';
      NO_DIR_CHECK='TRUE';
      ALLOW_CONNECT='TRUE';
    'VSS1685':
      PIN_NUMBER='(0,0,0,0,0,0,0,0,0,0,0,0,0,0,0,0,0,0,0,0,0,0,0,0,0,0,0,0,0,0,0,0,0,0,0,0,0,0,0,0,L78,0)';
      PINUSE='POWER';
      NO_LOAD_CHECK='Both';
      NO_IO_CHECK='Both';
      NO_ASSERT_CHECK='TRUE';
      NO_DIR_CHECK='TRUE';
      ALLOW_CONNECT='TRUE';
    'VSS1684':
      PIN_NUMBER='(0,0,0,0,0,0,0,0,0,0,0,0,0,0,0,0,0,0,0,0,0,0,0,0,0,0,0,0,0,0,0,0,0,0,0,0,0,0,0,0,L76,0)';
      PINUSE='POWER';
      NO_LOAD_CHECK='Both';
      NO_IO_CHECK='Both';
      NO_ASSERT_CHECK='TRUE';
      NO_DIR_CHECK='TRUE';
      ALLOW_CONNECT='TRUE';
    'VSS1683':
      PIN_NUMBER='(0,0,0,0,0,0,0,0,0,0,0,0,0,0,0,0,0,0,0,0,0,0,0,0,0,0,0,0,0,0,0,0,0,0,0,0,0,0,0,0,L74,0)';
      PINUSE='POWER';
      NO_LOAD_CHECK='Both';
      NO_IO_CHECK='Both';
      NO_ASSERT_CHECK='TRUE';
      NO_DIR_CHECK='TRUE';
      ALLOW_CONNECT='TRUE';
    'VSS1682':
      PIN_NUMBER='(0,0,0,0,0,0,0,0,0,0,0,0,0,0,0,0,0,0,0,0,0,0,0,0,0,0,0,0,0,0,0,0,0,0,0,0,0,0,0,0,L72,0)';
      PINUSE='POWER';
      NO_LOAD_CHECK='Both';
      NO_IO_CHECK='Both';
      NO_ASSERT_CHECK='TRUE';
      NO_DIR_CHECK='TRUE';
      ALLOW_CONNECT='TRUE';
    'VSS1681':
      PIN_NUMBER='(0,0,0,0,0,0,0,0,0,0,0,0,0,0,0,0,0,0,0,0,0,0,0,0,0,0,0,0,0,0,0,0,0,0,0,0,0,0,0,0,L68,0)';
      PINUSE='POWER';
      NO_LOAD_CHECK='Both';
      NO_IO_CHECK='Both';
      NO_ASSERT_CHECK='TRUE';
      NO_DIR_CHECK='TRUE';
      ALLOW_CONNECT='TRUE';
    'VSS1680':
      PIN_NUMBER='(0,0,0,0,0,0,0,0,0,0,0,0,0,0,0,0,0,0,0,0,0,0,0,0,0,0,0,0,0,0,0,0,0,0,0,0,0,0,0,0,L66,0)';
      PINUSE='POWER';
      NO_LOAD_CHECK='Both';
      NO_IO_CHECK='Both';
      NO_ASSERT_CHECK='TRUE';
      NO_DIR_CHECK='TRUE';
      ALLOW_CONNECT='TRUE';
    'VSS1679':
      PIN_NUMBER='(0,0,0,0,0,0,0,0,0,0,0,0,0,0,0,0,0,0,0,0,0,0,0,0,0,0,0,0,0,0,0,0,0,0,0,0,0,0,0,0,L64,0)';
      PINUSE='POWER';
      NO_LOAD_CHECK='Both';
      NO_IO_CHECK='Both';
      NO_ASSERT_CHECK='TRUE';
      NO_DIR_CHECK='TRUE';
      ALLOW_CONNECT='TRUE';
    'VSS1678':
      PIN_NUMBER='(0,0,0,0,0,0,0,0,0,0,0,0,0,0,0,0,0,0,0,0,0,0,0,0,0,0,0,0,0,0,0,0,0,0,0,0,0,0,0,0,L62,0)';
      PINUSE='POWER';
      NO_LOAD_CHECK='Both';
      NO_IO_CHECK='Both';
      NO_ASSERT_CHECK='TRUE';
      NO_DIR_CHECK='TRUE';
      ALLOW_CONNECT='TRUE';
    'VSS1677':
      PIN_NUMBER='(0,0,0,0,0,0,0,0,0,0,0,0,0,0,0,0,0,0,0,0,0,0,0,0,0,0,0,0,0,0,0,0,0,0,0,0,0,0,0,0,L60,0)';
      PINUSE='POWER';
      NO_LOAD_CHECK='Both';
      NO_IO_CHECK='Both';
      NO_ASSERT_CHECK='TRUE';
      NO_DIR_CHECK='TRUE';
      ALLOW_CONNECT='TRUE';
    'VSS1676':
      PIN_NUMBER='(0,0,0,0,0,0,0,0,0,0,0,0,0,0,0,0,0,0,0,0,0,0,0,0,0,0,0,0,0,0,0,0,0,0,0,0,0,0,0,0,L56,0)';
      PINUSE='POWER';
      NO_LOAD_CHECK='Both';
      NO_IO_CHECK='Both';
      NO_ASSERT_CHECK='TRUE';
      NO_DIR_CHECK='TRUE';
      ALLOW_CONNECT='TRUE';
    'VSS1675':
      PIN_NUMBER='(0,0,0,0,0,0,0,0,0,0,0,0,0,0,0,0,0,0,0,0,0,0,0,0,0,0,0,0,0,0,0,0,0,0,0,0,0,0,0,0,N64,0)';
      PINUSE='POWER';
      NO_LOAD_CHECK='Both';
      NO_IO_CHECK='Both';
      NO_ASSERT_CHECK='TRUE';
      NO_DIR_CHECK='TRUE';
      ALLOW_CONNECT='TRUE';
    'VSS1674':
      PIN_NUMBER='(0,0,0,0,0,0,0,0,0,0,0,0,0,0,0,0,0,0,0,0,0,0,0,0,0,0,0,0,0,0,0,0,0,0,0,0,0,0,0,0,L54,0)';
      PINUSE='POWER';
      NO_LOAD_CHECK='Both';
      NO_IO_CHECK='Both';
      NO_ASSERT_CHECK='TRUE';
      NO_DIR_CHECK='TRUE';
      ALLOW_CONNECT='TRUE';
    'VSS1673':
      PIN_NUMBER='(0,0,0,0,0,0,0,0,0,0,0,0,0,0,0,0,0,0,0,0,0,0,0,0,0,0,0,0,0,0,0,0,0,0,0,0,0,0,0,0,L52,0)';
      PINUSE='POWER';
      NO_LOAD_CHECK='Both';
      NO_IO_CHECK='Both';
      NO_ASSERT_CHECK='TRUE';
      NO_DIR_CHECK='TRUE';
      ALLOW_CONNECT='TRUE';
    'VSS1672':
      PIN_NUMBER='(0,0,0,0,0,0,0,0,0,0,0,0,0,0,0,0,0,0,0,0,0,0,0,0,0,0,0,0,0,0,0,0,0,0,0,0,0,0,0,0,L50,0)';
      PINUSE='POWER';
      NO_LOAD_CHECK='Both';
      NO_IO_CHECK='Both';
      NO_ASSERT_CHECK='TRUE';
      NO_DIR_CHECK='TRUE';
      ALLOW_CONNECT='TRUE';
    'VSS1671':
      PIN_NUMBER='(0,0,0,0,0,0,0,0,0,0,0,0,0,0,0,0,0,0,0,0,0,0,0,0,0,0,0,0,0,0,0,0,0,0,0,0,0,0,0,0,L5,0)';
      PINUSE='POWER';
      NO_LOAD_CHECK='Both';
      NO_IO_CHECK='Both';
      NO_ASSERT_CHECK='TRUE';
      NO_DIR_CHECK='TRUE';
      ALLOW_CONNECT='TRUE';
    'VSS1670':
      PIN_NUMBER='(0,0,0,0,0,0,0,0,0,0,0,0,0,0,0,0,0,0,0,0,0,0,0,0,0,0,0,0,0,0,0,0,0,0,0,0,0,0,0,0,L48,0)';
      PINUSE='POWER';
      NO_LOAD_CHECK='Both';
      NO_IO_CHECK='Both';
      NO_ASSERT_CHECK='TRUE';
      NO_DIR_CHECK='TRUE';
      ALLOW_CONNECT='TRUE';
    'VSS1669':
      PIN_NUMBER='(0,0,0,0,0,0,0,0,0,0,0,0,0,0,0,0,0,0,0,0,0,0,0,0,0,0,0,0,0,0,0,0,0,0,0,0,0,0,0,0,N39,0)';
      PINUSE='POWER';
      NO_LOAD_CHECK='Both';
      NO_IO_CHECK='Both';
      NO_ASSERT_CHECK='TRUE';
      NO_DIR_CHECK='TRUE';
      ALLOW_CONNECT='TRUE';
    'VSS1668':
      PIN_NUMBER='(0,0,0,0,0,0,0,0,0,0,0,0,0,0,0,0,0,0,0,0,0,0,0,0,0,0,0,0,0,0,0,0,0,0,0,0,0,0,0,0,L45,0)';
      PINUSE='POWER';
      NO_LOAD_CHECK='Both';
      NO_IO_CHECK='Both';
      NO_ASSERT_CHECK='TRUE';
      NO_DIR_CHECK='TRUE';
      ALLOW_CONNECT='TRUE';
    'VSS1667':
      PIN_NUMBER='(0,0,0,0,0,0,0,0,0,0,0,0,0,0,0,0,0,0,0,0,0,0,0,0,0,0,0,0,0,0,0,0,0,0,0,0,0,0,0,0,L43,0)';
      PINUSE='POWER';
      NO_LOAD_CHECK='Both';
      NO_IO_CHECK='Both';
      NO_ASSERT_CHECK='TRUE';
      NO_DIR_CHECK='TRUE';
      ALLOW_CONNECT='TRUE';
    'VSS1666':
      PIN_NUMBER='(0,0,0,0,0,0,0,0,0,0,0,0,0,0,0,0,0,0,0,0,0,0,0,0,0,0,0,0,0,0,0,0,0,0,0,0,0,0,0,0,L41,0)';
      PINUSE='POWER';
      NO_LOAD_CHECK='Both';
      NO_IO_CHECK='Both';
      NO_ASSERT_CHECK='TRUE';
      NO_DIR_CHECK='TRUE';
      ALLOW_CONNECT='TRUE';
    'VSS1665':
      PIN_NUMBER='(0,0,0,0,0,0,0,0,0,0,0,0,0,0,0,0,0,0,0,0,0,0,0,0,0,0,0,0,0,0,0,0,0,0,0,0,0,0,0,0,L39,0)';
      PINUSE='POWER';
      NO_LOAD_CHECK='Both';
      NO_IO_CHECK='Both';
      NO_ASSERT_CHECK='TRUE';
      NO_DIR_CHECK='TRUE';
      ALLOW_CONNECT='TRUE';
    'VSS1664':
      PIN_NUMBER='(0,0,0,0,0,0,0,0,0,0,0,0,0,0,0,0,0,0,0,0,0,0,0,0,0,0,0,0,0,0,0,0,0,0,0,0,0,0,0,0,N21,0)';
      PINUSE='POWER';
      NO_LOAD_CHECK='Both';
      NO_IO_CHECK='Both';
      NO_ASSERT_CHECK='TRUE';
      NO_DIR_CHECK='TRUE';
      ALLOW_CONNECT='TRUE';
    'VSS1663':
      PIN_NUMBER='(0,0,0,0,0,0,0,0,0,0,0,0,0,0,0,0,0,0,0,0,0,0,0,0,0,0,0,0,0,0,0,0,0,0,0,0,0,0,0,0,L37,0)';
      PINUSE='POWER';
      NO_LOAD_CHECK='Both';
      NO_IO_CHECK='Both';
      NO_ASSERT_CHECK='TRUE';
      NO_DIR_CHECK='TRUE';
      ALLOW_CONNECT='TRUE';
    'VSS1662':
      PIN_NUMBER='(0,0,0,0,0,0,0,0,0,0,0,0,0,0,0,0,0,0,0,0,0,0,0,0,0,0,0,0,0,0,0,0,0,0,0,0,0,0,0,0,L35,0)';
      PINUSE='POWER';
      NO_LOAD_CHECK='Both';
      NO_IO_CHECK='Both';
      NO_ASSERT_CHECK='TRUE';
      NO_DIR_CHECK='TRUE';
      ALLOW_CONNECT='TRUE';
    'VSS1661':
      PIN_NUMBER='(0,0,0,0,0,0,0,0,0,0,0,0,0,0,0,0,0,0,0,0,0,0,0,0,0,0,0,0,0,0,0,0,0,0,0,0,0,0,0,0,L33,0)';
      PINUSE='POWER';
      NO_LOAD_CHECK='Both';
      NO_IO_CHECK='Both';
      NO_ASSERT_CHECK='TRUE';
      NO_DIR_CHECK='TRUE';
      ALLOW_CONNECT='TRUE';
    'VSS1660':
      PIN_NUMBER='(0,0,0,0,0,0,0,0,0,0,0,0,0,0,0,0,0,0,0,0,0,0,0,0,0,0,0,0,0,0,0,0,0,0,0,0,0,0,0,0,L31,0)';
      PINUSE='POWER';
      NO_LOAD_CHECK='Both';
      NO_IO_CHECK='Both';
      NO_ASSERT_CHECK='TRUE';
      NO_DIR_CHECK='TRUE';
      ALLOW_CONNECT='TRUE';
    'VSS1659':
      PIN_NUMBER='(0,0,0,0,0,0,0,0,0,0,0,0,0,0,0,0,0,0,0,0,0,0,0,0,0,0,0,0,0,0,0,0,0,0,0,0,0,0,0,0,L29,0)';
      PINUSE='POWER';
      NO_LOAD_CHECK='Both';
      NO_IO_CHECK='Both';
      NO_ASSERT_CHECK='TRUE';
      NO_DIR_CHECK='TRUE';
      ALLOW_CONNECT='TRUE';
    'VSS1658':
      PIN_NUMBER='(0,0,0,0,0,0,0,0,0,0,0,0,0,0,0,0,0,0,0,0,0,0,0,0,0,0,0,0,0,0,0,0,0,0,0,0,0,0,0,0,L27,0)';
      PINUSE='POWER';
      NO_LOAD_CHECK='Both';
      NO_IO_CHECK='Both';
      NO_ASSERT_CHECK='TRUE';
      NO_DIR_CHECK='TRUE';
      ALLOW_CONNECT='TRUE';
    'VSS1657':
      PIN_NUMBER='(0,0,0,0,0,0,0,0,0,0,0,0,0,0,0,0,0,0,0,0,0,0,0,0,0,0,0,0,0,0,0,0,0,0,0,0,0,0,0,0,M8,0)';
      PINUSE='POWER';
      NO_LOAD_CHECK='Both';
      NO_IO_CHECK='Both';
      NO_ASSERT_CHECK='TRUE';
      NO_DIR_CHECK='TRUE';
      ALLOW_CONNECT='TRUE';
    'VSS1656':
      PIN_NUMBER='(0,0,0,0,0,0,0,0,0,0,0,0,0,0,0,0,0,0,0,0,0,0,0,0,0,0,0,0,0,0,0,0,0,0,0,0,0,0,0,0,L25,0)';
      PINUSE='POWER';
      NO_LOAD_CHECK='Both';
      NO_IO_CHECK='Both';
      NO_ASSERT_CHECK='TRUE';
      NO_DIR_CHECK='TRUE';
      ALLOW_CONNECT='TRUE';
    'VSS1655':
      PIN_NUMBER='(0,0,0,0,0,0,0,0,0,0,0,0,0,0,0,0,0,0,0,0,0,0,0,0,0,0,0,0,0,0,0,0,0,0,0,0,0,0,0,0,L23,0)';
      PINUSE='POWER';
      NO_LOAD_CHECK='Both';
      NO_IO_CHECK='Both';
      NO_ASSERT_CHECK='TRUE';
      NO_DIR_CHECK='TRUE';
      ALLOW_CONNECT='TRUE';
    'VSS1654':
      PIN_NUMBER='(0,0,0,0,0,0,0,0,0,0,0,0,0,0,0,0,0,0,0,0,0,0,0,0,0,0,0,0,0,0,0,0,0,0,0,0,0,0,0,0,M49,0)';
      PINUSE='POWER';
      NO_LOAD_CHECK='Both';
      NO_IO_CHECK='Both';
      NO_ASSERT_CHECK='TRUE';
      NO_DIR_CHECK='TRUE';
      ALLOW_CONNECT='TRUE';
    'VSS1653':
      PIN_NUMBER='(0,0,0,0,0,0,0,0,0,0,0,0,0,0,0,0,0,0,0,0,0,0,0,0,0,0,0,0,0,0,0,0,0,0,0,0,0,0,0,0,M42,0)';
      PINUSE='POWER';
      NO_LOAD_CHECK='Both';
      NO_IO_CHECK='Both';
      NO_ASSERT_CHECK='TRUE';
      NO_DIR_CHECK='TRUE';
      ALLOW_CONNECT='TRUE';
    'VSS1652':
      PIN_NUMBER='(0,0,0,0,0,0,0,0,0,0,0,0,0,0,0,0,0,0,0,0,0,0,0,0,0,0,0,0,0,0,0,0,0,0,0,0,0,0,0,0,M4,0)';
      PINUSE='POWER';
      NO_LOAD_CHECK='Both';
      NO_IO_CHECK='Both';
      NO_ASSERT_CHECK='TRUE';
      NO_DIR_CHECK='TRUE';
      ALLOW_CONNECT='TRUE';
    'VSS1651':
      PIN_NUMBER='(0,0,0,0,0,0,0,0,0,0,0,0,0,0,0,0,0,0,0,0,0,0,0,0,0,0,0,0,0,0,0,0,0,0,0,0,0,0,0,0,L21,0)';
      PINUSE='POWER';
      NO_LOAD_CHECK='Both';
      NO_IO_CHECK='Both';
      NO_ASSERT_CHECK='TRUE';
      NO_DIR_CHECK='TRUE';
      ALLOW_CONNECT='TRUE';
    'VSS1650':
      PIN_NUMBER='(0,0,0,0,0,0,0,0,0,0,0,0,0,0,0,0,0,0,0,0,0,0,0,0,0,0,0,0,0,0,0,0,0,0,0,0,0,0,0,0,L17,0)';
      PINUSE='POWER';
      NO_LOAD_CHECK='Both';
      NO_IO_CHECK='Both';
      NO_ASSERT_CHECK='TRUE';
      NO_DIR_CHECK='TRUE';
      ALLOW_CONNECT='TRUE';
    'VSS1649':
      PIN_NUMBER='(0,0,0,0,0,0,0,0,0,0,0,0,0,0,0,0,0,0,0,0,0,0,0,0,0,0,0,0,0,0,0,0,0,0,0,0,0,0,0,0,M12,0)';
      PINUSE='POWER';
      NO_LOAD_CHECK='Both';
      NO_IO_CHECK='Both';
      NO_ASSERT_CHECK='TRUE';
      NO_DIR_CHECK='TRUE';
      ALLOW_CONNECT='TRUE';
    'VSS1648':
      PIN_NUMBER='(0,0,0,0,0,0,0,0,0,0,0,0,0,0,0,0,0,0,0,0,0,0,0,0,0,0,0,0,0,0,0,0,0,0,0,0,0,0,0,0,L90,0)';
      PINUSE='POWER';
      NO_LOAD_CHECK='Both';
      NO_IO_CHECK='Both';
      NO_ASSERT_CHECK='TRUE';
      NO_DIR_CHECK='TRUE';
      ALLOW_CONNECT='TRUE';
    'VSS1647':
      PIN_NUMBER='(0,0,0,0,0,0,0,0,0,0,0,0,0,0,0,0,0,0,0,0,0,0,0,0,0,0,0,0,0,0,0,0,0,0,0,0,0,0,0,0,L9,0)';
      PINUSE='POWER';
      NO_LOAD_CHECK='Both';
      NO_IO_CHECK='Both';
      NO_ASSERT_CHECK='TRUE';
      NO_DIR_CHECK='TRUE';
      ALLOW_CONNECT='TRUE';
    'VSS1646':
      PIN_NUMBER='(0,0,0,0,0,0,0,0,0,0,0,0,0,0,0,0,0,0,0,0,0,0,0,0,0,0,0,0,0,0,0,0,0,0,0,0,0,0,0,0,L88,0)';
      PINUSE='POWER';
      NO_LOAD_CHECK='Both';
      NO_IO_CHECK='Both';
      NO_ASSERT_CHECK='TRUE';
      NO_DIR_CHECK='TRUE';
      ALLOW_CONNECT='TRUE';
    'VSS1645':
      PIN_NUMBER='(0,0,0,0,0,0,0,0,0,0,0,0,0,0,0,0,0,0,0,0,0,0,0,0,0,0,0,0,0,0,0,0,0,0,0,0,0,0,0,0,L15,0)';
      PINUSE='POWER';
      NO_LOAD_CHECK='Both';
      NO_IO_CHECK='Both';
      NO_ASSERT_CHECK='TRUE';
      NO_DIR_CHECK='TRUE';
      ALLOW_CONNECT='TRUE';
    'VSS1644':
      PIN_NUMBER='(0,0,0,0,0,0,0,0,0,0,0,0,0,0,0,0,0,0,0,0,0,0,0,0,0,0,0,0,0,0,0,0,0,0,0,0,0,0,0,0,L13,0)';
      PINUSE='POWER';
      NO_LOAD_CHECK='Both';
      NO_IO_CHECK='Both';
      NO_ASSERT_CHECK='TRUE';
      NO_DIR_CHECK='TRUE';
      ALLOW_CONNECT='TRUE';
    'VSS1643':
      PIN_NUMBER='(0,0,0,0,0,0,0,0,0,0,0,0,0,0,0,0,0,0,0,0,0,0,0,0,0,0,0,0,0,0,0,0,0,0,0,0,0,0,0,0,K85,0)';
      PINUSE='POWER';
      NO_LOAD_CHECK='Both';
      NO_IO_CHECK='Both';
      NO_ASSERT_CHECK='TRUE';
      NO_DIR_CHECK='TRUE';
      ALLOW_CONNECT='TRUE';
    'VSS1642':
      PIN_NUMBER='(0,0,0,0,0,0,0,0,0,0,0,0,0,0,0,0,0,0,0,0,0,0,0,0,0,0,0,0,0,0,0,0,0,0,0,0,0,0,0,0,K83,0)';
      PINUSE='POWER';
      NO_LOAD_CHECK='Both';
      NO_IO_CHECK='Both';
      NO_ASSERT_CHECK='TRUE';
      NO_DIR_CHECK='TRUE';
      ALLOW_CONNECT='TRUE';
    'VSS1641':
      PIN_NUMBER='(0,0,0,0,0,0,0,0,0,0,0,0,0,0,0,0,0,0,0,0,0,0,0,0,0,0,0,0,0,0,0,0,0,0,0,0,0,0,0,0,K8,0)';
      PINUSE='POWER';
      NO_LOAD_CHECK='Both';
      NO_IO_CHECK='Both';
      NO_ASSERT_CHECK='TRUE';
      NO_DIR_CHECK='TRUE';
      ALLOW_CONNECT='TRUE';
    'VSS1640':
      PIN_NUMBER='(0,0,0,0,0,0,0,0,0,0,0,0,0,0,0,0,0,0,0,0,0,0,0,0,0,0,0,0,0,0,0,0,0,0,0,0,0,0,0,0,L70,0)';
      PINUSE='POWER';
      NO_LOAD_CHECK='Both';
      NO_IO_CHECK='Both';
      NO_ASSERT_CHECK='TRUE';
      NO_DIR_CHECK='TRUE';
      ALLOW_CONNECT='TRUE';
    'VSS1639':
      PIN_NUMBER='(0,0,0,0,0,0,0,0,0,0,0,0,0,0,0,0,0,0,0,0,0,0,0,0,0,0,0,0,0,0,0,0,0,0,0,0,0,0,0,0,K77,0)';
      PINUSE='POWER';
      NO_LOAD_CHECK='Both';
      NO_IO_CHECK='Both';
      NO_ASSERT_CHECK='TRUE';
      NO_DIR_CHECK='TRUE';
      ALLOW_CONNECT='TRUE';
    'VSS1638':
      PIN_NUMBER='(0,0,0,0,0,0,0,0,0,0,0,0,0,0,0,0,0,0,0,0,0,0,0,0,0,0,0,0,0,0,0,0,0,0,0,0,0,0,0,0,J86,0)';
      PINUSE='POWER';
      NO_LOAD_CHECK='Both';
      NO_IO_CHECK='Both';
      NO_ASSERT_CHECK='TRUE';
      NO_DIR_CHECK='TRUE';
      ALLOW_CONNECT='TRUE';
    'VSS1637':
      PIN_NUMBER='(0,0,0,0,0,0,0,0,0,0,0,0,0,0,0,0,0,0,0,0,0,0,0,0,0,0,0,0,0,0,0,0,0,0,0,0,0,0,0,0,J84,0)';
      PINUSE='POWER';
      NO_LOAD_CHECK='Both';
      NO_IO_CHECK='Both';
      NO_ASSERT_CHECK='TRUE';
      NO_DIR_CHECK='TRUE';
      ALLOW_CONNECT='TRUE';
    'VSS1636':
      PIN_NUMBER='(0,0,0,0,0,0,0,0,0,0,0,0,0,0,0,0,0,0,0,0,0,0,0,0,0,0,0,0,0,0,0,0,0,0,0,0,0,0,0,0,J78,0)';
      PINUSE='POWER';
      NO_LOAD_CHECK='Both';
      NO_IO_CHECK='Both';
      NO_ASSERT_CHECK='TRUE';
      NO_DIR_CHECK='TRUE';
      ALLOW_CONNECT='TRUE';
    'VSS1635':
      PIN_NUMBER='(0,0,0,0,0,0,0,0,0,0,0,0,0,0,0,0,0,0,0,0,0,0,0,0,0,0,0,0,0,0,0,0,0,0,0,0,0,0,0,0,J76,0)';
      PINUSE='POWER';
      NO_LOAD_CHECK='Both';
      NO_IO_CHECK='Both';
      NO_ASSERT_CHECK='TRUE';
      NO_DIR_CHECK='TRUE';
      ALLOW_CONNECT='TRUE';
    'VSS1634':
      PIN_NUMBER='(0,0,0,0,0,0,0,0,0,0,0,0,0,0,0,0,0,0,0,0,0,0,0,0,0,0,0,0,0,0,0,0,0,0,0,0,0,0,0,0,L58,0)';
      PINUSE='POWER';
      NO_LOAD_CHECK='Both';
      NO_IO_CHECK='Both';
      NO_ASSERT_CHECK='TRUE';
      NO_DIR_CHECK='TRUE';
      ALLOW_CONNECT='TRUE';
    'VSS1633':
      PIN_NUMBER='(0,0,0,0,0,0,0,0,0,0,0,0,0,0,0,0,0,0,0,0,0,0,0,0,0,0,0,0,0,0,0,0,0,0,0,0,0,0,0,0,J58,0)';
      PINUSE='POWER';
      NO_LOAD_CHECK='Both';
      NO_IO_CHECK='Both';
      NO_ASSERT_CHECK='TRUE';
      NO_DIR_CHECK='TRUE';
      ALLOW_CONNECT='TRUE';
    'VSS1632':
      PIN_NUMBER='(0,0,0,0,0,0,0,0,0,0,0,0,0,0,0,0,0,0,0,0,0,0,0,0,0,0,0,0,0,0,0,0,0,0,0,0,0,0,0,0,J52,0)';
      PINUSE='POWER';
      NO_LOAD_CHECK='Both';
      NO_IO_CHECK='Both';
      NO_ASSERT_CHECK='TRUE';
      NO_DIR_CHECK='TRUE';
      ALLOW_CONNECT='TRUE';
    'VSS1631':
      PIN_NUMBER='(0,0,0,0,0,0,0,0,0,0,0,0,0,0,0,0,0,0,0,0,0,0,0,0,0,0,0,0,0,0,0,0,0,0,0,0,0,0,0,0,J45,0)';
      PINUSE='POWER';
      NO_LOAD_CHECK='Both';
      NO_IO_CHECK='Both';
      NO_ASSERT_CHECK='TRUE';
      NO_DIR_CHECK='TRUE';
      ALLOW_CONNECT='TRUE';
    'VSS1630':
      PIN_NUMBER='(0,0,0,0,0,0,0,0,0,0,0,0,0,0,0,0,0,0,0,0,0,0,0,0,0,0,0,0,0,0,0,0,0,0,0,0,0,0,0,0,J33,0)';
      PINUSE='POWER';
      NO_LOAD_CHECK='Both';
      NO_IO_CHECK='Both';
      NO_ASSERT_CHECK='TRUE';
      NO_DIR_CHECK='TRUE';
      ALLOW_CONNECT='TRUE';
    'VSS1629':
      PIN_NUMBER='(0,0,0,0,0,0,0,0,0,0,0,0,0,0,0,0,0,0,0,0,0,0,0,0,0,0,0,0,0,0,0,0,0,0,0,0,0,0,0,0,J27,0)';
      PINUSE='POWER';
      NO_LOAD_CHECK='Both';
      NO_IO_CHECK='Both';
      NO_ASSERT_CHECK='TRUE';
      NO_DIR_CHECK='TRUE';
      ALLOW_CONNECT='TRUE';
    'VSS1628':
      PIN_NUMBER='(0,0,0,0,0,0,0,0,0,0,0,0,0,0,0,0,0,0,0,0,0,0,0,0,0,0,0,0,0,0,0,0,0,0,0,0,0,0,0,0,J15,0)';
      PINUSE='POWER';
      NO_LOAD_CHECK='Both';
      NO_IO_CHECK='Both';
      NO_ASSERT_CHECK='TRUE';
      NO_DIR_CHECK='TRUE';
      ALLOW_CONNECT='TRUE';
    'VSS1627':
      PIN_NUMBER='(0,0,0,0,0,0,0,0,0,0,0,0,0,0,0,0,0,0,0,0,0,0,0,0,0,0,0,0,0,0,0,0,0,0,0,0,0,0,0,0,H81,0)';
      PINUSE='POWER';
      NO_LOAD_CHECK='Both';
      NO_IO_CHECK='Both';
      NO_ASSERT_CHECK='TRUE';
      NO_DIR_CHECK='TRUE';
      ALLOW_CONNECT='TRUE';
    'VSS1626':
      PIN_NUMBER='(0,0,0,0,0,0,0,0,0,0,0,0,0,0,0,0,0,0,0,0,0,0,0,0,0,0,0,0,0,0,0,0,0,0,0,0,0,0,0,0,H8,0)';
      PINUSE='POWER';
      NO_LOAD_CHECK='Both';
      NO_IO_CHECK='Both';
      NO_ASSERT_CHECK='TRUE';
      NO_DIR_CHECK='TRUE';
      ALLOW_CONNECT='TRUE';
    'VSS1625':
      PIN_NUMBER='(0,0,0,0,0,0,0,0,0,0,0,0,0,0,0,0,0,0,0,0,0,0,0,0,0,0,0,0,0,0,0,0,0,0,0,0,0,0,0,0,H79,0)';
      PINUSE='POWER';
      NO_LOAD_CHECK='Both';
      NO_IO_CHECK='Both';
      NO_ASSERT_CHECK='TRUE';
      NO_DIR_CHECK='TRUE';
      ALLOW_CONNECT='TRUE';
    'VSS1624':
      PIN_NUMBER='(0,0,0,0,0,0,0,0,0,0,0,0,0,0,0,0,0,0,0,0,0,0,0,0,0,0,0,0,0,0,0,0,0,0,0,0,0,0,0,0,H71,0)';
      PINUSE='POWER';
      NO_LOAD_CHECK='Both';
      NO_IO_CHECK='Both';
      NO_ASSERT_CHECK='TRUE';
      NO_DIR_CHECK='TRUE';
      ALLOW_CONNECT='TRUE';
    'VSS1623':
      PIN_NUMBER='(0,0,0,0,0,0,0,0,0,0,0,0,0,0,0,0,0,0,0,0,0,0,0,0,0,0,0,0,0,0,0,0,0,0,0,0,0,0,0,0,H69,0)';
      PINUSE='POWER';
      NO_LOAD_CHECK='Both';
      NO_IO_CHECK='Both';
      NO_ASSERT_CHECK='TRUE';
      NO_DIR_CHECK='TRUE';
      ALLOW_CONNECT='TRUE';
    'VSS1622':
      PIN_NUMBER='(0,0,0,0,0,0,0,0,0,0,0,0,0,0,0,0,0,0,0,0,0,0,0,0,0,0,0,0,0,0,0,0,0,0,0,0,0,0,0,0,H63,0)';
      PINUSE='POWER';
      NO_LOAD_CHECK='Both';
      NO_IO_CHECK='Both';
      NO_ASSERT_CHECK='TRUE';
      NO_DIR_CHECK='TRUE';
      ALLOW_CONNECT='TRUE';
    'VSS1621':
      PIN_NUMBER='(0,0,0,0,0,0,0,0,0,0,0,0,0,0,0,0,0,0,0,0,0,0,0,0,0,0,0,0,0,0,0,0,0,0,0,0,0,0,0,0,H6,0)';
      PINUSE='POWER';
      NO_LOAD_CHECK='Both';
      NO_IO_CHECK='Both';
      NO_ASSERT_CHECK='TRUE';
      NO_DIR_CHECK='TRUE';
      ALLOW_CONNECT='TRUE';
    'VSS1620':
      PIN_NUMBER='(0,0,0,0,0,0,0,0,0,0,0,0,0,0,0,0,0,0,0,0,0,0,0,0,0,0,0,0,0,0,0,0,0,0,0,0,0,0,0,0,H59,0)';
      PINUSE='POWER';
      NO_LOAD_CHECK='Both';
      NO_IO_CHECK='Both';
      NO_ASSERT_CHECK='TRUE';
      NO_DIR_CHECK='TRUE';
      ALLOW_CONNECT='TRUE';
    'VSS1619':
      PIN_NUMBER='(0,0,0,0,0,0,0,0,0,0,0,0,0,0,0,0,0,0,0,0,0,0,0,0,0,0,0,0,0,0,0,0,0,0,0,0,0,0,0,0,H53,0)';
      PINUSE='POWER';
      NO_LOAD_CHECK='Both';
      NO_IO_CHECK='Both';
      NO_ASSERT_CHECK='TRUE';
      NO_DIR_CHECK='TRUE';
      ALLOW_CONNECT='TRUE';
    'VSS1618':
      PIN_NUMBER='(0,0,0,0,0,0,0,0,0,0,0,0,0,0,0,0,0,0,0,0,0,0,0,0,0,0,0,0,0,0,0,0,0,0,0,0,0,0,0,0,H47,0)';
      PINUSE='POWER';
      NO_LOAD_CHECK='Both';
      NO_IO_CHECK='Both';
      NO_ASSERT_CHECK='TRUE';
      NO_DIR_CHECK='TRUE';
      ALLOW_CONNECT='TRUE';
    'VSS1617':
      PIN_NUMBER='(0,0,0,0,0,0,0,0,0,0,0,0,0,0,0,0,0,0,0,0,0,0,0,0,0,0,0,0,0,0,0,0,0,0,0,0,0,0,0,0,H44,0)';
      PINUSE='POWER';
      NO_LOAD_CHECK='Both';
      NO_IO_CHECK='Both';
      NO_ASSERT_CHECK='TRUE';
      NO_DIR_CHECK='TRUE';
      ALLOW_CONNECT='TRUE';
    'VSS1616':
      PIN_NUMBER='(0,0,0,0,0,0,0,0,0,0,0,0,0,0,0,0,0,0,0,0,0,0,0,0,0,0,0,0,0,0,0,0,0,0,0,0,0,0,0,0,H40,0)';
      PINUSE='POWER';
      NO_LOAD_CHECK='Both';
      NO_IO_CHECK='Both';
      NO_ASSERT_CHECK='TRUE';
      NO_DIR_CHECK='TRUE';
      ALLOW_CONNECT='TRUE';
    'VSS1615':
      PIN_NUMBER='(0,0,0,0,0,0,0,0,0,0,0,0,0,0,0,0,0,0,0,0,0,0,0,0,0,0,0,0,0,0,0,0,0,0,0,0,0,0,0,0,H4,0)';
      PINUSE='POWER';
      NO_LOAD_CHECK='Both';
      NO_IO_CHECK='Both';
      NO_ASSERT_CHECK='TRUE';
      NO_DIR_CHECK='TRUE';
      ALLOW_CONNECT='TRUE';
    'VSS1614':
      PIN_NUMBER='(0,0,0,0,0,0,0,0,0,0,0,0,0,0,0,0,0,0,0,0,0,0,0,0,0,0,0,0,0,0,0,0,0,0,0,0,0,0,0,0,L19,0)';
      PINUSE='POWER';
      NO_LOAD_CHECK='Both';
      NO_IO_CHECK='Both';
      NO_ASSERT_CHECK='TRUE';
      NO_DIR_CHECK='TRUE';
      ALLOW_CONNECT='TRUE';
    'VSS1613':
      PIN_NUMBER='(0,0,0,0,0,0,0,0,0,0,0,0,0,0,0,0,0,0,0,0,0,0,0,0,0,0,0,0,0,0,0,0,0,0,0,0,0,0,0,0,H38,0)';
      PINUSE='POWER';
      NO_LOAD_CHECK='Both';
      NO_IO_CHECK='Both';
      NO_ASSERT_CHECK='TRUE';
      NO_DIR_CHECK='TRUE';
      ALLOW_CONNECT='TRUE';
    'VSS1612':
      PIN_NUMBER='(0,0,0,0,0,0,0,0,0,0,0,0,0,0,0,0,0,0,0,0,0,0,0,0,0,0,0,0,0,0,0,0,0,0,0,0,0,0,0,0,H34,0)';
      PINUSE='POWER';
      NO_LOAD_CHECK='Both';
      NO_IO_CHECK='Both';
      NO_ASSERT_CHECK='TRUE';
      NO_DIR_CHECK='TRUE';
      ALLOW_CONNECT='TRUE';
    'VSS1611':
      PIN_NUMBER='(0,0,0,0,0,0,0,0,0,0,0,0,0,0,0,0,0,0,0,0,0,0,0,0,0,0,0,0,0,0,0,0,0,0,0,0,0,0,0,0,H32,0)';
      PINUSE='POWER';
      NO_LOAD_CHECK='Both';
      NO_IO_CHECK='Both';
      NO_ASSERT_CHECK='TRUE';
      NO_DIR_CHECK='TRUE';
      ALLOW_CONNECT='TRUE';
    'VSS1610':
      PIN_NUMBER='(0,0,0,0,0,0,0,0,0,0,0,0,0,0,0,0,0,0,0,0,0,0,0,0,0,0,0,0,0,0,0,0,0,0,0,0,0,0,0,0,H28,0)';
      PINUSE='POWER';
      NO_LOAD_CHECK='Both';
      NO_IO_CHECK='Both';
      NO_ASSERT_CHECK='TRUE';
      NO_DIR_CHECK='TRUE';
      ALLOW_CONNECT='TRUE';
    'VSS1609':
      PIN_NUMBER='(0,0,0,0,0,0,0,0,0,0,0,0,0,0,0,0,0,0,0,0,0,0,0,0,0,0,0,0,0,0,0,0,0,0,0,0,0,0,0,0,H26,0)';
      PINUSE='POWER';
      NO_LOAD_CHECK='Both';
      NO_IO_CHECK='Both';
      NO_ASSERT_CHECK='TRUE';
      NO_DIR_CHECK='TRUE';
      ALLOW_CONNECT='TRUE';
    'VSS1608':
      PIN_NUMBER='(0,0,0,0,0,0,0,0,0,0,0,0,0,0,0,0,0,0,0,0,0,0,0,0,0,0,0,0,0,0,0,0,0,0,0,0,0,0,0,0,H22,0)';
      PINUSE='POWER';
      NO_LOAD_CHECK='Both';
      NO_IO_CHECK='Both';
      NO_ASSERT_CHECK='TRUE';
      NO_DIR_CHECK='TRUE';
      ALLOW_CONNECT='TRUE';
    'VSS1607':
      PIN_NUMBER='(0,0,0,0,0,0,0,0,0,0,0,0,0,0,0,0,0,0,0,0,0,0,0,0,0,0,0,0,0,0,0,0,0,0,0,0,0,0,0,0,H20,0)';
      PINUSE='POWER';
      NO_LOAD_CHECK='Both';
      NO_IO_CHECK='Both';
      NO_ASSERT_CHECK='TRUE';
      NO_DIR_CHECK='TRUE';
      ALLOW_CONNECT='TRUE';
    'VSS1606':
      PIN_NUMBER='(0,0,0,0,0,0,0,0,0,0,0,0,0,0,0,0,0,0,0,0,0,0,0,0,0,0,0,0,0,0,0,0,0,0,0,0,0,0,0,0,H16,0)';
      PINUSE='POWER';
      NO_LOAD_CHECK='Both';
      NO_IO_CHECK='Both';
      NO_ASSERT_CHECK='TRUE';
      NO_DIR_CHECK='TRUE';
      ALLOW_CONNECT='TRUE';
    'VSS1605':
      PIN_NUMBER='(0,0,0,0,0,0,0,0,0,0,0,0,0,0,0,0,0,0,0,0,0,0,0,0,0,0,0,0,0,0,0,0,0,0,0,0,0,0,0,0,H10,0)';
      PINUSE='POWER';
      NO_LOAD_CHECK='Both';
      NO_IO_CHECK='Both';
      NO_ASSERT_CHECK='TRUE';
      NO_DIR_CHECK='TRUE';
      ALLOW_CONNECT='TRUE';
    'VSS1604':
      PIN_NUMBER='(0,0,0,0,0,0,0,0,0,0,0,0,0,0,0,0,0,0,0,0,0,0,0,0,0,0,0,0,0,0,0,0,0,0,0,0,0,0,0,0,G90,0)';
      PINUSE='POWER';
      NO_LOAD_CHECK='Both';
      NO_IO_CHECK='Both';
      NO_ASSERT_CHECK='TRUE';
      NO_DIR_CHECK='TRUE';
      ALLOW_CONNECT='TRUE';
    'VSS1603':
      PIN_NUMBER='(0,0,0,0,0,0,0,0,0,0,0,0,0,0,0,0,0,0,0,0,0,0,0,0,0,0,0,0,0,0,0,0,0,0,0,0,0,0,0,0,K49,0)';
      PINUSE='POWER';
      NO_LOAD_CHECK='Both';
      NO_IO_CHECK='Both';
      NO_ASSERT_CHECK='TRUE';
      NO_DIR_CHECK='TRUE';
      ALLOW_CONNECT='TRUE';
    'VSS1602':
      PIN_NUMBER='(0,0,0,0,0,0,0,0,0,0,0,0,0,0,0,0,0,0,0,0,0,0,0,0,0,0,0,0,0,0,0,0,0,0,0,0,0,0,0,0,K42,0)';
      PINUSE='POWER';
      NO_LOAD_CHECK='Both';
      NO_IO_CHECK='Both';
      NO_ASSERT_CHECK='TRUE';
      NO_DIR_CHECK='TRUE';
      ALLOW_CONNECT='TRUE';
    'VSS1601':
      PIN_NUMBER='(0,0,0,0,0,0,0,0,0,0,0,0,0,0,0,0,0,0,0,0,0,0,0,0,0,0,0,0,0,0,0,0,0,0,0,0,0,0,0,0,G88,0)';
      PINUSE='POWER';
      NO_LOAD_CHECK='Both';
      NO_IO_CHECK='Both';
      NO_ASSERT_CHECK='TRUE';
      NO_DIR_CHECK='TRUE';
      ALLOW_CONNECT='TRUE';
    'VSS1600':
      PIN_NUMBER='(0,0,0,0,0,0,0,0,0,0,0,0,0,0,0,0,0,0,0,0,0,0,0,0,0,0,0,0,0,0,0,0,0,0,0,0,0,0,0,0,G84,0)';
      PINUSE='POWER';
      NO_LOAD_CHECK='Both';
      NO_IO_CHECK='Both';
      NO_ASSERT_CHECK='TRUE';
      NO_DIR_CHECK='TRUE';
      ALLOW_CONNECT='TRUE';
    'VSS1599':
      PIN_NUMBER='(0,0,0,0,0,0,0,0,0,0,0,0,0,0,0,0,0,0,0,0,0,0,0,0,0,0,0,0,0,0,0,0,0,0,0,0,0,0,0,0,K2,0)';
      PINUSE='POWER';
      NO_LOAD_CHECK='Both';
      NO_IO_CHECK='Both';
      NO_ASSERT_CHECK='TRUE';
      NO_DIR_CHECK='TRUE';
      ALLOW_CONNECT='TRUE';
    'VSS1598':
      PIN_NUMBER='(0,0,0,0,0,0,0,0,0,0,0,0,0,0,0,0,0,0,0,0,0,0,0,0,0,0,0,0,0,0,0,0,0,0,0,0,0,0,0,0,K14,0)';
      PINUSE='POWER';
      NO_LOAD_CHECK='Both';
      NO_IO_CHECK='Both';
      NO_ASSERT_CHECK='TRUE';
      NO_DIR_CHECK='TRUE';
      ALLOW_CONNECT='TRUE';
    'VSS1597':
      PIN_NUMBER='(0,0,0,0,0,0,0,0,0,0,0,0,0,0,0,0,0,0,0,0,0,0,0,0,0,0,0,0,0,0,0,0,0,0,0,0,0,0,0,0,K12,0)';
      PINUSE='POWER';
      NO_LOAD_CHECK='Both';
      NO_IO_CHECK='Both';
      NO_ASSERT_CHECK='TRUE';
      NO_DIR_CHECK='TRUE';
      ALLOW_CONNECT='TRUE';
    'VSS1596':
      PIN_NUMBER='(0,0,0,0,0,0,0,0,0,0,0,0,0,0,0,0,0,0,0,0,0,0,0,0,0,0,0,0,0,0,0,0,0,0,0,0,0,0,0,0,J9,0)';
      PINUSE='POWER';
      NO_LOAD_CHECK='Both';
      NO_IO_CHECK='Both';
      NO_ASSERT_CHECK='TRUE';
      NO_DIR_CHECK='TRUE';
      ALLOW_CONNECT='TRUE';
    'VSS1595':
      PIN_NUMBER='(0,0,0,0,0,0,0,0,0,0,0,0,0,0,0,0,0,0,0,0,0,0,0,0,0,0,0,0,0,0,0,0,0,0,0,0,0,0,0,0,J88,0)';
      PINUSE='POWER';
      NO_LOAD_CHECK='Both';
      NO_IO_CHECK='Both';
      NO_ASSERT_CHECK='TRUE';
      NO_DIR_CHECK='TRUE';
      ALLOW_CONNECT='TRUE';
    'VSS1594':
      PIN_NUMBER='(0,0,0,0,0,0,0,0,0,0,0,0,0,0,0,0,0,0,0,0,0,0,0,0,0,0,0,0,0,0,0,0,0,0,0,0,0,0,0,0,G72,0)';
      PINUSE='POWER';
      NO_LOAD_CHECK='Both';
      NO_IO_CHECK='Both';
      NO_ASSERT_CHECK='TRUE';
      NO_DIR_CHECK='TRUE';
      ALLOW_CONNECT='TRUE';
    'VSS1593':
      PIN_NUMBER='(0,0,0,0,0,0,0,0,0,0,0,0,0,0,0,0,0,0,0,0,0,0,0,0,0,0,0,0,0,0,0,0,0,0,0,0,0,0,0,0,G62,0)';
      PINUSE='POWER';
      NO_LOAD_CHECK='Both';
      NO_IO_CHECK='Both';
      NO_ASSERT_CHECK='TRUE';
      NO_DIR_CHECK='TRUE';
      ALLOW_CONNECT='TRUE';
    'VSS1592':
      PIN_NUMBER='(0,0,0,0,0,0,0,0,0,0,0,0,0,0,0,0,0,0,0,0,0,0,0,0,0,0,0,0,0,0,0,0,0,0,0,0,0,0,0,0,G56,0)';
      PINUSE='POWER';
      NO_LOAD_CHECK='Both';
      NO_IO_CHECK='Both';
      NO_ASSERT_CHECK='TRUE';
      NO_DIR_CHECK='TRUE';
      ALLOW_CONNECT='TRUE';
    'VSS1591':
      PIN_NUMBER='(0,0,0,0,0,0,0,0,0,0,0,0,0,0,0,0,0,0,0,0,0,0,0,0,0,0,0,0,0,0,0,0,0,0,0,0,0,0,0,0,G54,0)';
      PINUSE='POWER';
      NO_LOAD_CHECK='Both';
      NO_IO_CHECK='Both';
      NO_ASSERT_CHECK='TRUE';
      NO_DIR_CHECK='TRUE';
      ALLOW_CONNECT='TRUE';
    'VSS1590':
      PIN_NUMBER='(0,0,0,0,0,0,0,0,0,0,0,0,0,0,0,0,0,0,0,0,0,0,0,0,0,0,0,0,0,0,0,0,0,0,0,0,0,0,0,0,G50,0)';
      PINUSE='POWER';
      NO_LOAD_CHECK='Both';
      NO_IO_CHECK='Both';
      NO_ASSERT_CHECK='TRUE';
      NO_DIR_CHECK='TRUE';
      ALLOW_CONNECT='TRUE';
    'VSS1589':
      PIN_NUMBER='(0,0,0,0,0,0,0,0,0,0,0,0,0,0,0,0,0,0,0,0,0,0,0,0,0,0,0,0,0,0,0,0,0,0,0,0,0,0,0,0,J70,0)';
      PINUSE='POWER';
      NO_LOAD_CHECK='Both';
      NO_IO_CHECK='Both';
      NO_ASSERT_CHECK='TRUE';
      NO_DIR_CHECK='TRUE';
      ALLOW_CONNECT='TRUE';
    'VSS1588':
      PIN_NUMBER='(0,0,0,0,0,0,0,0,0,0,0,0,0,0,0,0,0,0,0,0,0,0,0,0,0,0,0,0,0,0,0,0,0,0,0,0,0,0,0,0,G43,0)';
      PINUSE='POWER';
      NO_LOAD_CHECK='Both';
      NO_IO_CHECK='Both';
      NO_ASSERT_CHECK='TRUE';
      NO_DIR_CHECK='TRUE';
      ALLOW_CONNECT='TRUE';
    'VSS1587':
      PIN_NUMBER='(0,0,0,0,0,0,0,0,0,0,0,0,0,0,0,0,0,0,0,0,0,0,0,0,0,0,0,0,0,0,0,0,0,0,0,0,0,0,0,0,J64,0)';
      PINUSE='POWER';
      NO_LOAD_CHECK='Both';
      NO_IO_CHECK='Both';
      NO_ASSERT_CHECK='TRUE';
      NO_DIR_CHECK='TRUE';
      ALLOW_CONNECT='TRUE';
    'VSS1586':
      PIN_NUMBER='(0,0,0,0,0,0,0,0,0,0,0,0,0,0,0,0,0,0,0,0,0,0,0,0,0,0,0,0,0,0,0,0,0,0,0,0,0,0,0,0,G41,0)';
      PINUSE='POWER';
      NO_LOAD_CHECK='Both';
      NO_IO_CHECK='Both';
      NO_ASSERT_CHECK='TRUE';
      NO_DIR_CHECK='TRUE';
      ALLOW_CONNECT='TRUE';
    'VSS1585':
      PIN_NUMBER='(0,0,0,0,0,0,0,0,0,0,0,0,0,0,0,0,0,0,0,0,0,0,0,0,0,0,0,0,0,0,0,0,0,0,0,0,0,0,0,0,G37,0)';
      PINUSE='POWER';
      NO_LOAD_CHECK='Both';
      NO_IO_CHECK='Both';
      NO_ASSERT_CHECK='TRUE';
      NO_DIR_CHECK='TRUE';
      ALLOW_CONNECT='TRUE';
    'VSS1584':
      PIN_NUMBER='(0,0,0,0,0,0,0,0,0,0,0,0,0,0,0,0,0,0,0,0,0,0,0,0,0,0,0,0,0,0,0,0,0,0,0,0,0,0,0,0,G31,0)';
      PINUSE='POWER';
      NO_LOAD_CHECK='Both';
      NO_IO_CHECK='Both';
      NO_ASSERT_CHECK='TRUE';
      NO_DIR_CHECK='TRUE';
      ALLOW_CONNECT='TRUE';
    'VSS1583':
      PIN_NUMBER='(0,0,0,0,0,0,0,0,0,0,0,0,0,0,0,0,0,0,0,0,0,0,0,0,0,0,0,0,0,0,0,0,0,0,0,0,0,0,0,0,G29,0)';
      PINUSE='POWER';
      NO_LOAD_CHECK='Both';
      NO_IO_CHECK='Both';
      NO_ASSERT_CHECK='TRUE';
      NO_DIR_CHECK='TRUE';
      ALLOW_CONNECT='TRUE';
    'VSS1582':
      PIN_NUMBER='(0,0,0,0,0,0,0,0,0,0,0,0,0,0,0,0,0,0,0,0,0,0,0,0,0,0,0,0,0,0,0,0,0,0,0,0,0,0,0,0,J5,0)';
      PINUSE='POWER';
      NO_LOAD_CHECK='Both';
      NO_IO_CHECK='Both';
      NO_ASSERT_CHECK='TRUE';
      NO_DIR_CHECK='TRUE';
      ALLOW_CONNECT='TRUE';
    'VSS1581':
      PIN_NUMBER='(0,0,0,0,0,0,0,0,0,0,0,0,0,0,0,0,0,0,0,0,0,0,0,0,0,0,0,0,0,0,0,0,0,0,0,0,0,0,0,0,G23,0)';
      PINUSE='POWER';
      NO_LOAD_CHECK='Both';
      NO_IO_CHECK='Both';
      NO_ASSERT_CHECK='TRUE';
      NO_DIR_CHECK='TRUE';
      ALLOW_CONNECT='TRUE';
    'VSS1580':
      PIN_NUMBER='(0,0,0,0,0,0,0,0,0,0,0,0,0,0,0,0,0,0,0,0,0,0,0,0,0,0,0,0,0,0,0,0,0,0,0,0,0,0,0,0,J39,0)';
      PINUSE='POWER';
      NO_LOAD_CHECK='Both';
      NO_IO_CHECK='Both';
      NO_ASSERT_CHECK='TRUE';
      NO_DIR_CHECK='TRUE';
      ALLOW_CONNECT='TRUE';
    'VSS1579':
      PIN_NUMBER='(0,0,0,0,0,0,0,0,0,0,0,0,0,0,0,0,0,0,0,0,0,0,0,0,0,0,0,0,0,0,0,0,0,0,0,0,0,0,0,0,G19,0)';
      PINUSE='POWER';
      NO_LOAD_CHECK='Both';
      NO_IO_CHECK='Both';
      NO_ASSERT_CHECK='TRUE';
      NO_DIR_CHECK='TRUE';
      ALLOW_CONNECT='TRUE';
    'VSS1578':
      PIN_NUMBER='(0,0,0,0,0,0,0,0,0,0,0,0,0,0,0,0,0,0,0,0,0,0,0,0,0,0,0,0,0,0,0,0,0,0,0,0,0,0,0,0,G13,0)';
      PINUSE='POWER';
      NO_LOAD_CHECK='Both';
      NO_IO_CHECK='Both';
      NO_ASSERT_CHECK='TRUE';
      NO_DIR_CHECK='TRUE';
      ALLOW_CONNECT='TRUE';
    'VSS1577':
      PIN_NUMBER='(0,0,0,0,0,0,0,0,0,0,0,0,0,0,0,0,0,0,0,0,0,0,0,0,0,0,0,0,0,0,0,0,0,0,0,0,0,0,0,0,F89,0)';
      PINUSE='POWER';
      NO_LOAD_CHECK='Both';
      NO_IO_CHECK='Both';
      NO_ASSERT_CHECK='TRUE';
      NO_DIR_CHECK='TRUE';
      ALLOW_CONNECT='TRUE';
    'VSS1576':
      PIN_NUMBER='(0,0,0,0,0,0,0,0,0,0,0,0,0,0,0,0,0,0,0,0,0,0,0,0,0,0,0,0,0,0,0,0,0,0,0,0,0,0,0,0,F83,0)';
      PINUSE='POWER';
      NO_LOAD_CHECK='Both';
      NO_IO_CHECK='Both';
      NO_ASSERT_CHECK='TRUE';
      NO_DIR_CHECK='TRUE';
      ALLOW_CONNECT='TRUE';
    'VSS1575':
      PIN_NUMBER='(0,0,0,0,0,0,0,0,0,0,0,0,0,0,0,0,0,0,0,0,0,0,0,0,0,0,0,0,0,0,0,0,0,0,0,0,0,0,0,0,J21,0)';
      PINUSE='POWER';
      NO_LOAD_CHECK='Both';
      NO_IO_CHECK='Both';
      NO_ASSERT_CHECK='TRUE';
      NO_DIR_CHECK='TRUE';
      ALLOW_CONNECT='TRUE';
    'VSS1574':
      PIN_NUMBER='(0,0,0,0,0,0,0,0,0,0,0,0,0,0,0,0,0,0,0,0,0,0,0,0,0,0,0,0,0,0,0,0,0,0,0,0,0,0,0,0,F49,0)';
      PINUSE='POWER';
      NO_LOAD_CHECK='Both';
      NO_IO_CHECK='Both';
      NO_ASSERT_CHECK='TRUE';
      NO_DIR_CHECK='TRUE';
      ALLOW_CONNECT='TRUE';
    'VSS1573':
      PIN_NUMBER='(0,0,0,0,0,0,0,0,0,0,0,0,0,0,0,0,0,0,0,0,0,0,0,0,0,0,0,0,0,0,0,0,0,0,0,0,0,0,0,0,F4,0)';
      PINUSE='POWER';
      NO_LOAD_CHECK='Both';
      NO_IO_CHECK='Both';
      NO_ASSERT_CHECK='TRUE';
      NO_DIR_CHECK='TRUE';
      ALLOW_CONNECT='TRUE';
    'VSS1572':
      PIN_NUMBER='(0,0,0,0,0,0,0,0,0,0,0,0,0,0,0,0,0,0,0,0,0,0,0,0,0,0,0,0,0,0,0,0,0,0,0,0,0,0,0,0,F36,0)';
      PINUSE='POWER';
      NO_LOAD_CHECK='Both';
      NO_IO_CHECK='Both';
      NO_ASSERT_CHECK='TRUE';
      NO_DIR_CHECK='TRUE';
      ALLOW_CONNECT='TRUE';
    'VSS1571':
      PIN_NUMBER='(0,0,0,0,0,0,0,0,0,0,0,0,0,0,0,0,0,0,0,0,0,0,0,0,0,0,0,0,0,0,0,0,0,0,0,0,0,0,0,0,F30,0)';
      PINUSE='POWER';
      NO_LOAD_CHECK='Both';
      NO_IO_CHECK='Both';
      NO_ASSERT_CHECK='TRUE';
      NO_DIR_CHECK='TRUE';
      ALLOW_CONNECT='TRUE';
    'VSS1570':
      PIN_NUMBER='(0,0,0,0,0,0,0,0,0,0,0,0,0,0,0,0,0,0,0,0,0,0,0,0,0,0,0,0,0,0,0,0,0,0,0,0,0,0,0,0,F24,0)';
      PINUSE='POWER';
      NO_LOAD_CHECK='Both';
      NO_IO_CHECK='Both';
      NO_ASSERT_CHECK='TRUE';
      NO_DIR_CHECK='TRUE';
      ALLOW_CONNECT='TRUE';
    'VSS1567':
      PIN_NUMBER='(0,0,0,0,0,0,0,0,0,0,0,0,0,0,0,0,0,0,0,0,0,0,0,0,0,0,0,0,0,0,0,0,0,0,0,0,0,0,0,0,H75,0)';
      PINUSE='POWER';
      NO_LOAD_CHECK='Both';
      NO_IO_CHECK='Both';
      NO_ASSERT_CHECK='TRUE';
      NO_DIR_CHECK='TRUE';
      ALLOW_CONNECT='TRUE';
    'VSS1564':
      PIN_NUMBER='(0,0,0,0,0,0,0,0,0,0,0,0,0,0,0,0,0,0,0,0,0,0,0,0,0,0,0,0,0,0,0,0,0,0,0,0,0,0,0,0,H65,0)';
      PINUSE='POWER';
      NO_LOAD_CHECK='Both';
      NO_IO_CHECK='Both';
      NO_ASSERT_CHECK='TRUE';
      NO_DIR_CHECK='TRUE';
      ALLOW_CONNECT='TRUE';
    'VSS1560':
      PIN_NUMBER='(0,0,0,0,0,0,0,0,0,0,0,0,0,0,0,0,0,0,0,0,0,0,0,0,0,0,0,0,0,0,0,0,0,0,0,0,0,0,0,0,H57,0)';
      PINUSE='POWER';
      NO_LOAD_CHECK='Both';
      NO_IO_CHECK='Both';
      NO_ASSERT_CHECK='TRUE';
      NO_DIR_CHECK='TRUE';
      ALLOW_CONNECT='TRUE';
    'VSS1558':
      PIN_NUMBER='(0,0,0,0,0,0,0,0,0,0,0,0,0,0,0,0,0,0,0,0,0,0,0,0,0,0,0,0,0,0,0,0,0,0,0,0,0,0,0,0,H51,0)';
      PINUSE='POWER';
      NO_LOAD_CHECK='Both';
      NO_IO_CHECK='Both';
      NO_ASSERT_CHECK='TRUE';
      NO_DIR_CHECK='TRUE';
      ALLOW_CONNECT='TRUE';
    'VSS1546':
      PIN_NUMBER='(0,0,0,0,0,0,0,0,0,0,0,0,0,0,0,0,0,0,0,0,0,0,0,0,0,0,0,0,0,0,0,0,0,0,0,0,0,0,0,0,H2,0)';
      PINUSE='POWER';
      NO_LOAD_CHECK='Both';
      NO_IO_CHECK='Both';
      NO_ASSERT_CHECK='TRUE';
      NO_DIR_CHECK='TRUE';
      ALLOW_CONNECT='TRUE';
    'VSS1544':
      PIN_NUMBER='(0,0,0,0,0,0,0,0,0,0,0,0,0,0,0,0,0,0,0,0,0,0,0,0,0,0,0,0,0,0,0,0,0,0,0,0,0,0,0,0,H14,0)';
      PINUSE='POWER';
      NO_LOAD_CHECK='Both';
      NO_IO_CHECK='Both';
      NO_ASSERT_CHECK='TRUE';
      NO_DIR_CHECK='TRUE';
      ALLOW_CONNECT='TRUE';
    'VSS1538':
      PIN_NUMBER='(0,0,0,0,0,0,0,0,0,0,0,0,0,0,0,0,0,0,0,0,0,0,0,0,0,0,0,0,0,0,0,0,0,0,0,0,0,0,0,0,G74,0)';
      PINUSE='POWER';
      NO_LOAD_CHECK='Both';
      NO_IO_CHECK='Both';
      NO_ASSERT_CHECK='TRUE';
      NO_DIR_CHECK='TRUE';
      ALLOW_CONNECT='TRUE';
    'VSS1536':
      PIN_NUMBER='(0,0,0,0,0,0,0,0,0,0,0,0,0,0,0,0,0,0,0,0,0,0,0,0,0,0,0,0,0,0,0,0,0,0,0,0,0,0,0,0,G7,0)';
      PINUSE='POWER';
      NO_LOAD_CHECK='Both';
      NO_IO_CHECK='Both';
      NO_ASSERT_CHECK='TRUE';
      NO_DIR_CHECK='TRUE';
      ALLOW_CONNECT='TRUE';
    'VSS1535':
      PIN_NUMBER='(0,0,0,0,0,0,0,0,0,0,0,0,0,0,0,0,0,0,0,0,0,0,0,0,0,0,0,0,0,0,0,0,0,0,0,0,0,0,0,0,G68,0)';
      PINUSE='POWER';
      NO_LOAD_CHECK='Both';
      NO_IO_CHECK='Both';
      NO_ASSERT_CHECK='TRUE';
      NO_DIR_CHECK='TRUE';
      ALLOW_CONNECT='TRUE';
    'VSS1534':
      PIN_NUMBER='(0,0,0,0,0,0,0,0,0,0,0,0,0,0,0,0,0,0,0,0,0,0,0,0,0,0,0,0,0,0,0,0,0,0,0,0,0,0,0,0,G66,0)';
      PINUSE='POWER';
      NO_LOAD_CHECK='Both';
      NO_IO_CHECK='Both';
      NO_ASSERT_CHECK='TRUE';
      NO_DIR_CHECK='TRUE';
      ALLOW_CONNECT='TRUE';
    'VSS1532':
      PIN_NUMBER='(0,0,0,0,0,0,0,0,0,0,0,0,0,0,0,0,0,0,0,0,0,0,0,0,0,0,0,0,0,0,0,0,0,0,0,0,0,0,0,0,G60,0)';
      PINUSE='POWER';
      NO_LOAD_CHECK='Both';
      NO_IO_CHECK='Both';
      NO_ASSERT_CHECK='TRUE';
      NO_DIR_CHECK='TRUE';
      ALLOW_CONNECT='TRUE';
    'VSS1527':
      PIN_NUMBER='(0,0,0,0,0,0,0,0,0,0,0,0,0,0,0,0,0,0,0,0,0,0,0,0,0,0,0,0,0,0,0,0,0,0,0,0,0,0,0,0,G48,0)';
      PINUSE='POWER';
      NO_LOAD_CHECK='Both';
      NO_IO_CHECK='Both';
      NO_ASSERT_CHECK='TRUE';
      NO_DIR_CHECK='TRUE';
      ALLOW_CONNECT='TRUE';
    'VSS1523':
      PIN_NUMBER='(0,0,0,0,0,0,0,0,0,0,0,0,0,0,0,0,0,0,0,0,0,0,0,0,0,0,0,0,0,0,0,0,0,0,0,0,0,0,0,0,G35,0)';
      PINUSE='POWER';
      NO_LOAD_CHECK='Both';
      NO_IO_CHECK='Both';
      NO_ASSERT_CHECK='TRUE';
      NO_DIR_CHECK='TRUE';
      ALLOW_CONNECT='TRUE';
    'VSS1521':
      PIN_NUMBER='(0,0,0,0,0,0,0,0,0,0,0,0,0,0,0,0,0,0,0,0,0,0,0,0,0,0,0,0,0,0,0,0,0,0,0,0,0,0,0,0,G3,0)';
      PINUSE='POWER';
      NO_LOAD_CHECK='Both';
      NO_IO_CHECK='Both';
      NO_ASSERT_CHECK='TRUE';
      NO_DIR_CHECK='TRUE';
      ALLOW_CONNECT='TRUE';
    'VSS1519':
      PIN_NUMBER='(0,0,0,0,0,0,0,0,0,0,0,0,0,0,0,0,0,0,0,0,0,0,0,0,0,0,0,0,0,0,0,0,0,0,0,0,0,0,0,0,G25,0)';
      PINUSE='POWER';
      NO_LOAD_CHECK='Both';
      NO_IO_CHECK='Both';
      NO_ASSERT_CHECK='TRUE';
      NO_DIR_CHECK='TRUE';
      ALLOW_CONNECT='TRUE';
    'VSS1516':
      PIN_NUMBER='(0,0,0,0,0,0,0,0,0,0,0,0,0,0,0,0,0,0,0,0,0,0,0,0,0,0,0,0,0,0,0,0,0,0,0,0,0,0,0,0,G17,0)';
      PINUSE='POWER';
      NO_LOAD_CHECK='Both';
      NO_IO_CHECK='Both';
      NO_ASSERT_CHECK='TRUE';
      NO_DIR_CHECK='TRUE';
      ALLOW_CONNECT='TRUE';
    'VSS1514':
      PIN_NUMBER='(0,0,0,0,0,0,0,0,0,0,0,0,0,0,0,0,0,0,0,0,0,0,0,0,0,0,0,0,0,0,0,0,0,0,0,0,0,0,0,0,G11,0)';
      PINUSE='POWER';
      NO_LOAD_CHECK='Both';
      NO_IO_CHECK='Both';
      NO_ASSERT_CHECK='TRUE';
      NO_DIR_CHECK='TRUE';
      ALLOW_CONNECT='TRUE';
    'VSS1511':
      PIN_NUMBER='(0,0,0,0,0,0,0,0,0,0,0,0,0,0,0,0,0,0,0,0,0,0,0,0,0,0,0,0,0,0,0,0,0,0,0,0,0,0,0,0,F79,0)';
      PINUSE='POWER';
      NO_LOAD_CHECK='Both';
      NO_IO_CHECK='Both';
      NO_ASSERT_CHECK='TRUE';
      NO_DIR_CHECK='TRUE';
      ALLOW_CONNECT='TRUE';
    'VSS1510':
      PIN_NUMBER='(0,0,0,0,0,0,0,0,0,0,0,0,0,0,0,0,0,0,0,0,0,0,0,0,0,0,0,0,0,0,0,0,0,0,0,0,0,0,0,0,F73,0)';
      PINUSE='POWER';
      NO_LOAD_CHECK='Both';
      NO_IO_CHECK='Both';
      NO_ASSERT_CHECK='TRUE';
      NO_DIR_CHECK='TRUE';
      ALLOW_CONNECT='TRUE';
    'VSS1509':
      PIN_NUMBER='(0,0,0,0,0,0,0,0,0,0,0,0,0,0,0,0,0,0,0,0,0,0,0,0,0,0,0,0,0,0,0,0,0,0,0,0,0,0,0,0,F67,0)';
      PINUSE='POWER';
      NO_LOAD_CHECK='Both';
      NO_IO_CHECK='Both';
      NO_ASSERT_CHECK='TRUE';
      NO_DIR_CHECK='TRUE';
      ALLOW_CONNECT='TRUE';
    'VSS1508':
      PIN_NUMBER='(0,0,0,0,0,0,0,0,0,0,0,0,0,0,0,0,0,0,0,0,0,0,0,0,0,0,0,0,0,0,0,0,0,0,0,0,0,0,0,0,F61,0)';
      PINUSE='POWER';
      NO_LOAD_CHECK='Both';
      NO_IO_CHECK='Both';
      NO_ASSERT_CHECK='TRUE';
      NO_DIR_CHECK='TRUE';
      ALLOW_CONNECT='TRUE';
    'VSS1507':
      PIN_NUMBER='(0,0,0,0,0,0,0,0,0,0,0,0,0,0,0,0,0,0,0,0,0,0,0,0,0,0,0,0,0,0,0,0,0,0,0,0,0,0,0,0,F6,0)';
      PINUSE='POWER';
      NO_LOAD_CHECK='Both';
      NO_IO_CHECK='Both';
      NO_ASSERT_CHECK='TRUE';
      NO_DIR_CHECK='TRUE';
      ALLOW_CONNECT='TRUE';
    'VSS1504':
      PIN_NUMBER='(0,0,0,0,0,0,0,0,0,0,0,0,0,0,0,0,0,0,0,0,0,0,0,0,0,0,0,0,0,0,0,0,0,0,0,0,0,0,0,0,F55,0)';
      PINUSE='POWER';
      NO_LOAD_CHECK='Both';
      NO_IO_CHECK='Both';
      NO_ASSERT_CHECK='TRUE';
      NO_DIR_CHECK='TRUE';
      ALLOW_CONNECT='TRUE';
    'VSS1502':
      PIN_NUMBER='(0,0,0,0,0,0,0,0,0,0,0,0,0,0,0,0,0,0,0,0,0,0,0,0,0,0,0,0,0,0,0,0,0,0,0,0,0,0,0,0,F42,0)';
      PINUSE='POWER';
      NO_LOAD_CHECK='Both';
      NO_IO_CHECK='Both';
      NO_ASSERT_CHECK='TRUE';
      NO_DIR_CHECK='TRUE';
      ALLOW_CONNECT='TRUE';
    'VSS1495':
      PIN_NUMBER='(0,0,0,0,0,0,0,0,0,0,0,0,0,0,0,0,0,0,0,0,0,0,0,0,0,0,0,0,0,0,0,0,0,0,0,0,0,0,0,0,F18,0)';
      PINUSE='POWER';
      NO_LOAD_CHECK='Both';
      NO_IO_CHECK='Both';
      NO_ASSERT_CHECK='TRUE';
      NO_DIR_CHECK='TRUE';
      ALLOW_CONNECT='TRUE';
    'VSS1494':
      PIN_NUMBER='(0,0,0,0,0,0,0,0,0,0,0,0,0,0,0,0,0,0,0,0,0,0,0,0,0,0,0,0,0,0,0,0,0,0,0,0,0,0,0,0,F12,0)';
      PINUSE='POWER';
      NO_LOAD_CHECK='Both';
      NO_IO_CHECK='Both';
      NO_ASSERT_CHECK='TRUE';
      NO_DIR_CHECK='TRUE';
      ALLOW_CONNECT='TRUE';
    'VSS1273':
      PIN_NUMBER='(0,0,0,0,0,0,0,0,0,0,0,0,0,0,0,0,0,0,0,0,0,0,0,0,0,0,0,0,0,0,0,0,0,0,0,0,0,0,0,0,E86,0)';
      PINUSE='POWER';
      NO_LOAD_CHECK='Both';
      NO_IO_CHECK='Both';
      NO_ASSERT_CHECK='TRUE';
      NO_DIR_CHECK='TRUE';
      ALLOW_CONNECT='TRUE';
    'VSS1272':
      PIN_NUMBER='(0,0,0,0,0,0,0,0,0,0,0,0,0,0,0,0,0,0,0,0,0,0,0,0,0,0,0,0,0,0,0,0,0,0,0,0,0,0,0,0,E76,0)';
      PINUSE='POWER';
      NO_LOAD_CHECK='Both';
      NO_IO_CHECK='Both';
      NO_ASSERT_CHECK='TRUE';
      NO_DIR_CHECK='TRUE';
      ALLOW_CONNECT='TRUE';
    'VSS1131':
      PIN_NUMBER='(0,0,0,0,0,0,0,0,0,0,0,0,0,0,0,0,0,0,0,0,0,0,0,0,0,0,0,0,0,0,0,0,0,0,0,0,0,0,0,0,E78,0)';
      PINUSE='POWER';
      NO_LOAD_CHECK='Both';
      NO_IO_CHECK='Both';
      NO_ASSERT_CHECK='TRUE';
      NO_DIR_CHECK='TRUE';
      ALLOW_CONNECT='TRUE';
    'VSS1129':
      PIN_NUMBER='(0,0,0,0,0,0,0,0,0,0,0,0,0,0,0,0,0,0,0,0,0,0,0,0,0,0,0,0,0,0,0,0,0,0,0,0,0,0,0,0,E74,0)';
      PINUSE='POWER';
      NO_LOAD_CHECK='Both';
      NO_IO_CHECK='Both';
      NO_ASSERT_CHECK='TRUE';
      NO_DIR_CHECK='TRUE';
      ALLOW_CONNECT='TRUE';
    'VSS1126':
      PIN_NUMBER='(0,0,0,0,0,0,0,0,0,0,0,0,0,0,0,0,0,0,0,0,0,0,0,0,0,0,0,0,0,0,0,0,0,0,0,0,0,0,0,0,E52,0)';
      PINUSE='POWER';
      NO_LOAD_CHECK='Both';
      NO_IO_CHECK='Both';
      NO_ASSERT_CHECK='TRUE';
      NO_DIR_CHECK='TRUE';
      ALLOW_CONNECT='TRUE';
    'VSS1271':
      PIN_NUMBER='(0,0,0,0,0,0,0,0,0,0,0,0,0,0,0,0,0,0,0,0,0,0,0,0,0,0,0,0,0,0,0,0,0,0,0,0,0,0,0,0,0,E39)';
      PINUSE='POWER';
      NO_LOAD_CHECK='Both';
      NO_IO_CHECK='Both';
      NO_ASSERT_CHECK='TRUE';
      NO_DIR_CHECK='TRUE';
      ALLOW_CONNECT='TRUE';
    'VSS1125':
      PIN_NUMBER='(0,0,0,0,0,0,0,0,0,0,0,0,0,0,0,0,0,0,0,0,0,0,0,0,0,0,0,0,0,0,0,0,0,0,0,0,0,0,0,0,0,E5)';
      PINUSE='POWER';
      NO_LOAD_CHECK='Both';
      NO_IO_CHECK='Both';
      NO_ASSERT_CHECK='TRUE';
      NO_DIR_CHECK='TRUE';
      ALLOW_CONNECT='TRUE';
    'VSS907':
      PIN_NUMBER='(0,0,0,0,0,0,0,0,0,0,0,0,0,0,0,0,0,0,0,0,0,0,0,0,0,0,0,0,0,0,0,0,0,0,0,0,0,0,0,0,0,D83)';
      PINUSE='POWER';
      NO_LOAD_CHECK='Both';
      NO_IO_CHECK='Both';
      NO_ASSERT_CHECK='TRUE';
      NO_DIR_CHECK='TRUE';
      ALLOW_CONNECT='TRUE';
    'VSS906':
      PIN_NUMBER='(0,0,0,0,0,0,0,0,0,0,0,0,0,0,0,0,0,0,0,0,0,0,0,0,0,0,0,0,0,0,0,0,0,0,0,0,0,0,0,0,0,D81)';
      PINUSE='POWER';
      NO_LOAD_CHECK='Both';
      NO_IO_CHECK='Both';
      NO_ASSERT_CHECK='TRUE';
      NO_DIR_CHECK='TRUE';
      ALLOW_CONNECT='TRUE';
    'VSS902':
      PIN_NUMBER='(0,0,0,0,0,0,0,0,0,0,0,0,0,0,0,0,0,0,0,0,0,0,0,0,0,0,0,0,0,0,0,0,0,0,0,0,0,0,0,0,0,D71)';
      PINUSE='POWER';
      NO_LOAD_CHECK='Both';
      NO_IO_CHECK='Both';
      NO_ASSERT_CHECK='TRUE';
      NO_DIR_CHECK='TRUE';
      ALLOW_CONNECT='TRUE';
    'VSS901':
      PIN_NUMBER='(0,0,0,0,0,0,0,0,0,0,0,0,0,0,0,0,0,0,0,0,0,0,0,0,0,0,0,0,0,0,0,0,0,0,0,0,0,0,0,0,0,D69)';
      PINUSE='POWER';
      NO_LOAD_CHECK='Both';
      NO_IO_CHECK='Both';
      NO_ASSERT_CHECK='TRUE';
      NO_DIR_CHECK='TRUE';
      ALLOW_CONNECT='TRUE';
    'VSS900':
      PIN_NUMBER='(0,0,0,0,0,0,0,0,0,0,0,0,0,0,0,0,0,0,0,0,0,0,0,0,0,0,0,0,0,0,0,0,0,0,0,0,0,0,0,0,0,D61)';
      PINUSE='POWER';
      NO_LOAD_CHECK='Both';
      NO_IO_CHECK='Both';
      NO_ASSERT_CHECK='TRUE';
      NO_DIR_CHECK='TRUE';
      ALLOW_CONNECT='TRUE';
    'VSS899':
      PIN_NUMBER='(0,0,0,0,0,0,0,0,0,0,0,0,0,0,0,0,0,0,0,0,0,0,0,0,0,0,0,0,0,0,0,0,0,0,0,0,0,0,0,0,0,D6)';
      PINUSE='POWER';
      NO_LOAD_CHECK='Both';
      NO_IO_CHECK='Both';
      NO_ASSERT_CHECK='TRUE';
      NO_DIR_CHECK='TRUE';
      ALLOW_CONNECT='TRUE';
    'VSS898':
      PIN_NUMBER='(0,0,0,0,0,0,0,0,0,0,0,0,0,0,0,0,0,0,0,0,0,0,0,0,0,0,0,0,0,0,0,0,0,0,0,0,0,0,0,0,0,D59)';
      PINUSE='POWER';
      NO_LOAD_CHECK='Both';
      NO_IO_CHECK='Both';
      NO_ASSERT_CHECK='TRUE';
      NO_DIR_CHECK='TRUE';
      ALLOW_CONNECT='TRUE';
    'VSS897':
      PIN_NUMBER='(0,0,0,0,0,0,0,0,0,0,0,0,0,0,0,0,0,0,0,0,0,0,0,0,0,0,0,0,0,0,0,0,0,0,0,0,0,0,0,0,0,D57)';
      PINUSE='POWER';
      NO_LOAD_CHECK='Both';
      NO_IO_CHECK='Both';
      NO_ASSERT_CHECK='TRUE';
      NO_DIR_CHECK='TRUE';
      ALLOW_CONNECT='TRUE';
    'VSS896':
      PIN_NUMBER='(0,0,0,0,0,0,0,0,0,0,0,0,0,0,0,0,0,0,0,0,0,0,0,0,0,0,0,0,0,0,0,0,0,0,0,0,0,0,0,0,0,D55)';
      PINUSE='POWER';
      NO_LOAD_CHECK='Both';
      NO_IO_CHECK='Both';
      NO_ASSERT_CHECK='TRUE';
      NO_DIR_CHECK='TRUE';
      ALLOW_CONNECT='TRUE';
    'VSS895':
      PIN_NUMBER='(0,0,0,0,0,0,0,0,0,0,0,0,0,0,0,0,0,0,0,0,0,0,0,0,0,0,0,0,0,0,0,0,0,0,0,0,0,0,0,0,0,D53)';
      PINUSE='POWER';
      NO_LOAD_CHECK='Both';
      NO_IO_CHECK='Both';
      NO_ASSERT_CHECK='TRUE';
      NO_DIR_CHECK='TRUE';
      ALLOW_CONNECT='TRUE';
    'VSS892':
      PIN_NUMBER='(0,0,0,0,0,0,0,0,0,0,0,0,0,0,0,0,0,0,0,0,0,0,0,0,0,0,0,0,0,0,0,0,0,0,0,0,0,0,0,0,0,D51)';
      PINUSE='POWER';
      NO_LOAD_CHECK='Both';
      NO_IO_CHECK='Both';
      NO_ASSERT_CHECK='TRUE';
      NO_DIR_CHECK='TRUE';
      ALLOW_CONNECT='TRUE';
    'VSS891':
      PIN_NUMBER='(0,0,0,0,0,0,0,0,0,0,0,0,0,0,0,0,0,0,0,0,0,0,0,0,0,0,0,0,0,0,0,0,0,0,0,0,0,0,0,0,0,D49)';
      PINUSE='POWER';
      NO_LOAD_CHECK='Both';
      NO_IO_CHECK='Both';
      NO_ASSERT_CHECK='TRUE';
      NO_DIR_CHECK='TRUE';
      ALLOW_CONNECT='TRUE';
    'VSS889':
      PIN_NUMBER='(0,0,0,0,0,0,0,0,0,0,0,0,0,0,0,0,0,0,0,0,0,0,0,0,0,0,0,0,0,0,0,0,0,0,0,0,0,0,0,0,0,D47)';
      PINUSE='POWER';
      NO_LOAD_CHECK='Both';
      NO_IO_CHECK='Both';
      NO_ASSERT_CHECK='TRUE';
      NO_DIR_CHECK='TRUE';
      ALLOW_CONNECT='TRUE';
    'VSS888':
      PIN_NUMBER='(0,0,0,0,0,0,0,0,0,0,0,0,0,0,0,0,0,0,0,0,0,0,0,0,0,0,0,0,0,0,0,0,0,0,0,0,0,0,0,0,0,D44)';
      PINUSE='POWER';
      NO_LOAD_CHECK='Both';
      NO_IO_CHECK='Both';
      NO_ASSERT_CHECK='TRUE';
      NO_DIR_CHECK='TRUE';
      ALLOW_CONNECT='TRUE';
    'VSS886':
      PIN_NUMBER='(0,0,0,0,0,0,0,0,0,0,0,0,0,0,0,0,0,0,0,0,0,0,0,0,0,0,0,0,0,0,0,0,0,0,0,0,0,0,0,0,0,D42)';
      PINUSE='POWER';
      NO_LOAD_CHECK='Both';
      NO_IO_CHECK='Both';
      NO_ASSERT_CHECK='TRUE';
      NO_DIR_CHECK='TRUE';
      ALLOW_CONNECT='TRUE';
    'VSS885':
      PIN_NUMBER='(0,0,0,0,0,0,0,0,0,0,0,0,0,0,0,0,0,0,0,0,0,0,0,0,0,0,0,0,0,0,0,0,0,0,0,0,0,0,0,0,0,D40)';
      PINUSE='POWER';
      NO_LOAD_CHECK='Both';
      NO_IO_CHECK='Both';
      NO_ASSERT_CHECK='TRUE';
      NO_DIR_CHECK='TRUE';
      ALLOW_CONNECT='TRUE';
    'VSS884':
      PIN_NUMBER='(0,0,0,0,0,0,0,0,0,0,0,0,0,0,0,0,0,0,0,0,0,0,0,0,0,0,0,0,0,0,0,0,0,0,0,0,0,0,0,0,0,D38)';
      PINUSE='POWER';
      NO_LOAD_CHECK='Both';
      NO_IO_CHECK='Both';
      NO_ASSERT_CHECK='TRUE';
      NO_DIR_CHECK='TRUE';
      ALLOW_CONNECT='TRUE';
    'VSS881':
      PIN_NUMBER='(0,0,0,0,0,0,0,0,0,0,0,0,0,0,0,0,0,0,0,0,0,0,0,0,0,0,0,0,0,0,0,0,0,0,0,0,0,0,0,0,0,D36)';
      PINUSE='POWER';
      NO_LOAD_CHECK='Both';
      NO_IO_CHECK='Both';
      NO_ASSERT_CHECK='TRUE';
      NO_DIR_CHECK='TRUE';
      ALLOW_CONNECT='TRUE';
    'VSS879':
      PIN_NUMBER='(0,0,0,0,0,0,0,0,0,0,0,0,0,0,0,0,0,0,0,0,0,0,0,0,0,0,0,0,0,0,0,0,0,0,0,0,0,0,0,0,0,D34)';
      PINUSE='POWER';
      NO_LOAD_CHECK='Both';
      NO_IO_CHECK='Both';
      NO_ASSERT_CHECK='TRUE';
      NO_DIR_CHECK='TRUE';
      ALLOW_CONNECT='TRUE';
    'VSS878':
      PIN_NUMBER='(0,0,0,0,0,0,0,0,0,0,0,0,0,0,0,0,0,0,0,0,0,0,0,0,0,0,0,0,0,0,0,0,0,0,0,0,0,0,0,0,0,D32)';
      PINUSE='POWER';
      NO_LOAD_CHECK='Both';
      NO_IO_CHECK='Both';
      NO_ASSERT_CHECK='TRUE';
      NO_DIR_CHECK='TRUE';
      ALLOW_CONNECT='TRUE';
    'VSS877':
      PIN_NUMBER='(0,0,0,0,0,0,0,0,0,0,0,0,0,0,0,0,0,0,0,0,0,0,0,0,0,0,0,0,0,0,0,0,0,0,0,0,0,0,0,0,0,D30)';
      PINUSE='POWER';
      NO_LOAD_CHECK='Both';
      NO_IO_CHECK='Both';
      NO_ASSERT_CHECK='TRUE';
      NO_DIR_CHECK='TRUE';
      ALLOW_CONNECT='TRUE';
    'VSS876':
      PIN_NUMBER='(0,0,0,0,0,0,0,0,0,0,0,0,0,0,0,0,0,0,0,0,0,0,0,0,0,0,0,0,0,0,0,0,0,0,0,0,0,0,0,0,0,D28)';
      PINUSE='POWER';
      NO_LOAD_CHECK='Both';
      NO_IO_CHECK='Both';
      NO_ASSERT_CHECK='TRUE';
      NO_DIR_CHECK='TRUE';
      ALLOW_CONNECT='TRUE';
    'VSS875':
      PIN_NUMBER='(0,0,0,0,0,0,0,0,0,0,0,0,0,0,0,0,0,0,0,0,0,0,0,0,0,0,0,0,0,0,0,0,0,0,0,0,0,0,0,0,0,D26)';
      PINUSE='POWER';
      NO_LOAD_CHECK='Both';
      NO_IO_CHECK='Both';
      NO_ASSERT_CHECK='TRUE';
      NO_DIR_CHECK='TRUE';
      ALLOW_CONNECT='TRUE';
    'VSS874':
      PIN_NUMBER='(0,0,0,0,0,0,0,0,0,0,0,0,0,0,0,0,0,0,0,0,0,0,0,0,0,0,0,0,0,0,0,0,0,0,0,0,0,0,0,0,0,D24)';
      PINUSE='POWER';
      NO_LOAD_CHECK='Both';
      NO_IO_CHECK='Both';
      NO_ASSERT_CHECK='TRUE';
      NO_DIR_CHECK='TRUE';
      ALLOW_CONNECT='TRUE';
    'VSS873':
      PIN_NUMBER='(0,0,0,0,0,0,0,0,0,0,0,0,0,0,0,0,0,0,0,0,0,0,0,0,0,0,0,0,0,0,0,0,0,0,0,0,0,0,0,0,0,D22)';
      PINUSE='POWER';
      NO_LOAD_CHECK='Both';
      NO_IO_CHECK='Both';
      NO_ASSERT_CHECK='TRUE';
      NO_DIR_CHECK='TRUE';
      ALLOW_CONNECT='TRUE';
    'VSS871':
      PIN_NUMBER='(0,0,0,0,0,0,0,0,0,0,0,0,0,0,0,0,0,0,0,0,0,0,0,0,0,0,0,0,0,0,0,0,0,0,0,0,0,0,0,0,0,D20)';
      PINUSE='POWER';
      NO_LOAD_CHECK='Both';
      NO_IO_CHECK='Both';
      NO_ASSERT_CHECK='TRUE';
      NO_DIR_CHECK='TRUE';
      ALLOW_CONNECT='TRUE';
    'VSS869':
      PIN_NUMBER='(0,0,0,0,0,0,0,0,0,0,0,0,0,0,0,0,0,0,0,0,0,0,0,0,0,0,0,0,0,0,0,0,0,0,0,0,0,0,0,0,0,D18)';
      PINUSE='POWER';
      NO_LOAD_CHECK='Both';
      NO_IO_CHECK='Both';
      NO_ASSERT_CHECK='TRUE';
      NO_DIR_CHECK='TRUE';
      ALLOW_CONNECT='TRUE';
    'VSS868':
      PIN_NUMBER='(0,0,0,0,0,0,0,0,0,0,0,0,0,0,0,0,0,0,0,0,0,0,0,0,0,0,0,0,0,0,0,0,0,0,0,0,0,0,0,0,0,D16)';
      PINUSE='POWER';
      NO_LOAD_CHECK='Both';
      NO_IO_CHECK='Both';
      NO_ASSERT_CHECK='TRUE';
      NO_DIR_CHECK='TRUE';
      ALLOW_CONNECT='TRUE';
    'VSS866':
      PIN_NUMBER='(0,0,0,0,0,0,0,0,0,0,0,0,0,0,0,0,0,0,0,0,0,0,0,0,0,0,0,0,0,0,0,0,0,0,0,0,0,0,0,0,0,D14)';
      PINUSE='POWER';
      NO_LOAD_CHECK='Both';
      NO_IO_CHECK='Both';
      NO_ASSERT_CHECK='TRUE';
      NO_DIR_CHECK='TRUE';
      ALLOW_CONNECT='TRUE';
    'VSS865':
      PIN_NUMBER='(0,0,0,0,0,0,0,0,0,0,0,0,0,0,0,0,0,0,0,0,0,0,0,0,0,0,0,0,0,0,0,0,0,0,0,0,0,0,0,0,0,D12)';
      PINUSE='POWER';
      NO_LOAD_CHECK='Both';
      NO_IO_CHECK='Both';
      NO_ASSERT_CHECK='TRUE';
      NO_DIR_CHECK='TRUE';
      ALLOW_CONNECT='TRUE';
    'VSS864':
      PIN_NUMBER='(0,0,0,0,0,0,0,0,0,0,0,0,0,0,0,0,0,0,0,0,0,0,0,0,0,0,0,0,0,0,0,0,0,0,0,0,0,0,0,0,0,D10)';
      PINUSE='POWER';
      NO_LOAD_CHECK='Both';
      NO_IO_CHECK='Both';
      NO_ASSERT_CHECK='TRUE';
      NO_DIR_CHECK='TRUE';
      ALLOW_CONNECT='TRUE';
    'VSS663':
      PIN_NUMBER='(0,0,0,0,0,0,0,0,0,0,0,0,0,0,0,0,0,0,0,0,0,0,0,0,0,0,0,0,0,0,0,0,0,0,0,0,0,0,0,0,0,D8)';
      PINUSE='POWER';
      NO_LOAD_CHECK='Both';
      NO_IO_CHECK='Both';
      NO_ASSERT_CHECK='TRUE';
      NO_DIR_CHECK='TRUE';
      ALLOW_CONNECT='TRUE';
    'VSS662':
      PIN_NUMBER='(0,0,0,0,0,0,0,0,0,0,0,0,0,0,0,0,0,0,0,0,0,0,0,0,0,0,0,0,0,0,0,0,0,0,0,0,0,0,0,0,0,D79)';
      PINUSE='POWER';
      NO_LOAD_CHECK='Both';
      NO_IO_CHECK='Both';
      NO_ASSERT_CHECK='TRUE';
      NO_DIR_CHECK='TRUE';
      ALLOW_CONNECT='TRUE';
    'VSS659':
      PIN_NUMBER='(0,0,0,0,0,0,0,0,0,0,0,0,0,0,0,0,0,0,0,0,0,0,0,0,0,0,0,0,0,0,0,0,0,0,0,0,0,0,0,0,0,D67)';
      PINUSE='POWER';
      NO_LOAD_CHECK='Both';
      NO_IO_CHECK='Both';
      NO_ASSERT_CHECK='TRUE';
      NO_DIR_CHECK='TRUE';
      ALLOW_CONNECT='TRUE';
    'VSS658':
      PIN_NUMBER='(0,0,0,0,0,0,0,0,0,0,0,0,0,0,0,0,0,0,0,0,0,0,0,0,0,0,0,0,0,0,0,0,0,0,0,0,0,0,0,0,0,D65)';
      PINUSE='POWER';
      NO_LOAD_CHECK='Both';
      NO_IO_CHECK='Both';
      NO_ASSERT_CHECK='TRUE';
      NO_DIR_CHECK='TRUE';
      ALLOW_CONNECT='TRUE';
    'VSS657':
      PIN_NUMBER='(0,0,0,0,0,0,0,0,0,0,0,0,0,0,0,0,0,0,0,0,0,0,0,0,0,0,0,0,0,0,0,0,0,0,0,0,0,0,0,0,0,D63)';
      PINUSE='POWER';
      NO_LOAD_CHECK='Both';
      NO_IO_CHECK='Both';
      NO_ASSERT_CHECK='TRUE';
      NO_DIR_CHECK='TRUE';
      ALLOW_CONNECT='TRUE';
    'VSS619':
      PIN_NUMBER='(0,0,0,0,0,0,0,0,0,0,0,0,0,0,0,0,0,0,0,0,0,0,0,0,0,0,0,0,0,0,0,0,0,0,0,0,0,0,0,0,0,C86)';
      PINUSE='POWER';
      NO_LOAD_CHECK='Both';
      NO_IO_CHECK='Both';
      NO_ASSERT_CHECK='TRUE';
      NO_DIR_CHECK='TRUE';
      ALLOW_CONNECT='TRUE';
    'VSS618':
      PIN_NUMBER='(0,0,0,0,0,0,0,0,0,0,0,0,0,0,0,0,0,0,0,0,0,0,0,0,0,0,0,0,0,0,0,0,0,0,0,0,0,0,0,0,0,C82)';
      PINUSE='POWER';
      NO_LOAD_CHECK='Both';
      NO_IO_CHECK='Both';
      NO_ASSERT_CHECK='TRUE';
      NO_DIR_CHECK='TRUE';
      ALLOW_CONNECT='TRUE';
    'VSS617':
      PIN_NUMBER='(0,0,0,0,0,0,0,0,0,0,0,0,0,0,0,0,0,0,0,0,0,0,0,0,0,0,0,0,0,0,0,0,0,0,0,0,0,0,0,0,0,C80)';
      PINUSE='POWER';
      NO_LOAD_CHECK='Both';
      NO_IO_CHECK='Both';
      NO_ASSERT_CHECK='TRUE';
      NO_DIR_CHECK='TRUE';
      ALLOW_CONNECT='TRUE';
    'VSS616':
      PIN_NUMBER='(0,0,0,0,0,0,0,0,0,0,0,0,0,0,0,0,0,0,0,0,0,0,0,0,0,0,0,0,0,0,0,0,0,0,0,0,0,0,0,0,0,C78)';
      PINUSE='POWER';
      NO_LOAD_CHECK='Both';
      NO_IO_CHECK='Both';
      NO_ASSERT_CHECK='TRUE';
      NO_DIR_CHECK='TRUE';
      ALLOW_CONNECT='TRUE';
    'VSS615':
      PIN_NUMBER='(0,0,0,0,0,0,0,0,0,0,0,0,0,0,0,0,0,0,0,0,0,0,0,0,0,0,0,0,0,0,0,0,0,0,0,0,0,0,0,0,0,C74)';
      PINUSE='POWER';
      NO_LOAD_CHECK='Both';
      NO_IO_CHECK='Both';
      NO_ASSERT_CHECK='TRUE';
      NO_DIR_CHECK='TRUE';
      ALLOW_CONNECT='TRUE';
    'VSS614':
      PIN_NUMBER='(0,0,0,0,0,0,0,0,0,0,0,0,0,0,0,0,0,0,0,0,0,0,0,0,0,0,0,0,0,0,0,0,0,0,0,0,0,0,0,0,0,C72)';
      PINUSE='POWER';
      NO_LOAD_CHECK='Both';
      NO_IO_CHECK='Both';
      NO_ASSERT_CHECK='TRUE';
      NO_DIR_CHECK='TRUE';
      ALLOW_CONNECT='TRUE';
    'VSS613':
      PIN_NUMBER='(0,0,0,0,0,0,0,0,0,0,0,0,0,0,0,0,0,0,0,0,0,0,0,0,0,0,0,0,0,0,0,0,0,0,0,0,0,0,0,0,0,C52)';
      PINUSE='POWER';
      NO_LOAD_CHECK='Both';
      NO_IO_CHECK='Both';
      NO_ASSERT_CHECK='TRUE';
      NO_DIR_CHECK='TRUE';
      ALLOW_CONNECT='TRUE';
    'VSS612':
      PIN_NUMBER='(0,0,0,0,0,0,0,0,0,0,0,0,0,0,0,0,0,0,0,0,0,0,0,0,0,0,0,0,0,0,0,0,0,0,0,0,0,0,0,0,0,C5)';
      PINUSE='POWER';
      NO_LOAD_CHECK='Both';
      NO_IO_CHECK='Both';
      NO_ASSERT_CHECK='TRUE';
      NO_DIR_CHECK='TRUE';
      ALLOW_CONNECT='TRUE';
    'VSS610':
      PIN_NUMBER='(0,0,0,0,0,0,0,0,0,0,0,0,0,0,0,0,0,0,0,0,0,0,0,0,0,0,0,0,0,0,0,0,0,0,0,0,0,0,0,0,0,C45)';
      PINUSE='POWER';
      NO_LOAD_CHECK='Both';
      NO_IO_CHECK='Both';
      NO_ASSERT_CHECK='TRUE';
      NO_DIR_CHECK='TRUE';
      ALLOW_CONNECT='TRUE';
    'VSS609':
      PIN_NUMBER='(0,0,0,0,0,0,0,0,0,0,0,0,0,0,0,0,0,0,0,0,0,0,0,0,0,0,0,0,0,0,0,0,0,0,0,0,0,0,0,0,0,C39)';
      PINUSE='POWER';
      NO_LOAD_CHECK='Both';
      NO_IO_CHECK='Both';
      NO_ASSERT_CHECK='TRUE';
      NO_DIR_CHECK='TRUE';
      ALLOW_CONNECT='TRUE';
    'VSS392':
      PIN_NUMBER='(0,0,0,0,0,0,0,0,0,0,0,0,0,0,0,0,0,0,0,0,0,0,0,0,0,0,0,0,0,0,0,0,0,0,0,0,0,0,0,0,0,B87)';
      PINUSE='POWER';
      NO_LOAD_CHECK='Both';
      NO_IO_CHECK='Both';
      NO_ASSERT_CHECK='TRUE';
      NO_DIR_CHECK='TRUE';
      ALLOW_CONNECT='TRUE';
    'VSS391':
      PIN_NUMBER='(0,0,0,0,0,0,0,0,0,0,0,0,0,0,0,0,0,0,0,0,0,0,0,0,0,0,0,0,0,0,0,0,0,0,0,0,0,0,0,0,0,B83)';
      PINUSE='POWER';
      NO_LOAD_CHECK='Both';
      NO_IO_CHECK='Both';
      NO_ASSERT_CHECK='TRUE';
      NO_DIR_CHECK='TRUE';
      ALLOW_CONNECT='TRUE';
    'VSS390':
      PIN_NUMBER='(0,0,0,0,0,0,0,0,0,0,0,0,0,0,0,0,0,0,0,0,0,0,0,0,0,0,0,0,0,0,0,0,0,0,0,0,0,0,0,0,0,B75)';
      PINUSE='POWER';
      NO_LOAD_CHECK='Both';
      NO_IO_CHECK='Both';
      NO_ASSERT_CHECK='TRUE';
      NO_DIR_CHECK='TRUE';
      ALLOW_CONNECT='TRUE';
    'VSS389':
      PIN_NUMBER='(0,0,0,0,0,0,0,0,0,0,0,0,0,0,0,0,0,0,0,0,0,0,0,0,0,0,0,0,0,0,0,0,0,0,0,0,0,0,0,0,0,B67)';
      PINUSE='POWER';
      NO_LOAD_CHECK='Both';
      NO_IO_CHECK='Both';
      NO_ASSERT_CHECK='TRUE';
      NO_DIR_CHECK='TRUE';
      ALLOW_CONNECT='TRUE';
    'VSS388':
      PIN_NUMBER='(0,0,0,0,0,0,0,0,0,0,0,0,0,0,0,0,0,0,0,0,0,0,0,0,0,0,0,0,0,0,0,0,0,0,0,0,0,0,0,0,0,B61)';
      PINUSE='POWER';
      NO_LOAD_CHECK='Both';
      NO_IO_CHECK='Both';
      NO_ASSERT_CHECK='TRUE';
      NO_DIR_CHECK='TRUE';
      ALLOW_CONNECT='TRUE';
    'VSS387':
      PIN_NUMBER='(0,0,0,0,0,0,0,0,0,0,0,0,0,0,0,0,0,0,0,0,0,0,0,0,0,0,0,0,0,0,0,0,0,0,0,0,0,0,0,0,0,B6)';
      PINUSE='POWER';
      NO_LOAD_CHECK='Both';
      NO_IO_CHECK='Both';
      NO_ASSERT_CHECK='TRUE';
      NO_DIR_CHECK='TRUE';
      ALLOW_CONNECT='TRUE';
    'VSS386':
      PIN_NUMBER='(0,0,0,0,0,0,0,0,0,0,0,0,0,0,0,0,0,0,0,0,0,0,0,0,0,0,0,0,0,0,0,0,0,0,0,0,0,0,0,0,0,B55)';
      PINUSE='POWER';
      NO_LOAD_CHECK='Both';
      NO_IO_CHECK='Both';
      NO_ASSERT_CHECK='TRUE';
      NO_DIR_CHECK='TRUE';
      ALLOW_CONNECT='TRUE';
    'VSS385':
      PIN_NUMBER='(0,0,0,0,0,0,0,0,0,0,0,0,0,0,0,0,0,0,0,0,0,0,0,0,0,0,0,0,0,0,0,0,0,0,0,0,0,0,0,0,0,B49)';
      PINUSE='POWER';
      NO_LOAD_CHECK='Both';
      NO_IO_CHECK='Both';
      NO_ASSERT_CHECK='TRUE';
      NO_DIR_CHECK='TRUE';
      ALLOW_CONNECT='TRUE';
    'VSS384':
      PIN_NUMBER='(0,0,0,0,0,0,0,0,0,0,0,0,0,0,0,0,0,0,0,0,0,0,0,0,0,0,0,0,0,0,0,0,0,0,0,0,0,0,0,0,0,B42)';
      PINUSE='POWER';
      NO_LOAD_CHECK='Both';
      NO_IO_CHECK='Both';
      NO_ASSERT_CHECK='TRUE';
      NO_DIR_CHECK='TRUE';
      ALLOW_CONNECT='TRUE';
    'VSS382':
      PIN_NUMBER='(0,0,0,0,0,0,0,0,0,0,0,0,0,0,0,0,0,0,0,0,0,0,0,0,0,0,0,0,0,0,0,0,0,0,0,0,0,0,0,0,0,B36)';
      PINUSE='POWER';
      NO_LOAD_CHECK='Both';
      NO_IO_CHECK='Both';
      NO_ASSERT_CHECK='TRUE';
      NO_DIR_CHECK='TRUE';
      ALLOW_CONNECT='TRUE';
    'VSS381':
      PIN_NUMBER='(0,0,0,0,0,0,0,0,0,0,0,0,0,0,0,0,0,0,0,0,0,0,0,0,0,0,0,0,0,0,0,0,0,0,0,0,0,0,0,0,0,B30)';
      PINUSE='POWER';
      NO_LOAD_CHECK='Both';
      NO_IO_CHECK='Both';
      NO_ASSERT_CHECK='TRUE';
      NO_DIR_CHECK='TRUE';
      ALLOW_CONNECT='TRUE';
    'VSS380':
      PIN_NUMBER='(0,0,0,0,0,0,0,0,0,0,0,0,0,0,0,0,0,0,0,0,0,0,0,0,0,0,0,0,0,0,0,0,0,0,0,0,0,0,0,0,0,B24)';
      PINUSE='POWER';
      NO_LOAD_CHECK='Both';
      NO_IO_CHECK='Both';
      NO_ASSERT_CHECK='TRUE';
      NO_DIR_CHECK='TRUE';
      ALLOW_CONNECT='TRUE';
    'VSS379':
      PIN_NUMBER='(0,0,0,0,0,0,0,0,0,0,0,0,0,0,0,0,0,0,0,0,0,0,0,0,0,0,0,0,0,0,0,0,0,0,0,0,0,0,0,0,0,B18)';
      PINUSE='POWER';
      NO_LOAD_CHECK='Both';
      NO_IO_CHECK='Both';
      NO_ASSERT_CHECK='TRUE';
      NO_DIR_CHECK='TRUE';
      ALLOW_CONNECT='TRUE';
    'VSS378':
      PIN_NUMBER='(0,0,0,0,0,0,0,0,0,0,0,0,0,0,0,0,0,0,0,0,0,0,0,0,0,0,0,0,0,0,0,0,0,0,0,0,0,0,0,0,0,B12)';
      PINUSE='POWER';
      NO_LOAD_CHECK='Both';
      NO_IO_CHECK='Both';
      NO_ASSERT_CHECK='TRUE';
      NO_DIR_CHECK='TRUE';
      ALLOW_CONNECT='TRUE';
    'VSS16':
      PIN_NUMBER='(0,0,0,0,0,0,0,0,0,0,0,0,0,0,0,0,0,0,0,0,0,0,0,0,0,0,0,0,0,0,0,0,0,0,0,0,0,0,0,0,0,A62)';
      PINUSE='POWER';
      NO_LOAD_CHECK='Both';
      NO_IO_CHECK='Both';
      NO_ASSERT_CHECK='TRUE';
      NO_DIR_CHECK='TRUE';
      ALLOW_CONNECT='TRUE';
    'VSS15':
      PIN_NUMBER='(0,0,0,0,0,0,0,0,0,0,0,0,0,0,0,0,0,0,0,0,0,0,0,0,0,0,0,0,0,0,0,0,0,0,0,0,0,0,0,0,0,A60)';
      PINUSE='POWER';
      NO_LOAD_CHECK='Both';
      NO_IO_CHECK='Both';
      NO_ASSERT_CHECK='TRUE';
      NO_DIR_CHECK='TRUE';
      ALLOW_CONNECT='TRUE';
    'VSS14':
      PIN_NUMBER='(0,0,0,0,0,0,0,0,0,0,0,0,0,0,0,0,0,0,0,0,0,0,0,0,0,0,0,0,0,0,0,0,0,0,0,0,0,0,0,0,0,A56)';
      PINUSE='POWER';
      NO_LOAD_CHECK='Both';
      NO_IO_CHECK='Both';
      NO_ASSERT_CHECK='TRUE';
      NO_DIR_CHECK='TRUE';
      ALLOW_CONNECT='TRUE';
    'VSS13':
      PIN_NUMBER='(0,0,0,0,0,0,0,0,0,0,0,0,0,0,0,0,0,0,0,0,0,0,0,0,0,0,0,0,0,0,0,0,0,0,0,0,0,0,0,0,0,A54)';
      PINUSE='POWER';
      NO_LOAD_CHECK='Both';
      NO_IO_CHECK='Both';
      NO_ASSERT_CHECK='TRUE';
      NO_DIR_CHECK='TRUE';
      ALLOW_CONNECT='TRUE';
    'VSS12':
      PIN_NUMBER='(0,0,0,0,0,0,0,0,0,0,0,0,0,0,0,0,0,0,0,0,0,0,0,0,0,0,0,0,0,0,0,0,0,0,0,0,0,0,0,0,0,A50)';
      PINUSE='POWER';
      NO_LOAD_CHECK='Both';
      NO_IO_CHECK='Both';
      NO_ASSERT_CHECK='TRUE';
      NO_DIR_CHECK='TRUE';
      ALLOW_CONNECT='TRUE';
    'VSS11':
      PIN_NUMBER='(0,0,0,0,0,0,0,0,0,0,0,0,0,0,0,0,0,0,0,0,0,0,0,0,0,0,0,0,0,0,0,0,0,0,0,0,0,0,0,0,0,A41)';
      PINUSE='POWER';
      NO_LOAD_CHECK='Both';
      NO_IO_CHECK='Both';
      NO_ASSERT_CHECK='TRUE';
      NO_DIR_CHECK='TRUE';
      ALLOW_CONNECT='TRUE';
    'VSS10':
      PIN_NUMBER='(0,0,0,0,0,0,0,0,0,0,0,0,0,0,0,0,0,0,0,0,0,0,0,0,0,0,0,0,0,0,0,0,0,0,0,0,0,0,0,0,0,A37)';
      PINUSE='POWER';
      NO_LOAD_CHECK='Both';
      NO_IO_CHECK='Both';
      NO_ASSERT_CHECK='TRUE';
      NO_DIR_CHECK='TRUE';
      ALLOW_CONNECT='TRUE';
    'VSS9':
      PIN_NUMBER='(0,0,0,0,0,0,0,0,0,0,0,0,0,0,0,0,0,0,0,0,0,0,0,0,0,0,0,0,0,0,0,0,0,0,0,0,0,0,0,0,0,A35)';
      PINUSE='POWER';
      NO_LOAD_CHECK='Both';
      NO_IO_CHECK='Both';
      NO_ASSERT_CHECK='TRUE';
      NO_DIR_CHECK='TRUE';
      ALLOW_CONNECT='TRUE';
    'VSS8':
      PIN_NUMBER='(0,0,0,0,0,0,0,0,0,0,0,0,0,0,0,0,0,0,0,0,0,0,0,0,0,0,0,0,0,0,0,0,0,0,0,0,0,0,0,0,0,A31)';
      PINUSE='POWER';
      NO_LOAD_CHECK='Both';
      NO_IO_CHECK='Both';
      NO_ASSERT_CHECK='TRUE';
      NO_DIR_CHECK='TRUE';
      ALLOW_CONNECT='TRUE';
    'VSS7':
      PIN_NUMBER='(0,0,0,0,0,0,0,0,0,0,0,0,0,0,0,0,0,0,0,0,0,0,0,0,0,0,0,0,0,0,0,0,0,0,0,0,0,0,0,0,0,A29)';
      PINUSE='POWER';
      NO_LOAD_CHECK='Both';
      NO_IO_CHECK='Both';
      NO_ASSERT_CHECK='TRUE';
      NO_DIR_CHECK='TRUE';
      ALLOW_CONNECT='TRUE';
    'VSS6':
      PIN_NUMBER='(0,0,0,0,0,0,0,0,0,0,0,0,0,0,0,0,0,0,0,0,0,0,0,0,0,0,0,0,0,0,0,0,0,0,0,0,0,0,0,0,0,A25)';
      PINUSE='POWER';
      NO_LOAD_CHECK='Both';
      NO_IO_CHECK='Both';
      NO_ASSERT_CHECK='TRUE';
      NO_DIR_CHECK='TRUE';
      ALLOW_CONNECT='TRUE';
    'VSS5':
      PIN_NUMBER='(0,0,0,0,0,0,0,0,0,0,0,0,0,0,0,0,0,0,0,0,0,0,0,0,0,0,0,0,0,0,0,0,0,0,0,0,0,0,0,0,0,A23)';
      PINUSE='POWER';
      NO_LOAD_CHECK='Both';
      NO_IO_CHECK='Both';
      NO_ASSERT_CHECK='TRUE';
      NO_DIR_CHECK='TRUE';
      ALLOW_CONNECT='TRUE';
    'VSS4':
      PIN_NUMBER='(0,0,0,0,0,0,0,0,0,0,0,0,0,0,0,0,0,0,0,0,0,0,0,0,0,0,0,0,0,0,0,0,0,0,0,0,0,0,0,0,0,A19)';
      PINUSE='POWER';
      NO_LOAD_CHECK='Both';
      NO_IO_CHECK='Both';
      NO_ASSERT_CHECK='TRUE';
      NO_DIR_CHECK='TRUE';
      ALLOW_CONNECT='TRUE';
    'VSS3':
      PIN_NUMBER='(0,0,0,0,0,0,0,0,0,0,0,0,0,0,0,0,0,0,0,0,0,0,0,0,0,0,0,0,0,0,0,0,0,0,0,0,0,0,0,0,0,A17)';
      PINUSE='POWER';
      NO_LOAD_CHECK='Both';
      NO_IO_CHECK='Both';
      NO_ASSERT_CHECK='TRUE';
      NO_DIR_CHECK='TRUE';
      ALLOW_CONNECT='TRUE';
    'VSS2':
      PIN_NUMBER='(0,0,0,0,0,0,0,0,0,0,0,0,0,0,0,0,0,0,0,0,0,0,0,0,0,0,0,0,0,0,0,0,0,0,0,0,0,0,0,0,0,A13)';
      PINUSE='POWER';
      NO_LOAD_CHECK='Both';
      NO_IO_CHECK='Both';
      NO_ASSERT_CHECK='TRUE';
      NO_DIR_CHECK='TRUE';
      ALLOW_CONNECT='TRUE';
    'VSS1':
      PIN_NUMBER='(0,0,0,0,0,0,0,0,0,0,0,0,0,0,0,0,0,0,0,0,0,0,0,0,0,0,0,0,0,0,0,0,0,0,0,0,0,0,0,0,0,A11)';
      PINUSE='POWER';
      NO_LOAD_CHECK='Both';
      NO_IO_CHECK='Both';
      NO_ASSERT_CHECK='TRUE';
      NO_DIR_CHECK='TRUE';
      ALLOW_CONNECT='TRUE';
  end_pin;
  body
    PART_NAME='SOCKET4677_AZIF0045P001C01CS';
    BODY_NAME='SOCKET4677_AZIF0045P001C01CS';
    PHYS_DES_PREFIX='U';
    CLASS='IC';
  end_body;
end_primitive;

END.
